G04 ================== begin FILE IDENTIFICATION RECORD ==================*
G04 Layout Name:  9324_DA0F0TMBIJ0_F0T_Motherboard_J_v01_20230324_0910.brd*
G04 Film Name:    gnd4*
G04 File Format:  Gerber RS274X*
G04 File Origin:  Cadence Allegro 17.2-S081*
G04 Origin Date:  Sat Mar 25 08:45:08 2023*
G04 *
G04 Layer:  DRAWING FORMAT/TITLE_BLOCK_A*
G04 Layer:  PIN/SPECIAL_DRILL*
G04 Layer:  VIA CLASS/GND4*
G04 Layer:  PIN/GND4*
G04 Layer:  MANUFACTURING/PHOTOPLOT_OUTLINE*
G04 Layer:  ETCH/GND4*
G04 Layer:  DRAWING FORMAT/TITLE_BLOCK*
G04 Layer:  DRAWING FORMAT/TITLE_DATA_GND4*
G04 *
G04 Offset:    (0.00 0.00)*
G04 Mirror:    No*
G04 Mode:      Negative*
G04 Rotation:  0*
G04 FullContactRelief:  No*
G04 UndefLineWidth:     6.00*
G04 ================== end FILE IDENTIFICATION RECORD ====================*
%FSLAX25Y25*MOIN*%
%IR0*IPPOS*OFA0.00000B0.00000*MIA0B0*SFA1.00000B1.00000*%
%ADD15C,.03*%
%ADD31C,.06*%
%ADD46C,.061*%
%ADD27C,.07*%
%AMMACRO55*
4,1,36,0.0,.01,
-.001736,.009848,
-.00342,.009397,
-.005,.00866,
-.006428,.00766,
-.00766,.006428,
-.00866,.005,
-.009397,.00342,
-.009848,.001736,
-.01,0.0,
-.009848,-.001736,
-.009397,-.00342,
-.00866,-.005,
-.00766,-.006428,
-.006428,-.00766,
-.005,-.00866,
-.00342,-.009397,
-.001736,-.009848,
0.0,-.01,
.001736,-.009848,
.00342,-.009397,
.005,-.00866,
.006428,-.00766,
.00766,-.006428,
.00866,-.005,
.009397,-.00342,
.009848,-.001736,
.01,0.0,
.009848,.001736,
.009397,.00342,
.00866,.005,
.00766,.006428,
.006428,.00766,
.005,.00866,
.00342,.009397,
.001736,.009848,
0.0,.01,
0.0*
%
%ADD55MACRO55*%
%ADD52C,.071*%
%ADD29C,.062*%
%ADD17C,.026*%
%AMMACRO71*
4,1,36,.0025,0.0,
.002462,.000434,
.002349,.000855,
.002165,.00125,
.001915,.001607,
.001607,.001915,
.00125,.002165,
.000855,.002349,
.000434,.002462,
0.0,.0025,
-.000434,.002462,
-.000855,.002349,
-.00125,.002165,
-.001607,.001915,
-.001915,.001607,
-.002165,.00125,
-.002349,.000855,
-.002462,.000434,
-.0025,0.0,
-.002462,-.000434,
-.002349,-.000855,
-.002165,-.00125,
-.001915,-.001607,
-.001607,-.001915,
-.00125,-.002165,
-.000855,-.002349,
-.000434,-.002462,
0.0,-.0025,
.000434,-.002462,
.000855,-.002349,
.00125,-.002165,
.001607,-.001915,
.001915,-.001607,
.002165,-.00125,
.002349,-.000855,
.002462,-.000434,
.0025,0.0,
135.*
%
%ADD71MACRO71*%
%ADD67C,.064*%
%AMMACRO19*
4,1,36,.0025,0.0,
.002462,.000434,
.002349,.000855,
.002165,.00125,
.001915,.001607,
.001607,.001915,
.00125,.002165,
.000855,.002349,
.000434,.002462,
0.0,.0025,
-.000434,.002462,
-.000855,.002349,
-.00125,.002165,
-.001607,.001915,
-.001915,.001607,
-.002165,.00125,
-.002349,.000855,
-.002462,.000434,
-.0025,0.0,
-.002462,-.000434,
-.002349,-.000855,
-.002165,-.00125,
-.001915,-.001607,
-.001607,-.001915,
-.00125,-.002165,
-.000855,-.002349,
-.000434,-.002462,
0.0,-.0025,
.000434,-.002462,
.000855,-.002349,
.00125,-.002165,
.001607,-.001915,
.001915,-.001607,
.002165,-.00125,
.002349,-.000855,
.002462,-.000434,
.0025,0.0,
225.*
%
%ADD19MACRO19*%
%AMMACRO14*
4,1,36,.0025,0.0,
.002462,.000434,
.002349,.000855,
.002165,.00125,
.001915,.001607,
.001607,.001915,
.00125,.002165,
.000855,.002349,
.000434,.002462,
0.0,.0025,
-.000434,.002462,
-.000855,.002349,
-.00125,.002165,
-.001607,.001915,
-.001915,.001607,
-.002165,.00125,
-.002349,.000855,
-.002462,.000434,
-.0025,0.0,
-.002462,-.000434,
-.002349,-.000855,
-.002165,-.00125,
-.001915,-.001607,
-.001607,-.001915,
-.00125,-.002165,
-.000855,-.002349,
-.000434,-.002462,
0.0,-.0025,
.000434,-.002462,
.000855,-.002349,
.00125,-.002165,
.001607,-.001915,
.001915,-.001607,
.002165,-.00125,
.002349,-.000855,
.002462,-.000434,
.0025,0.0,
180.*
%
%ADD14MACRO14*%
%AMMACRO11*
4,1,36,.0025,0.0,
.002462,.000434,
.002349,.000855,
.002165,.00125,
.001915,.001607,
.001607,.001915,
.00125,.002165,
.000855,.002349,
.000434,.002462,
0.0,.0025,
-.000434,.002462,
-.000855,.002349,
-.00125,.002165,
-.001607,.001915,
-.001915,.001607,
-.002165,.00125,
-.002349,.000855,
-.002462,.000434,
-.0025,0.0,
-.002462,-.000434,
-.002349,-.000855,
-.002165,-.00125,
-.001915,-.001607,
-.001607,-.001915,
-.00125,-.002165,
-.000855,-.002349,
-.000434,-.002462,
0.0,-.0025,
.000434,-.002462,
.000855,-.002349,
.00125,-.002165,
.001607,-.001915,
.001915,-.001607,
.002165,-.00125,
.002349,-.000855,
.002462,-.000434,
.0025,0.0,
270.*
%
%ADD11MACRO11*%
%AMMACRO53*
4,1,36,-.0025,0.0,
-.002462,.000434,
-.002349,.000855,
-.002165,.00125,
-.001915,.001607,
-.001607,.001915,
-.00125,.002165,
-.000855,.002349,
-.000434,.002462,
0.0,.0025,
.000434,.002462,
.000855,.002349,
.00125,.002165,
.001607,.001915,
.001915,.001607,
.002165,.00125,
.002349,.000855,
.002462,.000434,
.0025,0.0,
.002462,-.000434,
.002349,-.000855,
.002165,-.00125,
.001915,-.001607,
.001607,-.001915,
.00125,-.002165,
.000855,-.002349,
.000434,-.002462,
0.0,-.0025,
-.000434,-.002462,
-.000855,-.002349,
-.00125,-.002165,
-.001607,-.001915,
-.001915,-.001607,
-.002165,-.00125,
-.002349,-.000855,
-.002462,-.000434,
-.0025,0.0,
180.*
%
%ADD53MACRO53*%
%AMMACRO44*
4,1,36,.003,0.0,
.002954,.000521,
.002819,.001026,
.002598,.0015,
.002298,.001928,
.001928,.002298,
.0015,.002598,
.001026,.002819,
.000521,.002954,
0.0,.003,
-.000521,.002954,
-.001026,.002819,
-.0015,.002598,
-.001928,.002298,
-.002298,.001928,
-.002598,.0015,
-.002819,.001026,
-.002954,.000521,
-.003,0.0,
-.002954,-.000521,
-.002819,-.001026,
-.002598,-.0015,
-.002298,-.001928,
-.001928,-.002298,
-.0015,-.002598,
-.001026,-.002819,
-.000521,-.002954,
0.0,-.003,
.000521,-.002954,
.001026,-.002819,
.0015,-.002598,
.001928,-.002298,
.002298,-.001928,
.002598,-.0015,
.002819,-.001026,
.002954,-.000521,
.003,0.0,
270.*
%
%ADD44MACRO44*%
%AMMACRO42*
4,1,36,.003,0.0,
.002954,.000521,
.002819,.001026,
.002598,.0015,
.002298,.001928,
.001928,.002298,
.0015,.002598,
.001026,.002819,
.000521,.002954,
0.0,.003,
-.000521,.002954,
-.001026,.002819,
-.0015,.002598,
-.001928,.002298,
-.002298,.001928,
-.002598,.0015,
-.002819,.001026,
-.002954,.000521,
-.003,0.0,
-.002954,-.000521,
-.002819,-.001026,
-.002598,-.0015,
-.002298,-.001928,
-.001928,-.002298,
-.0015,-.002598,
-.001026,-.002819,
-.000521,-.002954,
0.0,-.003,
.000521,-.002954,
.001026,-.002819,
.0015,-.002598,
.001928,-.002298,
.002298,-.001928,
.002598,-.0015,
.002819,-.001026,
.002954,-.000521,
.003,0.0,
180.*
%
%ADD42MACRO42*%
%ADD26C,.074*%
%AMMACRO74*
4,1,36,-.003,0.0,
-.002954,.000521,
-.002819,.001026,
-.002598,.0015,
-.002298,.001928,
-.001928,.002298,
-.0015,.002598,
-.001026,.002819,
-.000521,.002954,
0.0,.003,
.000521,.002954,
.001026,.002819,
.0015,.002598,
.001928,.002298,
.002298,.001928,
.002598,.0015,
.002819,.001026,
.002954,.000521,
.003,0.0,
.002954,-.000521,
.002819,-.001026,
.002598,-.0015,
.002298,-.001928,
.001928,-.002298,
.0015,-.002598,
.001026,-.002819,
.000521,-.002954,
0.0,-.003,
-.000521,-.002954,
-.001026,-.002819,
-.0015,-.002598,
-.001928,-.002298,
-.002298,-.001928,
-.002598,-.0015,
-.002819,-.001026,
-.002954,-.000521,
-.003,0.0,
270.*
%
%ADD74MACRO74*%
%ADD73C,.0435*%
%ADD63C,.06015*%
%ADD50C,.076*%
%ADD49C,.095*%
%ADD24C,.0257*%
%ADD76C,.087*%
%ADD35C,.03417*%
%ADD41C,.0259*%
%ADD22C,.0277*%
%AMMACRO40*
4,1,15,.06231,.03403,
.067273,.022693,
.070191,.010666,
.070977,-.001684,
.069606,-.013984,
.066121,-.025858,
.06231,-.03403,
.06745,-.03917,
.073227,-.026862,
.076779,-.013739,
.077998,-.000197,
.076848,.01335,
.073362,.026492,
.067647,.038828,
.06745,.03917,
.06231,.03403,
0.0*
4,1,15,.03403,-.06231,
.022693,-.067273,
.010666,-.070191,
-.001684,-.070977,
-.013984,-.069606,
-.025858,-.066121,
-.03403,-.06231,
-.03917,-.06745,
-.026862,-.073227,
-.013739,-.076779,
-.000197,-.077998,
.01335,-.076848,
.026492,-.073362,
.038828,-.067647,
.03917,-.06745,
.03403,-.06231,
0.0*
4,1,15,-.06231,-.03403,
-.067273,-.022693,
-.070191,-.010666,
-.070977,.001684,
-.069606,.013984,
-.066121,.025858,
-.06231,.03403,
-.06745,.03917,
-.073227,.026862,
-.076779,.013739,
-.077998,.000197,
-.076848,-.01335,
-.073362,-.026492,
-.067647,-.038828,
-.06745,-.03917,
-.06231,-.03403,
0.0*
4,1,15,-.03403,.06231,
-.022693,.067273,
-.010666,.070191,
.001684,.070977,
.013984,.069606,
.025858,.066121,
.03403,.06231,
.03917,.06745,
.026862,.073227,
.013739,.076779,
.000197,.077998,
-.01335,.076848,
-.026492,.073362,
-.038828,.067647,
-.03917,.06745,
-.03403,.06231,
0.0*
%
%ADD40MACRO40*%
%AMMACRO10*
4,1,18,.09673,.06845,
.107147,.050613,
.114308,.031238,
.117996,.010914,
.118098,-.009741,
.114613,-.030101,
.107644,-.049546,
.097406,-.067485,
.09673,-.06845,
.10175,-.07347,
.112962,-.054685,
.120742,-.034239,
.124853,-.012752,
.125171,.009122,
.121685,.030719,
.114502,.051383,
.10384,.070486,
.10175,.07347,
.09673,.06845,
0.0*
4,1,18,.06845,-.09673,
.050613,-.107147,
.031238,-.114308,
.010914,-.117996,
-.009741,-.118098,
-.030101,-.114613,
-.049546,-.107644,
-.067485,-.097406,
-.06845,-.09673,
-.07347,-.10175,
-.054685,-.112962,
-.034239,-.120742,
-.012752,-.124853,
.009122,-.125171,
.030719,-.121685,
.051383,-.114502,
.070486,-.10384,
.07347,-.10175,
.06845,-.09673,
0.0*
4,1,18,-.09673,-.06845,
-.107147,-.050613,
-.114308,-.031238,
-.117996,-.010914,
-.118098,.009741,
-.114613,.030101,
-.107644,.049546,
-.097406,.067485,
-.09673,.06845,
-.10175,.07347,
-.112962,.054685,
-.120742,.034239,
-.124853,.012752,
-.125171,-.009122,
-.121685,-.030719,
-.114502,-.051383,
-.10384,-.070486,
-.10175,-.07347,
-.09673,-.06845,
0.0*
4,1,18,-.06845,.09673,
-.050613,.107147,
-.031238,.114308,
-.010914,.117996,
.009741,.118098,
.030101,.114613,
.049546,.107644,
.067485,.097406,
.06845,.09673,
.07347,.10175,
.054685,.112962,
.034239,.120742,
.012752,.124853,
-.009122,.125171,
-.030719,.121685,
-.051383,.114502,
-.070486,.10384,
-.07347,.10175,
-.06845,.09673,
0.0*
%
%ADD10MACRO10*%
%ADD36C,.03187*%
%AMMACRO37*
4,1,16,.0711,.04282,
.077455,.029823,
.081457,.01592,
.082984,.001533,
.08199,-.0129,
.078504,-.026942,
.072633,-.040164,
.0711,-.04282,
.07619,-.04791,
.083352,-.033952,
.087981,-.018962,
.089937,-.003396,
.089161,.012273,
.085675,.027569,
.079586,.042027,
.07619,.04791,
.0711,.04282,
0.0*
4,1,16,.04282,-.0711,
.029823,-.077455,
.01592,-.081457,
.001533,-.082984,
-.0129,-.08199,
-.026942,-.078504,
-.040164,-.072633,
-.04282,-.0711,
-.04791,-.07619,
-.033952,-.083352,
-.018962,-.087981,
-.003396,-.089937,
.012273,-.089161,
.027569,-.085675,
.042027,-.079586,
.04791,-.07619,
.04282,-.0711,
0.0*
4,1,16,-.0711,-.04282,
-.077455,-.029823,
-.081457,-.01592,
-.082984,-.001533,
-.08199,.0129,
-.078504,.026942,
-.072633,.040164,
-.0711,.04282,
-.07619,.04791,
-.083352,.033952,
-.087981,.018962,
-.089937,.003396,
-.089161,-.012273,
-.085675,-.027569,
-.079586,-.042027,
-.07619,-.04791,
-.0711,-.04282,
0.0*
4,1,16,-.04282,.0711,
-.029823,.077455,
-.01592,.081457,
-.001533,.082984,
.0129,.08199,
.026942,.078504,
.040164,.072633,
.04282,.0711,
.04791,.07619,
.033952,.083352,
.018962,.087981,
.003396,.089937,
-.012273,.089161,
-.027569,.085675,
-.042027,.079586,
-.04791,.07619,
-.04282,.0711,
0.0*
%
%ADD37MACRO37*%
%AMMACRO32*
4,1,15,.02438,.01377,
.026401,.009327,
.027619,.004601,
.027999,-.000265,
.027527,-.005123,
.02622,-.009825,
.02438,-.01377,
.02948,-.01887,
.032309,-.013464,
.034156,-.007649,
.034965,-.001602,
.034712,.004494,
.033405,.010454,
.031082,.016095,
.02948,.01887,
.02438,.01377,
90.*
4,1,15,.01377,-.02438,
.009327,-.026401,
.004601,-.027619,
-.000265,-.027999,
-.005123,-.027527,
-.009825,-.02622,
-.01377,-.02438,
-.01887,-.02948,
-.013464,-.032309,
-.007649,-.034156,
-.001602,-.034965,
.004494,-.034712,
.010454,-.033405,
.016095,-.031082,
.01887,-.02948,
.01377,-.02438,
90.*
4,1,15,-.02438,-.01377,
-.026401,-.009327,
-.027619,-.004601,
-.027999,.000265,
-.027527,.005123,
-.02622,.009825,
-.02438,.01377,
-.02948,.01887,
-.032309,.013464,
-.034156,.007649,
-.034965,.001602,
-.034712,-.004494,
-.033405,-.010454,
-.031082,-.016095,
-.02948,-.01887,
-.02438,-.01377,
90.*
4,1,15,-.01377,.02438,
-.009327,.026401,
-.004601,.027619,
.000265,.027999,
.005123,.027527,
.009825,.02622,
.01377,.02438,
.01887,.02948,
.013464,.032309,
.007649,.034156,
.001602,.034965,
-.004494,.034712,
-.010454,.033405,
-.016095,.031082,
-.01887,.02948,
-.01377,.02438,
90.*
%
%ADD32MACRO32*%
%AMMACRO30*
4,1,15,.02438,.01377,
.026401,.009327,
.027619,.004601,
.027999,-.000265,
.027527,-.005123,
.02622,-.009825,
.02438,-.01377,
.02948,-.01887,
.032309,-.013464,
.034156,-.007649,
.034965,-.001602,
.034712,.004494,
.033405,.010454,
.031082,.016095,
.02948,.01887,
.02438,.01377,
0.0*
4,1,15,.01377,-.02438,
.009327,-.026401,
.004601,-.027619,
-.000265,-.027999,
-.005123,-.027527,
-.009825,-.02622,
-.01377,-.02438,
-.01887,-.02948,
-.013464,-.032309,
-.007649,-.034156,
-.001602,-.034965,
.004494,-.034712,
.010454,-.033405,
.016095,-.031082,
.01887,-.02948,
.01377,-.02438,
0.0*
4,1,15,-.02438,-.01377,
-.026401,-.009327,
-.027619,-.004601,
-.027999,.000265,
-.027527,.005123,
-.02622,.009825,
-.02438,.01377,
-.02948,.01887,
-.032309,.013464,
-.034156,.007649,
-.034965,.001602,
-.034712,-.004494,
-.033405,-.010454,
-.031082,-.016095,
-.02948,-.01887,
-.02438,-.01377,
0.0*
4,1,15,-.01377,.02438,
-.009327,.026401,
-.004601,.027619,
.000265,.027999,
.005123,.027527,
.009825,.02622,
.01377,.02438,
.01887,.02948,
.013464,.032309,
.007649,.034156,
.001602,.034965,
-.004494,.034712,
-.010454,.033405,
-.016095,.031082,
-.01887,.02948,
-.01377,.02438,
0.0*
%
%ADD30MACRO30*%
%AMMACRO48*
4,1,15,.02475,.01414,
.026829,.009627,
.028094,.004822,
.028504,-.000129,
.028049,-.005077,
.026741,-.009871,
.02475,-.01414,
.02984,-.01923,
.032726,-.013756,
.034617,-.007864,
.035457,-.001734,
.03522,.00445,
.033912,.010498,
.031574,.016227,
.02984,.01923,
.02475,.01414,
90.*
4,1,15,.01414,-.02475,
.009627,-.026829,
.004822,-.028094,
-.000129,-.028504,
-.005077,-.028049,
-.009871,-.026741,
-.01414,-.02475,
-.01923,-.02984,
-.013756,-.032726,
-.007864,-.034617,
-.001734,-.035457,
.00445,-.03522,
.010498,-.033912,
.016227,-.031574,
.01923,-.02984,
.01414,-.02475,
90.*
4,1,15,-.02475,-.01414,
-.026829,-.009627,
-.028094,-.004822,
-.028504,.000129,
-.028049,.005077,
-.026741,.009871,
-.02475,.01414,
-.02984,.01923,
-.032726,.013756,
-.034617,.007864,
-.035457,.001734,
-.03522,-.00445,
-.033912,-.010498,
-.031574,-.016227,
-.02984,-.01923,
-.02475,-.01414,
90.*
4,1,15,-.01414,.02475,
-.009627,.026829,
-.004822,.028094,
.000129,.028504,
.005077,.028049,
.009871,.026741,
.01414,.02475,
.01923,.02984,
.013756,.032726,
.007864,.034617,
.001734,.035457,
-.00445,.03522,
-.010498,.033912,
-.016227,.031574,
-.01923,.02984,
-.01414,.02475,
90.*
%
%ADD48MACRO48*%
%AMMACRO66*
4,1,18,.07103,.05689,
.07983,.043691,
.086204,.029165,
.089959,.013753,
.09098,-.002077,
.089237,-.017844,
.084783,-.033069,
.077753,-.047289,
.07103,-.05689,
.07601,-.06186,
.085597,-.047721,
.092583,-.032132,
.096757,-.015567,
.09799,.001471,
.096246,.018464,
.091577,.034897,
.084126,.050269,
.07601,.06186,
.07103,.05689,
0.0*
4,1,18,.05689,-.07103,
.043691,-.07983,
.029165,-.086204,
.013753,-.089959,
-.002077,-.09098,
-.017844,-.089237,
-.033069,-.084783,
-.047289,-.077753,
-.05689,-.07103,
-.06186,-.07601,
-.047721,-.085597,
-.032132,-.092583,
-.015567,-.096757,
.001471,-.09799,
.018464,-.096246,
.034897,-.091577,
.050269,-.084126,
.06186,-.07601,
.05689,-.07103,
0.0*
4,1,18,-.07103,-.05689,
-.07983,-.043691,
-.086204,-.029165,
-.089959,-.013753,
-.09098,.002077,
-.089237,.017844,
-.084783,.033069,
-.077753,.047289,
-.07103,.05689,
-.07601,.06186,
-.085597,.047721,
-.092583,.032132,
-.096757,.015567,
-.09799,-.001471,
-.096246,-.018464,
-.091577,-.034897,
-.084126,-.050269,
-.07601,-.06186,
-.07103,-.05689,
0.0*
4,1,18,-.05689,.07103,
-.043691,.07983,
-.029165,.086204,
-.013753,.089959,
.002077,.09098,
.017844,.089237,
.033069,.084783,
.047289,.077753,
.05689,.07103,
.06186,.07601,
.047721,.085597,
.032132,.092583,
.015567,.096757,
-.001471,.09799,
-.018464,.096246,
-.034897,.091577,
-.050269,.084126,
-.06186,.07601,
-.05689,.07103,
0.0*
%
%ADD66MACRO66*%
%AMMACRO51*
4,1,15,.02475,.01414,
.026829,.009627,
.028094,.004822,
.028504,-.000129,
.028049,-.005077,
.026741,-.009871,
.02475,-.01414,
.02984,-.01923,
.032726,-.013756,
.034617,-.007864,
.035457,-.001734,
.03522,.00445,
.033912,.010498,
.031574,.016227,
.02984,.01923,
.02475,.01414,
0.0*
4,1,15,.01414,-.02475,
.009627,-.026829,
.004822,-.028094,
-.000129,-.028504,
-.005077,-.028049,
-.009871,-.026741,
-.01414,-.02475,
-.01923,-.02984,
-.013756,-.032726,
-.007864,-.034617,
-.001734,-.035457,
.00445,-.03522,
.010498,-.033912,
.016227,-.031574,
.01923,-.02984,
.01414,-.02475,
0.0*
4,1,15,-.02475,-.01414,
-.026829,-.009627,
-.028094,-.004822,
-.028504,.000129,
-.028049,.005077,
-.026741,.009871,
-.02475,.01414,
-.02984,.01923,
-.032726,.013756,
-.034617,.007864,
-.035457,.001734,
-.03522,-.00445,
-.033912,-.010498,
-.031574,-.016227,
-.02984,-.01923,
-.02475,-.01414,
0.0*
4,1,15,-.01414,.02475,
-.009627,.026829,
-.004822,.028094,
.000129,.028504,
.005077,.028049,
.009871,.026741,
.01414,.02475,
.01923,.02984,
.013756,.032726,
.007864,.034617,
.001734,.035457,
-.00445,.03522,
-.010498,.033912,
-.016227,.031574,
-.01923,.02984,
-.01414,.02475,
0.0*
%
%ADD51MACRO51*%
%AMMACRO38*
4,1,16,.02511,.01451,
.027248,.009929,
.028558,.005047,
.029001,.000011,
.028562,-.005025,
.027256,-.009909,
.025121,-.014491,
.02511,-.01451,
.0302,-.01959,
.033143,-.014048,
.035079,-.00808,
.035949,-.001865,
.035727,.004405,
.034419,.010542,
.032065,.016359,
.0302,.01959,
.02511,.01451,
90.*
4,1,16,.01451,-.02511,
.009929,-.027248,
.005047,-.028558,
.000011,-.029001,
-.005025,-.028562,
-.009909,-.027256,
-.014491,-.025121,
-.01451,-.02511,
-.01959,-.0302,
-.014048,-.033143,
-.00808,-.035079,
-.001865,-.035949,
.004405,-.035727,
.010542,-.034419,
.016359,-.032065,
.01959,-.0302,
.01451,-.02511,
90.*
4,1,16,-.02511,-.01451,
-.027248,-.009929,
-.028558,-.005047,
-.029001,-.000011,
-.028562,.005025,
-.027256,.009909,
-.025121,.014491,
-.02511,.01451,
-.0302,.01959,
-.033143,.014048,
-.035079,.00808,
-.035949,.001865,
-.035727,-.004405,
-.034419,-.010542,
-.032065,-.016359,
-.0302,-.01959,
-.02511,-.01451,
90.*
4,1,16,-.01451,.02511,
-.009929,.027248,
-.005047,.028558,
-.000011,.029001,
.005025,.028562,
.009909,.027256,
.014491,.025121,
.01451,.02511,
.01959,.0302,
.014048,.033143,
.00808,.035079,
.001865,.035949,
-.004405,.035727,
-.010542,.034419,
-.016359,.032065,
-.01959,.0302,
-.01451,.02511,
90.*
%
%ADD38MACRO38*%
%AMMACRO28*
4,1,16,.02511,.01451,
.027248,.009929,
.028558,.005047,
.029001,.000011,
.028562,-.005025,
.027256,-.009909,
.025121,-.014491,
.02511,-.01451,
.0302,-.01959,
.033143,-.014048,
.035079,-.00808,
.035949,-.001865,
.035727,.004405,
.034419,.010542,
.032065,.016359,
.0302,.01959,
.02511,.01451,
0.0*
4,1,16,.01451,-.02511,
.009929,-.027248,
.005047,-.028558,
.000011,-.029001,
-.005025,-.028562,
-.009909,-.027256,
-.014491,-.025121,
-.01451,-.02511,
-.01959,-.0302,
-.014048,-.033143,
-.00808,-.035079,
-.001865,-.035949,
.004405,-.035727,
.010542,-.034419,
.016359,-.032065,
.01959,-.0302,
.01451,-.02511,
0.0*
4,1,16,-.02511,-.01451,
-.027248,-.009929,
-.028558,-.005047,
-.029001,-.000011,
-.028562,.005025,
-.027256,.009909,
-.025121,.014491,
-.02511,.01451,
-.0302,.01959,
-.033143,.014048,
-.035079,.00808,
-.035949,.001865,
-.035727,-.004405,
-.034419,-.010542,
-.032065,-.016359,
-.0302,-.01959,
-.02511,-.01451,
0.0*
4,1,16,-.01451,.02511,
-.009929,.027248,
-.005047,.028558,
-.000011,.029001,
.005025,.028562,
.009909,.027256,
.014491,.025121,
.01451,.02511,
.01959,.0302,
.014048,.033143,
.00808,.035079,
.001865,.035949,
-.004405,.035727,
-.010542,.034419,
-.016359,.032065,
-.01959,.0302,
-.01451,.02511,
0.0*
%
%ADD28MACRO28*%
%AMMACRO78*
4,1,15,.03682,.01914,
.039584,.012455,
.041146,.005393,
.041457,-.001834,
.040509,-.009005,
.03833,-.015903,
.03682,-.01914,
.04197,-.0243,
.045552,-.016643,
.04775,-.00848,
.048497,-.000059,
.047771,.008363,
.045593,.016531,
.042029,.024197,
.04197,.0243,
.03682,.01914,
0.0*
4,1,15,.01914,-.03682,
.012455,-.039584,
.005393,-.041146,
-.001834,-.041457,
-.009005,-.040509,
-.015903,-.03833,
-.01914,-.03682,
-.0243,-.04197,
-.016643,-.045552,
-.00848,-.04775,
-.000059,-.048497,
.008363,-.047771,
.016531,-.045593,
.024197,-.042029,
.0243,-.04197,
.01914,-.03682,
0.0*
4,1,15,-.03682,-.01914,
-.039584,-.012455,
-.041146,-.005393,
-.041457,.001834,
-.040509,.009005,
-.03833,.015903,
-.03682,.01914,
-.04197,.0243,
-.045552,.016643,
-.04775,.00848,
-.048497,.000059,
-.047771,-.008363,
-.045593,-.016531,
-.042029,-.024197,
-.04197,-.0243,
-.03682,-.01914,
0.0*
4,1,15,-.01914,.03682,
-.012455,.039584,
-.005393,.041146,
.001834,.041457,
.009005,.040509,
.015903,.03833,
.01914,.03682,
.0243,.04197,
.016643,.045552,
.00848,.04775,
.000059,.048497,
-.008363,.047771,
-.016531,.045593,
-.024197,.042029,
-.0243,.04197,
-.01914,.03682,
0.0*
%
%ADD78MACRO78*%
%AMMACRO75*
4,1,15,-.03682,.01914,
-.039584,.012455,
-.041146,.005393,
-.041457,-.001834,
-.040509,-.009005,
-.03833,-.015903,
-.03682,-.01914,
-.04197,-.0243,
-.045552,-.016643,
-.04775,-.00848,
-.048497,-.000059,
-.047771,.008363,
-.045593,.016531,
-.042029,.024197,
-.04197,.0243,
-.03682,.01914,
0.0*
4,1,15,-.01914,-.03682,
-.012455,-.039584,
-.005393,-.041146,
.001834,-.041457,
.009005,-.040509,
.015903,-.03833,
.01914,-.03682,
.0243,-.04197,
.016643,-.045552,
.00848,-.04775,
.000059,-.048497,
-.008363,-.047771,
-.016531,-.045593,
-.024197,-.042029,
-.0243,-.04197,
-.01914,-.03682,
0.0*
4,1,15,.03682,-.01914,
.039584,-.012455,
.041146,-.005393,
.041457,.001834,
.040509,.009005,
.03833,.015903,
.03682,.01914,
.04197,.0243,
.045552,.016643,
.04775,.00848,
.048497,.000059,
.047771,-.008363,
.045593,-.016531,
.042029,-.024197,
.04197,-.0243,
.03682,-.01914,
0.0*
4,1,15,.01914,.03682,
.012455,.039584,
.005393,.041146,
-.001834,.041457,
-.009005,.040509,
-.015903,.03833,
-.01914,.03682,
-.0243,.04197,
-.016643,.045552,
-.00848,.04775,
-.000059,.048497,
.008363,.047771,
.016531,.045593,
.024197,.042029,
.0243,.04197,
.01914,.03682,
0.0*
%
%ADD75MACRO75*%
%AMMACRO23*
4,1,25,-.0605,.00499,
-.05909,.011105,
-.05664,.016881,
-.053224,.022145,
-.048946,.026736,
-.043935,.030513,
-.038345,.033364,
-.032345,.0352,
-.02985,.03564,
-.025195,.035958,
-.02422,.03599,
-.005,.03599,
-.005,.03099,
-.02474,.03099,
-.026534,.030943,
-.028322,.030793,
-.02985,.03058,
-.035086,.029247,
-.040011,.027025,
-.044475,.023982,
-.048343,.020209,
-.051497,.015823,
-.053842,.010955,
-.055305,.005754,
-.05544,.00499,
-.0605,.00499,
0.0*
4,1,27,.005,.03599,
.02451,.03599,
.026071,.035998,
.027631,.035916,
.029183,.035743,
.02985,.03564,
.035965,.03423,
.041741,.03178,
.047005,.028364,
.051596,.024086,
.055373,.019075,
.058224,.013485,
.06006,.007485,
.0605,.00499,
.05544,.00499,
.054107,.010226,
.051885,.015151,
.048842,.019615,
.045069,.023483,
.040683,.026637,
.035815,.028982,
.030614,.030445,
.02985,.03058,
.0281,.030818,
.02634,.030955,
.02482,.03099,
.005,.03099,
.005,.03599,
0.0*
4,1,25,-.0605,-.00501,
-.05544,-.00501,
-.054107,-.010246,
-.051885,-.015171,
-.048842,-.019635,
-.045069,-.023503,
-.040683,-.026657,
-.035815,-.029002,
-.030614,-.030465,
-.02985,-.0306,
-.028079,-.03084,
-.026298,-.030976,
-.02487,-.03101,
-.005,-.03101,
-.005,-.03601,
-.02375,-.03601,
-.028562,-.035772,
-.02985,-.03566,
-.035965,-.03425,
-.041741,-.0318,
-.047005,-.028384,
-.051596,-.024106,
-.055373,-.019095,
-.058224,-.013505,
-.06006,-.007505,
-.0605,-.00501,
0.0*
4,1,27,.005,-.03101,
.02485,-.03101,
.02659,-.030963,
.028324,-.030815,
.02985,-.0306,
.035086,-.029267,
.040011,-.027045,
.044475,-.024002,
.048343,-.020229,
.051497,-.015843,
.053842,-.010975,
.055305,-.005774,
.05544,-.00501,
.0605,-.00501,
.05909,-.011125,
.05664,-.016901,
.053224,-.022165,
.048946,-.026756,
.043935,-.030533,
.038345,-.033384,
.032345,-.03522,
.02985,-.03566,
.028758,-.035841,
.027658,-.035958,
.026553,-.036011,
.02578,-.03601,
.005,-.03601,
.005,-.03101,
0.0*
%
%ADD23MACRO23*%
%ADD61R,.285X.23*%
%ADD68C,.142*%
%AMMACRO62*
4,1,36,0.0,.01,
-.001736,.009848,
-.00342,.009397,
-.005,.00866,
-.006428,.00766,
-.00766,.006428,
-.00866,.005,
-.009397,.00342,
-.009848,.001736,
-.01,0.0,
-.009848,-.001736,
-.009397,-.00342,
-.00866,-.005,
-.00766,-.006428,
-.006428,-.00766,
-.005,-.00866,
-.00342,-.009397,
-.001736,-.009848,
0.0,-.01,
.001736,-.009848,
.00342,-.009397,
.005,-.00866,
.006428,-.00766,
.00766,-.006428,
.00866,-.005,
.009397,-.00342,
.009848,-.001736,
.01,0.0,
.009848,.001736,
.009397,.00342,
.00866,.005,
.00766,.006428,
.006428,.00766,
.005,.00866,
.00342,.009397,
.001736,.009848,
0.0,.01,
180.*
%
%ADD62MACRO62*%
%ADD33O,.219X.156*%
%ADD13C,.125*%
%AMMACRO69*
4,1,36,.0025,0.0,
.002462,.000434,
.002349,.000855,
.002165,.00125,
.001915,.001607,
.001607,.001915,
.00125,.002165,
.000855,.002349,
.000434,.002462,
0.0,.0025,
-.000434,.002462,
-.000855,.002349,
-.00125,.002165,
-.001607,.001915,
-.001915,.001607,
-.002165,.00125,
-.002349,.000855,
-.002462,.000434,
-.0025,0.0,
-.002462,-.000434,
-.002349,-.000855,
-.002165,-.00125,
-.001915,-.001607,
-.001607,-.001915,
-.00125,-.002165,
-.000855,-.002349,
-.000434,-.002462,
0.0,-.0025,
.000434,-.002462,
.000855,-.002349,
.00125,-.002165,
.001607,-.001915,
.001915,-.001607,
.002165,-.00125,
.002349,-.000855,
.002462,-.000434,
.0025,0.0,
30.*
%
%ADD69MACRO69*%
%ADD18C,.424*%
%ADD21C,.155*%
%ADD54C,.291*%
%ADD39C,.165*%
%ADD56C,.247*%
%ADD45C,.256*%
%AMMACRO34*
4,1,36,0.0,.0085,
.001476,.008371,
.002907,.007987,
.00425,.007361,
.005464,.006511,
.006511,.005464,
.007361,.00425,
.007987,.002907,
.008371,.001476,
.0085,0.0,
.008371,-.001476,
.007987,-.002907,
.007361,-.00425,
.006511,-.005464,
.005464,-.006511,
.00425,-.007361,
.002907,-.007987,
.001476,-.008371,
0.0,-.0085,
-.001476,-.008371,
-.002907,-.007987,
-.00425,-.007361,
-.005464,-.006511,
-.006511,-.005464,
-.007361,-.00425,
-.007987,-.002907,
-.008371,-.001476,
-.0085,0.0,
-.008371,.001476,
-.007987,.002907,
-.007361,.00425,
-.006511,.005464,
-.005464,.006511,
-.00425,.007361,
-.002907,.007987,
-.001476,.008371,
0.0,.0085,
180.*
%
%ADD34MACRO34*%
%AMMACRO60*
4,1,20,-.0075,-.05555,
-.0075,-.06273,
-.013677,-.060878,
-.019439,-.057981,
-.024611,-.054127,
-.029034,-.049434,
-.032576,-.044045,
-.035127,-.038122,
-.036612,-.031846,
-.037,-.0265,
-.037,-.0075,
-.03,-.0075,
-.03,-.0265,
-.029544,-.03171,
-.028191,-.036762,
-.02598,-.041502,
-.022981,-.045786,
-.019282,-.049484,
-.014998,-.052484,
-.010258,-.054694,
-.0075,-.05555,
90.*
4,1,20,.0075,-.06273,
.0075,-.05555,
.01243,-.053806,
.016983,-.051232,
.02102,-.047906,
.024418,-.043931,
.027073,-.039425,
.028906,-.034527,
.029861,-.029385,
.03,-.0265,
.03,-.0075,
.037,-.0075,
.037,-.0265,
.036438,-.032925,
.034769,-.039154,
.032043,-.044999,
.028344,-.050282,
.023784,-.054842,
.018501,-.058541,
.012656,-.061266,
.0075,-.06273,
90.*
4,1,20,-.0075,.06273,
-.0075,.05555,
-.01243,.053806,
-.016983,.051232,
-.02102,.047906,
-.024418,.043931,
-.027073,.039425,
-.028906,.034527,
-.029861,.029385,
-.03,.0265,
-.03,.0075,
-.037,.0075,
-.037,.0265,
-.036438,.032925,
-.034769,.039154,
-.032043,.044999,
-.028344,.050282,
-.023784,.054842,
-.018501,.058541,
-.012656,.061266,
-.0075,.06273,
90.*
4,1,20,.0075,.05555,
.0075,.06273,
.013677,.060878,
.019439,.057981,
.024611,.054127,
.029034,.049434,
.032576,.044045,
.035127,.038122,
.036612,.031846,
.037,.0265,
.037,.0075,
.03,.0075,
.03,.0265,
.029544,.03171,
.028191,.036762,
.02598,.041502,
.022981,.045786,
.019282,.049484,
.014998,.052484,
.010258,.054694,
.0075,.05555,
90.*
%
%ADD60MACRO60*%
%AMMACRO20*
4,1,36,.0025,0.0,
.002462,.000434,
.002349,.000855,
.002165,.00125,
.001915,.001607,
.001607,.001915,
.00125,.002165,
.000855,.002349,
.000434,.002462,
0.0,.0025,
-.000434,.002462,
-.000855,.002349,
-.00125,.002165,
-.001607,.001915,
-.001915,.001607,
-.002165,.00125,
-.002349,.000855,
-.002462,.000434,
-.0025,0.0,
-.002462,-.000434,
-.002349,-.000855,
-.002165,-.00125,
-.001915,-.001607,
-.001607,-.001915,
-.00125,-.002165,
-.000855,-.002349,
-.000434,-.002462,
0.0,-.0025,
.000434,-.002462,
.000855,-.002349,
.00125,-.002165,
.001607,-.001915,
.001915,-.001607,
.002165,-.00125,
.002349,-.000855,
.002462,-.000434,
.0025,0.0,
90.*
%
%ADD20MACRO20*%
%AMMACRO57*
4,1,36,0.0,.019,
-.003299,.018711,
-.006498,.017854,
-.0095,.016454,
-.012213,.014555,
-.014555,.012213,
-.016454,.0095,
-.017854,.006498,
-.018711,.003299,
-.019,0.0,
-.018711,-.003299,
-.017854,-.006498,
-.016454,-.0095,
-.014555,-.012213,
-.012213,-.014555,
-.0095,-.016454,
-.006498,-.017854,
-.003299,-.018711,
0.0,-.019,
.003299,-.018711,
.006498,-.017854,
.0095,-.016454,
.012213,-.014555,
.014555,-.012213,
.016454,-.0095,
.017854,-.006498,
.018711,-.003299,
.019,0.0,
.018711,.003299,
.017854,.006498,
.016454,.0095,
.014555,.012213,
.012213,.014555,
.0095,.016454,
.006498,.017854,
.003299,.018711,
0.0,.019,
270.*
%
%ADD57MACRO57*%
%AMMACRO43*
4,1,36,.003,0.0,
.002954,.000521,
.002819,.001026,
.002598,.0015,
.002298,.001928,
.001928,.002298,
.0015,.002598,
.001026,.002819,
.000521,.002954,
0.0,.003,
-.000521,.002954,
-.001026,.002819,
-.0015,.002598,
-.001928,.002298,
-.002298,.001928,
-.002598,.0015,
-.002819,.001026,
-.002954,.000521,
-.003,0.0,
-.002954,-.000521,
-.002819,-.001026,
-.002598,-.0015,
-.002298,-.001928,
-.001928,-.002298,
-.0015,-.002598,
-.001026,-.002819,
-.000521,-.002954,
0.0,-.003,
.000521,-.002954,
.001026,-.002819,
.0015,-.002598,
.001928,-.002298,
.002298,-.001928,
.002598,-.0015,
.002819,-.001026,
.002954,-.000521,
.003,0.0,
90.*
%
%ADD43MACRO43*%
%AMMACRO12*
4,1,36,.0025,0.0,
.002462,.000434,
.002349,.000855,
.002165,.00125,
.001915,.001607,
.001607,.001915,
.00125,.002165,
.000855,.002349,
.000434,.002462,
0.0,.0025,
-.000434,.002462,
-.000855,.002349,
-.00125,.002165,
-.001607,.001915,
-.001915,.001607,
-.002165,.00125,
-.002349,.000855,
-.002462,.000434,
-.0025,0.0,
-.002462,-.000434,
-.002349,-.000855,
-.002165,-.00125,
-.001915,-.001607,
-.001607,-.001915,
-.00125,-.002165,
-.000855,-.002349,
-.000434,-.002462,
0.0,-.0025,
.000434,-.002462,
.000855,-.002349,
.00125,-.002165,
.001607,-.001915,
.001915,-.001607,
.002165,-.00125,
.002349,-.000855,
.002462,-.000434,
.0025,0.0,
0.0*
%
%ADD12MACRO12*%
%AMMACRO72*
4,1,36,-.003,0.0,
-.002954,.000521,
-.002819,.001026,
-.002598,.0015,
-.002298,.001928,
-.001928,.002298,
-.0015,.002598,
-.001026,.002819,
-.000521,.002954,
0.0,.003,
.000521,.002954,
.001026,.002819,
.0015,.002598,
.001928,.002298,
.002298,.001928,
.002598,.0015,
.002819,.001026,
.002954,.000521,
.003,0.0,
.002954,-.000521,
.002819,-.001026,
.002598,-.0015,
.002298,-.001928,
.001928,-.002298,
.0015,-.002598,
.001026,-.002819,
.000521,-.002954,
0.0,-.003,
-.000521,-.002954,
-.001026,-.002819,
-.0015,-.002598,
-.001928,-.002298,
-.002298,-.001928,
-.002598,-.0015,
-.002819,-.001026,
-.002954,-.000521,
-.003,0.0,
90.*
%
%ADD72MACRO72*%
%AMMACRO64*
4,1,36,-.0025,0.0,
-.002462,.000434,
-.002349,.000855,
-.002165,.00125,
-.001915,.001607,
-.001607,.001915,
-.00125,.002165,
-.000855,.002349,
-.000434,.002462,
0.0,.0025,
.000434,.002462,
.000855,.002349,
.00125,.002165,
.001607,.001915,
.001915,.001607,
.002165,.00125,
.002349,.000855,
.002462,.000434,
.0025,0.0,
.002462,-.000434,
.002349,-.000855,
.002165,-.00125,
.001915,-.001607,
.001607,-.001915,
.00125,-.002165,
.000855,-.002349,
.000434,-.002462,
0.0,-.0025,
-.000434,-.002462,
-.000855,-.002349,
-.00125,-.002165,
-.001607,-.001915,
-.001915,-.001607,
-.002165,-.00125,
-.002349,-.000855,
-.002462,-.000434,
-.0025,0.0,
0.0*
%
%ADD64MACRO64*%
%ADD58C,.188*%
%AMMACRO16*
4,1,36,.003,0.0,
.002954,.000521,
.002819,.001026,
.002598,.0015,
.002298,.001928,
.001928,.002298,
.0015,.002598,
.001026,.002819,
.000521,.002954,
0.0,.003,
-.000521,.002954,
-.001026,.002819,
-.0015,.002598,
-.001928,.002298,
-.002298,.001928,
-.002598,.0015,
-.002819,.001026,
-.002954,.000521,
-.003,0.0,
-.002954,-.000521,
-.002819,-.001026,
-.002598,-.0015,
-.002298,-.001928,
-.001928,-.002298,
-.0015,-.002598,
-.001026,-.002819,
-.000521,-.002954,
0.0,-.003,
.000521,-.002954,
.001026,-.002819,
.0015,-.002598,
.001928,-.002298,
.002298,-.001928,
.002598,-.0015,
.002819,-.001026,
.002954,-.000521,
.003,0.0,
0.0*
%
%ADD16MACRO16*%
%AMMACRO25*
4,1,16,.02584,.01524,
.028094,.010521,
.029494,.005483,
.029998,.000278,
.029591,-.004935,
.028284,-.009999,
.026118,-.014758,
.02584,-.01524,
.03092,-.02032,
.033979,-.014642,
.036005,-.008519,
.036938,-.002138,
.036748,.004309,
.035441,.010625,
.033058,.016618,
.03092,.02032,
.02584,.01524,
180.*
4,1,16,.01524,-.02584,
.010521,-.028094,
.005483,-.029494,
.000278,-.029998,
-.004935,-.029591,
-.009999,-.028284,
-.014758,-.026118,
-.01524,-.02584,
-.02032,-.03092,
-.014642,-.033979,
-.008519,-.036005,
-.002138,-.036938,
.004309,-.036748,
.010625,-.035441,
.016618,-.033058,
.02032,-.03092,
.01524,-.02584,
180.*
4,1,16,-.02584,-.01524,
-.028094,-.010521,
-.029494,-.005483,
-.029998,-.000278,
-.029591,.004935,
-.028284,.009999,
-.026118,.014758,
-.02584,.01524,
-.03092,.02032,
-.033979,.014642,
-.036005,.008519,
-.036938,.002138,
-.036748,-.004309,
-.035441,-.010625,
-.033058,-.016618,
-.03092,-.02032,
-.02584,-.01524,
180.*
4,1,16,-.01524,.02584,
-.010521,.028094,
-.005483,.029494,
-.000278,.029998,
.004935,.029591,
.009999,.028284,
.014758,.026118,
.01524,.02584,
.02032,.03092,
.014642,.033979,
.008519,.036005,
.002138,.036938,
-.004309,.036748,
-.010625,.035441,
-.016618,.033058,
-.02032,.03092,
-.01524,.02584,
180.*
%
%ADD25MACRO25*%
%AMMACRO65*
4,1,15,.02438,.01377,
.026401,.009327,
.027619,.004601,
.027999,-.000265,
.027527,-.005123,
.02622,-.009825,
.02438,-.01377,
.02948,-.01887,
.032309,-.013464,
.034156,-.007649,
.034965,-.001602,
.034712,.004494,
.033405,.010454,
.031082,.016095,
.02948,.01887,
.02438,.01377,
270.*
4,1,15,.01377,-.02438,
.009327,-.026401,
.004601,-.027619,
-.000265,-.027999,
-.005123,-.027527,
-.009825,-.02622,
-.01377,-.02438,
-.01887,-.02948,
-.013464,-.032309,
-.007649,-.034156,
-.001602,-.034965,
.004494,-.034712,
.010454,-.033405,
.016095,-.031082,
.01887,-.02948,
.01377,-.02438,
270.*
4,1,15,-.02438,-.01377,
-.026401,-.009327,
-.027619,-.004601,
-.027999,.000265,
-.027527,.005123,
-.02622,.009825,
-.02438,.01377,
-.02948,.01887,
-.032309,.013464,
-.034156,.007649,
-.034965,.001602,
-.034712,-.004494,
-.033405,-.010454,
-.031082,-.016095,
-.02948,-.01887,
-.02438,-.01377,
270.*
4,1,15,-.01377,.02438,
-.009327,.026401,
-.004601,.027619,
.000265,.027999,
.005123,.027527,
.009825,.02622,
.01377,.02438,
.01887,.02948,
.013464,.032309,
.007649,.034156,
.001602,.034965,
-.004494,.034712,
-.010454,.033405,
-.016095,.031082,
-.01887,.02948,
-.01377,.02438,
270.*
%
%ADD65MACRO65*%
%AMMACRO70*
4,1,15,.02475,.01414,
.026829,.009627,
.028094,.004822,
.028504,-.000129,
.028049,-.005077,
.026741,-.009871,
.02475,-.01414,
.02984,-.01923,
.032726,-.013756,
.034617,-.007864,
.035457,-.001734,
.03522,.00445,
.033912,.010498,
.031574,.016227,
.02984,.01923,
.02475,.01414,
180.*
4,1,15,.01414,-.02475,
.009627,-.026829,
.004822,-.028094,
-.000129,-.028504,
-.005077,-.028049,
-.009871,-.026741,
-.01414,-.02475,
-.01923,-.02984,
-.013756,-.032726,
-.007864,-.034617,
-.001734,-.035457,
.00445,-.03522,
.010498,-.033912,
.016227,-.031574,
.01923,-.02984,
.01414,-.02475,
180.*
4,1,15,-.02475,-.01414,
-.026829,-.009627,
-.028094,-.004822,
-.028504,.000129,
-.028049,.005077,
-.026741,.009871,
-.02475,.01414,
-.02984,.01923,
-.032726,.013756,
-.034617,.007864,
-.035457,.001734,
-.03522,-.00445,
-.033912,-.010498,
-.031574,-.016227,
-.02984,-.01923,
-.02475,-.01414,
180.*
4,1,15,-.01414,.02475,
-.009627,.026829,
-.004822,.028094,
.000129,.028504,
.005077,.028049,
.009871,.026741,
.01414,.02475,
.01923,.02984,
.013756,.032726,
.007864,.034617,
.001734,.035457,
-.00445,.03522,
-.010498,.033912,
-.016227,.031574,
-.01923,.02984,
-.01414,.02475,
180.*
%
%ADD70MACRO70*%
%AMMACRO47*
4,1,15,.02475,.01414,
.026829,.009627,
.028094,.004822,
.028504,-.000129,
.028049,-.005077,
.026741,-.009871,
.02475,-.01414,
.02984,-.01923,
.032726,-.013756,
.034617,-.007864,
.035457,-.001734,
.03522,.00445,
.033912,.010498,
.031574,.016227,
.02984,.01923,
.02475,.01414,
270.*
4,1,15,.01414,-.02475,
.009627,-.026829,
.004822,-.028094,
-.000129,-.028504,
-.005077,-.028049,
-.009871,-.026741,
-.01414,-.02475,
-.01923,-.02984,
-.013756,-.032726,
-.007864,-.034617,
-.001734,-.035457,
.00445,-.03522,
.010498,-.033912,
.016227,-.031574,
.01923,-.02984,
.01414,-.02475,
270.*
4,1,15,-.02475,-.01414,
-.026829,-.009627,
-.028094,-.004822,
-.028504,.000129,
-.028049,.005077,
-.026741,.009871,
-.02475,.01414,
-.02984,.01923,
-.032726,.013756,
-.034617,.007864,
-.035457,.001734,
-.03522,-.00445,
-.033912,-.010498,
-.031574,-.016227,
-.02984,-.01923,
-.02475,-.01414,
270.*
4,1,15,-.01414,.02475,
-.009627,.026829,
-.004822,.028094,
.000129,.028504,
.005077,.028049,
.009871,.026741,
.01414,.02475,
.01923,.02984,
.013756,.032726,
.007864,.034617,
.001734,.035457,
-.00445,.03522,
-.010498,.033912,
-.016227,.031574,
-.01923,.02984,
-.01414,.02475,
270.*
%
%ADD47MACRO47*%
%AMMACRO59*
4,1,15,.04124,.02356,
.044705,.016041,
.046811,.008034,
.047495,-.000216,
.046736,-.008461,
.044557,-.016448,
.04124,-.02356,
.04635,-.02867,
.050624,-.020186,
.05336,-.011088,
.054475,-.001654,
.053935,.007831,
.051756,.017077,
.048004,.025805,
.04635,.02867,
.04124,.02356,
0.0*
4,1,15,.02356,-.04124,
.016041,-.044705,
.008034,-.046811,
-.000216,-.047495,
-.008461,-.046736,
-.016448,-.044557,
-.02356,-.04124,
-.02867,-.04635,
-.020186,-.050624,
-.011088,-.05336,
-.001654,-.054475,
.007831,-.053935,
.017077,-.051756,
.025805,-.048004,
.02867,-.04635,
.02356,-.04124,
0.0*
4,1,15,-.04124,-.02356,
-.044705,-.016041,
-.046811,-.008034,
-.047495,.000216,
-.046736,.008461,
-.044557,.016448,
-.04124,.02356,
-.04635,.02867,
-.050624,.020186,
-.05336,.011088,
-.054475,.001654,
-.053935,-.007831,
-.051756,-.017077,
-.048004,-.025805,
-.04635,-.02867,
-.04124,-.02356,
0.0*
4,1,15,-.02356,.04124,
-.016041,.044705,
-.008034,.046811,
.000216,.047495,
.008461,.046736,
.016448,.044557,
.02356,.04124,
.02867,.04635,
.020186,.050624,
.011088,.05336,
.001654,.054475,
-.007831,.053935,
-.017077,.051756,
-.025805,.048004,
-.02867,.04635,
-.02356,.04124,
0.0*
%
%ADD59MACRO59*%
%AMMACRO79*
4,1,15,.03682,.01914,
.039584,.012455,
.041146,.005393,
.041457,-.001834,
.040509,-.009005,
.03833,-.015903,
.03682,-.01914,
.04197,-.0243,
.045552,-.016643,
.04775,-.00848,
.048497,-.000059,
.047771,.008363,
.045593,.016531,
.042029,.024197,
.04197,.0243,
.03682,.01914,
180.*
4,1,15,.01914,-.03682,
.012455,-.039584,
.005393,-.041146,
-.001834,-.041457,
-.009005,-.040509,
-.015903,-.03833,
-.01914,-.03682,
-.0243,-.04197,
-.016643,-.045552,
-.00848,-.04775,
-.000059,-.048497,
.008363,-.047771,
.016531,-.045593,
.024197,-.042029,
.0243,-.04197,
.01914,-.03682,
180.*
4,1,15,-.03682,-.01914,
-.039584,-.012455,
-.041146,-.005393,
-.041457,.001834,
-.040509,.009005,
-.03833,.015903,
-.03682,.01914,
-.04197,.0243,
-.045552,.016643,
-.04775,.00848,
-.048497,.000059,
-.047771,-.008363,
-.045593,-.016531,
-.042029,-.024197,
-.04197,-.0243,
-.03682,-.01914,
180.*
4,1,15,-.01914,.03682,
-.012455,.039584,
-.005393,.041146,
.001834,.041457,
.009005,.040509,
.015903,.03833,
.01914,.03682,
.0243,.04197,
.016643,.045552,
.00848,.04775,
.000059,.048497,
-.008363,.047771,
-.016531,.045593,
-.024197,.042029,
-.0243,.04197,
-.01914,.03682,
180.*
%
%ADD79MACRO79*%
%AMMACRO77*
4,1,15,-.03682,.01914,
-.039584,.012455,
-.041146,.005393,
-.041457,-.001834,
-.040509,-.009005,
-.03833,-.015903,
-.03682,-.01914,
-.04197,-.0243,
-.045552,-.016643,
-.04775,-.00848,
-.048497,-.000059,
-.047771,.008363,
-.045593,.016531,
-.042029,.024197,
-.04197,.0243,
-.03682,.01914,
180.*
4,1,15,-.01914,-.03682,
-.012455,-.039584,
-.005393,-.041146,
.001834,-.041457,
.009005,-.040509,
.015903,-.03833,
.01914,-.03682,
.0243,-.04197,
.016643,-.045552,
.00848,-.04775,
.000059,-.048497,
-.008363,-.047771,
-.016531,-.045593,
-.024197,-.042029,
-.0243,-.04197,
-.01914,-.03682,
180.*
4,1,15,.03682,-.01914,
.039584,-.012455,
.041146,-.005393,
.041457,.001834,
.040509,.009005,
.03833,.015903,
.03682,.01914,
.04197,.0243,
.045552,.016643,
.04775,.00848,
.048497,.000059,
.047771,-.008363,
.045593,-.016531,
.042029,-.024197,
.04197,-.0243,
.03682,-.01914,
180.*
4,1,15,.01914,.03682,
.012455,.039584,
.005393,.041146,
-.001834,.041457,
-.009005,.040509,
-.015903,.03833,
-.01914,.03682,
-.0243,.04197,
-.016643,.045552,
-.00848,.04775,
-.000059,.048497,
.008363,.047771,
.016531,.045593,
.024197,.042029,
.0243,.04197,
.01914,.03682,
180.*
%
%ADD77MACRO77*%
%ADD80C,.006*%
%ADD105C,.04006*%
%ADD102C,.03016*%
%ADD98C,.03018*%
%ADD103C,.07008*%
%ADD83C,.07306*%
%ADD90C,.07208*%
%ADD94C,.07308*%
%ADD95C,.07608*%
%ADD93C,.07808*%
%ADD92C,.09708*%
%ADD89O,.1621X.2251*%
%ADD85C,.311*%
%ADD100C,.1621*%
%ADD82O,.03004X.06404*%
%ADD101C,.16211*%
%ADD97C,.1751*%
%ADD81O,.03006X.06406*%
%ADD96C,.43406*%
%ADD84C,.16506*%
%ADD91C,.25806*%
%ADD99C,.43376*%
%ADD104C,.19786*%
%ADD88O,.43374X.77626*%
%ADD86O,.43374X.69752*%
%ADD87O,.43376X.69754*%
G75*
%LPD*%
G75*
G36*
G01X-984580Y-698988D02*
X5868320D01*
Y4193602D01*
X-984580D01*
Y-698988D01*
G37*
%LPC*%
G75*
G36*
G01X1828062Y36504D02*
X1828081Y36500D01*
G03X1828470Y36462I388J1962D01*
G03X1828859Y36500I1J2000D01*
G01X1828878Y36504D01*
X1849606D01*
G02X1855480Y30630I0J-5874D01*
G01Y-40945D01*
G02X1849606Y-46819I-5874J0D01*
G01X7874D01*
G02X2000Y-40945I0J5874D01*
G01Y30630D01*
G02X7874Y36504I5874J0D01*
G01X35835D01*
G02X41709Y30630I0J-5874D01*
G01Y-3937D01*
G03X51583Y-13811I9874J0D01*
G01X321661D01*
G03X331535Y-3937I0J9874D01*
G01Y30630D01*
G02X337409Y36504I5874J0D01*
G01X480717D01*
G02X486591Y30630I0J-5874D01*
G01Y16850D01*
G03X496465Y6976I9874J0D01*
G01X766543D01*
G03X776417Y16850I0J9874D01*
G01Y30630D01*
G02X782291Y36504I5874J0D01*
G01X879134D01*
G03X889008Y46378I0J9874D01*
G01Y122824D01*
X895188Y129004D01*
X1002542D01*
X1009024Y122522D01*
Y46378D01*
G03X1018898Y36504I9874J0D01*
G01X1510244D01*
G02X1516118Y30630I0J-5874D01*
G01Y-3937D01*
G03X1525992Y-13811I9874J0D01*
G01X1796071D01*
G03X1805945Y-3937I0J9874D01*
G01Y30630D01*
G02X1811819Y36504I5874J0D01*
G01X1828062D01*
G37*
G36*
G01X1829886Y1650538D02*
X1829890D01*
Y1650237D01*
X1829889Y1650231D01*
G03X1829820Y1649712I1931J-521D01*
G03X1829886Y1649203I2000J1D01*
G01Y1612316D01*
G03X1832779Y1605332I9877J0D01*
G01X1839978Y1598133D01*
G02X1841697Y1593983I-4151J-4151D01*
G01Y326095D01*
G03X1844590Y319111I9878J1D01*
G01X1853757Y309944D01*
G02X1855476Y305794I-4151J-4151D01*
G01Y54252D01*
G02X1849606Y48382I-5870J0D01*
G01X1829186D01*
Y48378D01*
X1827844D01*
Y48382D01*
X1803945D01*
G03X1794067Y38504I0J-9878D01*
G01Y3937D01*
G02X1792134Y2004I-1933J0D01*
G01X1529929D01*
G02X1527996Y3937I0J1933D01*
G01Y38504D01*
G03X1518118Y48382I-9878J0D01*
G01X1026772D01*
G02X1020902Y54252I0J5870D01*
G01Y131004D01*
G03X1011024Y140882I-9878J0D01*
G01X887008D01*
G03X877130Y131004I0J-9878D01*
G01Y54252D01*
G02X871260Y48382I-5870J0D01*
G01X774417D01*
G03X764539Y38504I0J-9878D01*
G01Y24724D01*
G02X762606Y22791I-1933J0D01*
G01X500402D01*
G02X498469Y24724I0J1933D01*
G01Y38504D01*
G03X488591Y48382I-9878J0D01*
G01X329535D01*
G03X319657Y38504I0J-9878D01*
G01Y3937D01*
G02X317724Y2004I-1933J0D01*
G01X55520D01*
G02X53587Y3937I0J1933D01*
G01Y38504D01*
G03X43709Y48382I-9878J0D01*
G01X7874D01*
G02X2004Y54252I0J5870D01*
G01Y305794D01*
G02X3723Y309944I5870J-1D01*
G01X6985Y313206D01*
G03X9878Y320190I-6984J6984D01*
G01Y1588078D01*
G02X11597Y1592228I5870J-1D01*
G01X24701Y1605332D01*
G03X27595Y1612316I-6983J6985D01*
G01Y1732244D01*
G02X33465Y1738114I5870J0D01*
G01X765732D01*
Y1736890D01*
G03X769705Y1732917I3973J0D01*
G01X1087854D01*
G03X1091827Y1736890I0J3973D01*
G01Y1738114D01*
X1824016D01*
G02X1829886Y1732244I0J-5870D01*
G01Y1650538D01*
G37*
G36*
G01X1867354Y305795D02*
G03X1862156Y318343I-17746J-1D01*
G01X1855296Y325203D01*
G02X1853575Y329357I4153J4154D01*
G01Y1593984D01*
G03X1848377Y1606532I-17746J-1D01*
G01X1843484Y1611425D01*
G02X1841764Y1615579I4156J4154D01*
G01Y1732244D01*
G02X1847638Y1738118I5874J0D01*
G01X1857480D01*
G03X1867354Y1747992I0J9874D01*
G01Y1815072D01*
G02X1873228Y1820946I5874J0D01*
G01X2093700D01*
G02X2099574Y1815072I0J-5874D01*
G01Y1791450D01*
G02X2093700Y1785576I-5874J0D01*
G01X2031574D01*
G03X2021700Y1775702I0J-9874D01*
G01Y1229954D01*
G03X2031574Y1220080I9874J0D01*
G01X2093700D01*
G02X2099574Y1214206I0J-5874D01*
G01Y-40945D01*
G02X2093700Y-46819I-5874J0D01*
G01X1873228D01*
G02X1867354Y-40945I0J5874D01*
G01Y305795D01*
G37*
%LPD*%
G75*
G36*
G01X381207Y1105426D02*
G02X384015I1404J0D01*
G02X382796Y1104034I-1404J0D01*
G01X382698Y1104021D01*
X382019Y1102846D01*
G02X382166Y1102221I-1257J-625D01*
G02X379358I-1404J0D01*
G02X380672Y1103622I1404J0D01*
G01X381352Y1104797D01*
X381314Y1104889D01*
G02X381207Y1105426I1297J538D01*
G37*
G36*
G01X1357349D02*
G02X1360157I1404J0D01*
G02X1358938Y1104034I-1404J0D01*
G01X1358840Y1104021D01*
X1358161Y1102846D01*
G02X1358308Y1102221I-1257J-625D01*
G02X1355500I-1404J0D01*
G02X1356814Y1103622I1404J0D01*
G01X1357494Y1104797D01*
X1357456Y1104889D01*
G02X1357349Y1105426I1297J538D01*
G37*
G36*
G01X349758Y1108630D02*
G02X352566I1404J0D01*
G01Y1108629D01*
G02X352460Y1108093I-1404J-1D01*
G01X352422Y1108002D01*
X353101Y1106827D01*
G02X354415Y1105426I-90J-1401D01*
G02X351607I-1404J0D01*
G02X351754Y1106051I1404J0D01*
G01X351075Y1107225D01*
X350977Y1107238D01*
G02X349758Y1108630I185J1392D01*
G37*
G36*
G01X364557Y1108628D02*
Y1108630D01*
G02X367365I1404J0D01*
G02X366146Y1107238I-1404J0D01*
G01X366048Y1107225D01*
X365369Y1106051D01*
G02X365516Y1105426I-1257J-625D01*
G02X362708I-1404J0D01*
G02X364022Y1106827I1404J0D01*
G01X364701Y1108003D01*
X364663Y1108094D01*
G02X364557Y1108628I1298J535D01*
G37*
G36*
G01X1325900Y1108630D02*
G02X1328708I1404J0D01*
G01Y1108629D01*
G02X1328602Y1108093I-1404J-1D01*
G01X1328564Y1108002D01*
X1329243Y1106827D01*
G02X1330557Y1105426I-90J-1401D01*
G02X1327749I-1404J0D01*
G02X1327896Y1106051I1404J0D01*
G01X1327217Y1107225D01*
X1327119Y1107238D01*
G02X1325900Y1108630I185J1392D01*
G37*
G36*
G01X1340699Y1108628D02*
Y1108630D01*
G02X1343507I1404J0D01*
G02X1342288Y1107238I-1404J0D01*
G01X1342190Y1107225D01*
X1341511Y1106051D01*
G02X1341658Y1105426I-1257J-625D01*
G02X1338850I-1404J0D01*
G02X1340164Y1106827I1404J0D01*
G01X1340843Y1108003D01*
X1340805Y1108094D01*
G02X1340699Y1108628I1298J535D01*
G37*
G36*
G01X390458Y1115039D02*
G02X393266I1404J0D01*
G02X393159Y1114502I-1404J1D01*
G01X393121Y1114410D01*
X393801Y1113235D01*
G02X395115Y1111834I-90J-1401D01*
G02X392307I-1404J0D01*
G02X392454Y1112459I1404J0D01*
G01X391775Y1113634D01*
X391677Y1113647D01*
G02X390458Y1115039I185J1392D01*
G37*
G36*
G01X412658D02*
G02X415466I1404J0D01*
G02X415359Y1114502I-1404J1D01*
G01X415321Y1114410D01*
X416001Y1113235D01*
G02X417315Y1111834I-90J-1401D01*
G02X414507I-1404J0D01*
G02X414654Y1112459I1404J0D01*
G01X413975Y1113634D01*
X413877Y1113647D01*
G02X412658Y1115039I185J1392D01*
G37*
G36*
G01X1366600D02*
G02X1369408I1404J0D01*
G02X1369301Y1114502I-1404J1D01*
G01X1369263Y1114410D01*
X1369943Y1113235D01*
G02X1371257Y1111834I-90J-1401D01*
G02X1368449I-1404J0D01*
G02X1368596Y1112459I1404J0D01*
G01X1367917Y1113634D01*
X1367819Y1113647D01*
G02X1366600Y1115039I185J1392D01*
G37*
G36*
G01X1388800D02*
G02X1391608I1404J0D01*
G02X1391501Y1114502I-1404J1D01*
G01X1391463Y1114410D01*
X1392143Y1113235D01*
G02X1393457Y1111834I-90J-1401D01*
G02X1390649I-1404J0D01*
G02X1390796Y1112459I1404J0D01*
G01X1390117Y1113634D01*
X1390019Y1113647D01*
G02X1388800Y1115039I185J1392D01*
G37*
G36*
G01X1758669Y52153D02*
G02X1760173Y50649I0J-1504D01*
G01Y50648D01*
G02X1760172Y50593I-1504J0D01*
G02X1758669Y49100I-1503J10D01*
G01X1755269D01*
G02X1753766Y50593I0J1503D01*
G02X1753765Y50648I1503J55D01*
G01Y50649D01*
G02X1755269Y52153I1504J0D01*
G02X1755620Y52112I2J-1504D01*
G01X1755643Y52106D01*
X1758295D01*
X1758318Y52112D01*
G02X1758669Y52153I349J-1463D01*
G37*
G36*
G01X1394374Y172851D02*
G02X1395334Y173198I960J-1154D01*
G01X1398734D01*
G02X1400236Y171696I0J-1502D01*
G02X1398743Y170194I-1502J0D01*
G02X1398182Y170076I-561J1276D01*
G02X1397656Y170179I0J1394D01*
G01X1397620Y170194D01*
X1395334D01*
G02X1394882Y170264I1J1502D01*
G02X1394184Y170076I-699J1206D01*
G01X1394182D01*
G02Y172864I0J1394D01*
G02X1394374Y172851I2J-1394D01*
G37*
G36*
G01X880168Y504762D02*
Y508162D01*
G02X881670Y509664I1502J0D01*
G02X882945Y508955I0J-1501D01*
G02X883184Y508142I-1265J-813D01*
G01Y508141D01*
G02X883173Y507963I-1504J4D01*
G01X883172Y507952D01*
Y504897D01*
X883173Y504888D01*
G02X883180Y504743I-1493J-145D01*
G01Y504742D01*
G02X881680Y503242I-1500J0D01*
G02X880398Y503963I0J1500D01*
G02X880168Y504762I1273J799D01*
G37*
G36*
G01X356723Y844971D02*
G02X359531I1404J0D01*
G02X358310Y843579I-1404J0D01*
G01X358208Y843565D01*
X357485Y842193D01*
X357532Y842101D01*
G02X357683Y841468I-1252J-633D01*
G01Y841467D01*
G02X354875I-1404J0D01*
G02X356096Y842859I1404J0D01*
G01X356198Y842873D01*
X356921Y844245D01*
X356874Y844337D01*
G02X356723Y844970I1252J633D01*
G01Y844971D01*
G37*
G36*
G01X364123D02*
G02X366931I1404J0D01*
G02X365710Y843579I-1404J0D01*
G01X365608Y843565D01*
X364885Y842193D01*
X364932Y842101D01*
G02X365083Y841468I-1252J-633D01*
G01Y841467D01*
G02X362275I-1404J0D01*
G02X363496Y842859I1404J0D01*
G01X363598Y842873D01*
X364321Y844245D01*
X364274Y844337D01*
G02X364123Y844970I1252J633D01*
G01Y844971D01*
G37*
G36*
G01X371523D02*
G02X374331I1404J0D01*
G02X373110Y843579I-1404J0D01*
G01X373008Y843565D01*
X372285Y842193D01*
X372332Y842101D01*
G02X372483Y841468I-1252J-633D01*
G01Y841467D01*
G02X369675I-1404J0D01*
G02X370896Y842859I1404J0D01*
G01X370998Y842873D01*
X371721Y844245D01*
X371674Y844337D01*
G02X371523Y844970I1252J633D01*
G01Y844971D01*
G37*
G36*
G01X378923D02*
G02X381731I1404J0D01*
G02X380510Y843579I-1404J0D01*
G01X380408Y843565D01*
X379685Y842193D01*
X379732Y842101D01*
G02X379883Y841468I-1252J-633D01*
G01Y841467D01*
G02X377075I-1404J0D01*
G02X378296Y842859I1404J0D01*
G01X378398Y842873D01*
X379121Y844245D01*
X379074Y844337D01*
G02X378923Y844970I1252J633D01*
G01Y844971D01*
G37*
G36*
G01X386323D02*
G02X389131I1404J0D01*
G02X387910Y843579I-1404J0D01*
G01X387808Y843565D01*
X387085Y842193D01*
X387132Y842101D01*
G02X387283Y841468I-1252J-633D01*
G01Y841467D01*
G02X384475I-1404J0D01*
G02X385696Y842859I1404J0D01*
G01X385798Y842873D01*
X386521Y844245D01*
X386474Y844337D01*
G02X386323Y844970I1252J633D01*
G01Y844971D01*
G37*
G36*
G01X393723D02*
G02X396531I1404J0D01*
G02X395310Y843579I-1404J0D01*
G01X395208Y843565D01*
X394485Y842193D01*
X394532Y842101D01*
G02X394683Y841468I-1252J-633D01*
G01Y841467D01*
G02X391875I-1404J0D01*
G02X393096Y842859I1404J0D01*
G01X393198Y842873D01*
X393921Y844245D01*
X393874Y844337D01*
G02X393723Y844970I1252J633D01*
G01Y844971D01*
G37*
G36*
G01X401123D02*
G02X403931I1404J0D01*
G02X402710Y843579I-1404J0D01*
G01X402608Y843565D01*
X401885Y842193D01*
X401932Y842101D01*
G02X402083Y841468I-1252J-633D01*
G01Y841467D01*
G02X399275I-1404J0D01*
G02X400496Y842859I1404J0D01*
G01X400598Y842873D01*
X401321Y844245D01*
X401274Y844337D01*
G02X401123Y844970I1252J633D01*
G01Y844971D01*
G37*
G36*
G01X408523D02*
G02X411331I1404J0D01*
G02X410110Y843579I-1404J0D01*
G01X410008Y843565D01*
X409285Y842193D01*
X409332Y842101D01*
G02X409483Y841468I-1252J-633D01*
G01Y841467D01*
G02X406675I-1404J0D01*
G02X407896Y842859I1404J0D01*
G01X407998Y842873D01*
X408721Y844245D01*
X408674Y844337D01*
G02X408523Y844970I1252J633D01*
G01Y844971D01*
G37*
G36*
G01X415923D02*
G02X418731I1404J0D01*
G02X417510Y843579I-1404J0D01*
G01X417408Y843565D01*
X416685Y842193D01*
X416732Y842101D01*
G02X416883Y841468I-1252J-633D01*
G01Y841467D01*
G02X414075I-1404J0D01*
G02X415296Y842859I1404J0D01*
G01X415398Y842873D01*
X416121Y844245D01*
X416074Y844337D01*
G02X415923Y844970I1252J633D01*
G01Y844971D01*
G37*
G36*
G01X423323D02*
G02X426131I1404J0D01*
G02X424910Y843579I-1404J0D01*
G01X424808Y843565D01*
X424085Y842193D01*
X424132Y842101D01*
G02X424283Y841468I-1252J-633D01*
G01Y841467D01*
G02X421475I-1404J0D01*
G02X422696Y842859I1404J0D01*
G01X422798Y842873D01*
X423521Y844245D01*
X423474Y844337D01*
G02X423323Y844970I1252J633D01*
G01Y844971D01*
G37*
G36*
G01X452923D02*
G02X455731I1404J0D01*
G02X454510Y843579I-1404J0D01*
G01X454408Y843565D01*
X453685Y842193D01*
X453732Y842101D01*
G02X453883Y841468I-1252J-633D01*
G01Y841467D01*
G02X451075I-1404J0D01*
G02X452296Y842859I1404J0D01*
G01X452398Y842873D01*
X453121Y844245D01*
X453074Y844337D01*
G02X452923Y844970I1252J633D01*
G01Y844971D01*
G37*
G36*
G01X460323D02*
G02X463131I1404J0D01*
G02X461910Y843579I-1404J0D01*
G01X461808Y843565D01*
X461085Y842193D01*
X461132Y842101D01*
G02X461283Y841468I-1252J-633D01*
G01Y841467D01*
G02X458475I-1404J0D01*
G02X459696Y842859I1404J0D01*
G01X459798Y842873D01*
X460521Y844245D01*
X460474Y844337D01*
G02X460323Y844970I1252J633D01*
G01Y844971D01*
G37*
G36*
G01X467723D02*
G02X470531I1404J0D01*
G02X469310Y843579I-1404J0D01*
G01X469208Y843565D01*
X468485Y842193D01*
X468532Y842101D01*
G02X468683Y841468I-1252J-633D01*
G01Y841467D01*
G02X465875I-1404J0D01*
G02X467096Y842859I1404J0D01*
G01X467198Y842873D01*
X467921Y844245D01*
X467874Y844337D01*
G02X467723Y844970I1252J633D01*
G01Y844971D01*
G37*
G36*
G01X475123D02*
G02X477931I1404J0D01*
G02X476710Y843579I-1404J0D01*
G01X476608Y843565D01*
X475885Y842193D01*
X475932Y842101D01*
G02X476083Y841468I-1252J-633D01*
G01Y841467D01*
G02X473275I-1404J0D01*
G02X474496Y842859I1404J0D01*
G01X474598Y842873D01*
X475321Y844245D01*
X475274Y844337D01*
G02X475123Y844970I1252J633D01*
G01Y844971D01*
G37*
G36*
G01X482523D02*
G02X485331I1404J0D01*
G02X484110Y843579I-1404J0D01*
G01X484008Y843565D01*
X483285Y842193D01*
X483332Y842101D01*
G02X483483Y841468I-1252J-633D01*
G01Y841467D01*
G02X480675I-1404J0D01*
G02X481896Y842859I1404J0D01*
G01X481998Y842873D01*
X482721Y844245D01*
X482674Y844337D01*
G02X482523Y844970I1252J633D01*
G01Y844971D01*
G37*
G36*
G01X489923D02*
G02X492731I1404J0D01*
G02X491468Y843574I-1404J0D01*
G01X491361Y843563D01*
X490665Y842223D01*
X490715Y842130D01*
G02X490882Y841467I-1237J-664D01*
G02X488074I-1404J0D01*
G02X489366Y842867I1405J0D01*
G01X489476Y842875D01*
X490157Y844188D01*
X490104Y844282D01*
G02X489923Y844971I1223J689D01*
G37*
G36*
G01X497323D02*
G02X500131I1404J0D01*
G02X498910Y843579I-1404J0D01*
G01X498808Y843565D01*
X498084Y842193D01*
X498131Y842101D01*
G02X498282Y841468I-1252J-633D01*
G01Y841467D01*
G02X495474I-1404J0D01*
G02X496695Y842859I1404J0D01*
G01X496798Y842873D01*
X497521Y844245D01*
X497474Y844337D01*
G02X497323Y844970I1252J633D01*
G01Y844971D01*
G37*
G36*
G01X504723D02*
G02X507531I1404J0D01*
G02X506310Y843579I-1404J0D01*
G01X506208Y843565D01*
X505485Y842193D01*
X505532Y842101D01*
G02X505683Y841468I-1252J-633D01*
G01Y841467D01*
G02X502875I-1404J0D01*
G02X504096Y842859I1404J0D01*
G01X504198Y842873D01*
X504921Y844245D01*
X504874Y844337D01*
G02X504723Y844970I1252J633D01*
G01Y844971D01*
G37*
G36*
G01X512123D02*
G02X514931I1404J0D01*
G02X513710Y843579I-1404J0D01*
G01X513608Y843565D01*
X512885Y842193D01*
X512932Y842101D01*
G02X513083Y841468I-1252J-633D01*
G01Y841467D01*
G02X510275I-1404J0D01*
G02X511496Y842859I1404J0D01*
G01X511598Y842873D01*
X512321Y844245D01*
X512274Y844337D01*
G02X512123Y844970I1252J633D01*
G01Y844971D01*
G37*
G36*
G01X519523D02*
G02X522331I1404J0D01*
G02X521110Y843579I-1404J0D01*
G01X521008Y843565D01*
X520285Y842193D01*
X520332Y842101D01*
G02X520483Y841468I-1252J-633D01*
G01Y841467D01*
G02X517675I-1404J0D01*
G02X518896Y842859I1404J0D01*
G01X518998Y842873D01*
X519721Y844245D01*
X519674Y844337D01*
G02X519523Y844970I1252J633D01*
G01Y844971D01*
G37*
G36*
G01X1332865D02*
G02X1335673I1404J0D01*
G02X1334452Y843579I-1404J0D01*
G01X1334350Y843565D01*
X1333627Y842193D01*
X1333674Y842101D01*
G02X1333825Y841468I-1252J-633D01*
G01Y841467D01*
G02X1331017I-1404J0D01*
G02X1332238Y842859I1404J0D01*
G01X1332340Y842873D01*
X1333063Y844245D01*
X1333016Y844337D01*
G02X1332865Y844970I1252J633D01*
G01Y844971D01*
G37*
G36*
G01X1340265D02*
G02X1343073I1404J0D01*
G02X1341852Y843579I-1404J0D01*
G01X1341750Y843565D01*
X1341027Y842193D01*
X1341074Y842101D01*
G02X1341225Y841468I-1252J-633D01*
G01Y841467D01*
G02X1338417I-1404J0D01*
G02X1339638Y842859I1404J0D01*
G01X1339740Y842873D01*
X1340463Y844245D01*
X1340416Y844337D01*
G02X1340265Y844970I1252J633D01*
G01Y844971D01*
G37*
G36*
G01X1347665D02*
G02X1350473I1404J0D01*
G02X1349252Y843579I-1404J0D01*
G01X1349150Y843565D01*
X1348427Y842193D01*
X1348474Y842101D01*
G02X1348625Y841468I-1252J-633D01*
G01Y841467D01*
G02X1345817I-1404J0D01*
G02X1347038Y842859I1404J0D01*
G01X1347140Y842873D01*
X1347863Y844245D01*
X1347816Y844337D01*
G02X1347665Y844970I1252J633D01*
G01Y844971D01*
G37*
G36*
G01X1355065D02*
G02X1357873I1404J0D01*
G02X1356652Y843579I-1404J0D01*
G01X1356550Y843565D01*
X1355827Y842193D01*
X1355874Y842101D01*
G02X1356025Y841468I-1252J-633D01*
G01Y841467D01*
G02X1353217I-1404J0D01*
G02X1354438Y842859I1404J0D01*
G01X1354540Y842873D01*
X1355263Y844245D01*
X1355216Y844337D01*
G02X1355065Y844970I1252J633D01*
G01Y844971D01*
G37*
G36*
G01X1362465D02*
G02X1365273I1404J0D01*
G02X1364052Y843579I-1404J0D01*
G01X1363950Y843565D01*
X1363227Y842193D01*
X1363274Y842101D01*
G02X1363425Y841468I-1252J-633D01*
G01Y841467D01*
G02X1360617I-1404J0D01*
G02X1361838Y842859I1404J0D01*
G01X1361940Y842873D01*
X1362663Y844245D01*
X1362616Y844337D01*
G02X1362465Y844970I1252J633D01*
G01Y844971D01*
G37*
G36*
G01X1369865D02*
G02X1372673I1404J0D01*
G02X1371452Y843579I-1404J0D01*
G01X1371350Y843565D01*
X1370627Y842193D01*
X1370674Y842101D01*
G02X1370825Y841468I-1252J-633D01*
G01Y841467D01*
G02X1368017I-1404J0D01*
G02X1369238Y842859I1404J0D01*
G01X1369340Y842873D01*
X1370063Y844245D01*
X1370016Y844337D01*
G02X1369865Y844970I1252J633D01*
G01Y844971D01*
G37*
G36*
G01X1377265D02*
G02X1380073I1404J0D01*
G02X1378852Y843579I-1404J0D01*
G01X1378750Y843565D01*
X1378027Y842193D01*
X1378074Y842101D01*
G02X1378225Y841468I-1252J-633D01*
G01Y841467D01*
G02X1375417I-1404J0D01*
G02X1376638Y842859I1404J0D01*
G01X1376740Y842873D01*
X1377463Y844245D01*
X1377416Y844337D01*
G02X1377265Y844970I1252J633D01*
G01Y844971D01*
G37*
G36*
G01X1384665D02*
G02X1387473I1404J0D01*
G02X1386252Y843579I-1404J0D01*
G01X1386150Y843565D01*
X1385427Y842193D01*
X1385474Y842101D01*
G02X1385625Y841468I-1252J-633D01*
G01Y841467D01*
G02X1382817I-1404J0D01*
G02X1384038Y842859I1404J0D01*
G01X1384140Y842873D01*
X1384863Y844245D01*
X1384816Y844337D01*
G02X1384665Y844970I1252J633D01*
G01Y844971D01*
G37*
G36*
G01X1392065D02*
G02X1394873I1404J0D01*
G02X1393652Y843579I-1404J0D01*
G01X1393550Y843565D01*
X1392827Y842193D01*
X1392874Y842101D01*
G02X1393025Y841468I-1252J-633D01*
G01Y841467D01*
G02X1390217I-1404J0D01*
G02X1391438Y842859I1404J0D01*
G01X1391540Y842873D01*
X1392263Y844245D01*
X1392216Y844337D01*
G02X1392065Y844970I1252J633D01*
G01Y844971D01*
G37*
G36*
G01X1399465D02*
G02X1402273I1404J0D01*
G02X1401052Y843579I-1404J0D01*
G01X1400950Y843565D01*
X1400227Y842193D01*
X1400274Y842101D01*
G02X1400425Y841468I-1252J-633D01*
G01Y841467D01*
G02X1397617I-1404J0D01*
G02X1398838Y842859I1404J0D01*
G01X1398940Y842873D01*
X1399663Y844245D01*
X1399616Y844337D01*
G02X1399465Y844970I1252J633D01*
G01Y844971D01*
G37*
G36*
G01X351174Y848176D02*
G02X353982I1404J0D01*
G02X353875Y847639I-1404J1D01*
G01X353837Y847547D01*
X354514Y846376D01*
X354612Y846363D01*
G02X355831Y844971I-185J-1392D01*
G02X353023I-1404J0D01*
G02X353130Y845508I1404J-1D01*
G01X353168Y845600D01*
X352491Y846771D01*
X352393Y846784D01*
G02X351174Y848176I185J1392D01*
G37*
G36*
G01X358574D02*
G02X361382I1404J0D01*
G02X361275Y847639I-1404J1D01*
G01X361237Y847547D01*
X361914Y846376D01*
X362012Y846363D01*
G02X363231Y844971I-185J-1392D01*
G02X360423I-1404J0D01*
G02X360530Y845508I1404J-1D01*
G01X360568Y845600D01*
X359891Y846771D01*
X359793Y846784D01*
G02X358574Y848176I185J1392D01*
G37*
G36*
G01X365974D02*
G02X368782I1404J0D01*
G02X368675Y847639I-1404J1D01*
G01X368637Y847547D01*
X369314Y846376D01*
X369412Y846363D01*
G02X370631Y844971I-185J-1392D01*
G02X367823I-1404J0D01*
G02X367930Y845508I1404J-1D01*
G01X367968Y845600D01*
X367291Y846771D01*
X367193Y846784D01*
G02X365974Y848176I185J1392D01*
G37*
G36*
G01X373374D02*
G02X376182I1404J0D01*
G02X376075Y847639I-1404J1D01*
G01X376037Y847547D01*
X376714Y846376D01*
X376812Y846363D01*
G02X378031Y844971I-185J-1392D01*
G02X375223I-1404J0D01*
G02X375330Y845508I1404J-1D01*
G01X375368Y845600D01*
X374691Y846771D01*
X374593Y846784D01*
G02X373374Y848176I185J1392D01*
G37*
G36*
G01X380774D02*
G02X383582I1404J0D01*
G02X383475Y847639I-1404J1D01*
G01X383437Y847547D01*
X384114Y846376D01*
X384212Y846363D01*
G02X385431Y844971I-185J-1392D01*
G02X382623I-1404J0D01*
G02X382730Y845508I1404J-1D01*
G01X382768Y845600D01*
X382091Y846771D01*
X381993Y846784D01*
G02X380774Y848176I185J1392D01*
G37*
G36*
G01X388174D02*
G02X390982I1404J0D01*
G02X390875Y847639I-1404J1D01*
G01X390837Y847547D01*
X391514Y846376D01*
X391612Y846363D01*
G02X392831Y844971I-185J-1392D01*
G02X390023I-1404J0D01*
G02X390130Y845508I1404J-1D01*
G01X390168Y845600D01*
X389491Y846771D01*
X389393Y846784D01*
G02X388174Y848176I185J1392D01*
G37*
G36*
G01X395574D02*
G02X398382I1404J0D01*
G02X398275Y847639I-1404J1D01*
G01X398237Y847547D01*
X398914Y846376D01*
X399012Y846363D01*
G02X400231Y844971I-185J-1392D01*
G02X397423I-1404J0D01*
G02X397530Y845508I1404J-1D01*
G01X397568Y845600D01*
X396891Y846771D01*
X396793Y846784D01*
G02X395574Y848176I185J1392D01*
G37*
G36*
G01X402974D02*
G02X405782I1404J0D01*
G02X405675Y847639I-1404J1D01*
G01X405637Y847547D01*
X406314Y846376D01*
X406412Y846363D01*
G02X407631Y844971I-185J-1392D01*
G02X404823I-1404J0D01*
G02X404930Y845508I1404J-1D01*
G01X404968Y845600D01*
X404291Y846771D01*
X404193Y846784D01*
G02X402974Y848176I185J1392D01*
G37*
G36*
G01X410374D02*
G02X413182I1404J0D01*
G02X413075Y847639I-1404J1D01*
G01X413037Y847547D01*
X413714Y846376D01*
X413812Y846363D01*
G02X415031Y844971I-185J-1392D01*
G02X412223I-1404J0D01*
G02X412330Y845508I1404J-1D01*
G01X412368Y845600D01*
X411691Y846771D01*
X411593Y846784D01*
G02X410374Y848176I185J1392D01*
G37*
G36*
G01X417774D02*
G02X420582I1404J0D01*
G02X420475Y847639I-1404J1D01*
G01X420437Y847547D01*
X421114Y846376D01*
X421212Y846363D01*
G02X422431Y844971I-185J-1392D01*
G02X419623I-1404J0D01*
G02X419730Y845508I1404J-1D01*
G01X419768Y845600D01*
X419091Y846771D01*
X418993Y846784D01*
G02X417774Y848176I185J1392D01*
G37*
G36*
G01X425174D02*
G02X427982I1404J0D01*
G02X427875Y847639I-1404J1D01*
G01X427837Y847547D01*
X428514Y846376D01*
X428612Y846363D01*
G02X429831Y844971I-185J-1392D01*
G02X427023I-1404J0D01*
G02X427130Y845508I1404J-1D01*
G01X427168Y845600D01*
X426491Y846771D01*
X426393Y846784D01*
G02X425174Y848176I185J1392D01*
G37*
G36*
G01X436274D02*
G02X439082I1404J0D01*
G02X437861Y846784I-1404J0D01*
G01X437759Y846770D01*
X437035Y845397D01*
X437082Y845305D01*
G02X437233Y844672I-1252J-633D01*
G01Y844671D01*
G02X434425I-1404J0D01*
G02X435646Y846063I1404J0D01*
G01X435748Y846077D01*
X436472Y847450D01*
X436425Y847542D01*
G02X436274Y848175I1252J633D01*
G01Y848176D01*
G37*
G36*
G01X447374D02*
G02X450182I1404J0D01*
G02X450075Y847639I-1404J1D01*
G01X450037Y847547D01*
X450715Y846376D01*
X450812Y846363D01*
G02X452032Y844971I-184J-1392D01*
G02X449224I-1404J0D01*
G02X449331Y845508I1404J-1D01*
G01X449369Y845600D01*
X448691Y846771D01*
X448594Y846784D01*
G02X447374Y848176I184J1392D01*
G37*
G36*
G01X454774D02*
G02X457582I1404J0D01*
G02X457475Y847639I-1404J1D01*
G01X457437Y847547D01*
X458114Y846376D01*
X458212Y846363D01*
G02X459431Y844971I-185J-1392D01*
G02X456623I-1404J0D01*
G02X456730Y845508I1404J-1D01*
G01X456768Y845600D01*
X456091Y846771D01*
X455993Y846784D01*
G02X454774Y848176I185J1392D01*
G37*
G36*
G01X462174D02*
G02X464982I1404J0D01*
G02X464875Y847639I-1404J1D01*
G01X464837Y847547D01*
X465514Y846376D01*
X465612Y846363D01*
G02X466831Y844971I-185J-1392D01*
G02X464023I-1404J0D01*
G02X464130Y845508I1404J-1D01*
G01X464168Y845600D01*
X463491Y846771D01*
X463393Y846784D01*
G02X462174Y848176I185J1392D01*
G37*
G36*
G01X469574D02*
G02X472382I1404J0D01*
G02X472275Y847639I-1404J1D01*
G01X472237Y847547D01*
X472914Y846376D01*
X473012Y846363D01*
G02X474231Y844971I-185J-1392D01*
G02X471423I-1404J0D01*
G02X471530Y845508I1404J-1D01*
G01X471568Y845600D01*
X470891Y846771D01*
X470793Y846784D01*
G02X469574Y848176I185J1392D01*
G37*
G36*
G01X476974D02*
G02X479782I1404J0D01*
G02X479675Y847639I-1404J1D01*
G01X479637Y847547D01*
X480314Y846376D01*
X480412Y846363D01*
G02X481631Y844971I-185J-1392D01*
G02X478823I-1404J0D01*
G02X478930Y845508I1404J-1D01*
G01X478968Y845600D01*
X478291Y846771D01*
X478193Y846784D01*
G02X476974Y848176I185J1392D01*
G37*
G36*
G01X484374D02*
G02X487182I1404J0D01*
G02X487075Y847639I-1404J1D01*
G01X487037Y847547D01*
X487714Y846376D01*
X487812Y846363D01*
G02X489031Y844971I-185J-1392D01*
G02X486223I-1404J0D01*
G02X486330Y845508I1404J-1D01*
G01X486368Y845600D01*
X485691Y846771D01*
X485593Y846784D01*
G02X484374Y848176I185J1392D01*
G37*
G36*
G01X491774D02*
G02X494582I1404J0D01*
G02X494475Y847639I-1404J1D01*
G01X494437Y847547D01*
X495114Y846376D01*
X495212Y846363D01*
G02X496431Y844971I-185J-1392D01*
G02X493623I-1404J0D01*
G02X493730Y845508I1404J-1D01*
G01X493768Y845600D01*
X493091Y846771D01*
X492993Y846784D01*
G02X491774Y848176I185J1392D01*
G37*
G36*
G01X499174D02*
G02X501982I1404J0D01*
G02X501875Y847639I-1404J1D01*
G01X501837Y847547D01*
X502514Y846376D01*
X502612Y846363D01*
G02X503831Y844971I-185J-1392D01*
G02X501023I-1404J0D01*
G02X501130Y845508I1404J-1D01*
G01X501168Y845600D01*
X500491Y846771D01*
X500393Y846784D01*
G02X499174Y848176I185J1392D01*
G37*
G36*
G01X506574D02*
G02X509382I1404J0D01*
G02X509275Y847639I-1404J1D01*
G01X509237Y847547D01*
X509914Y846376D01*
X510012Y846363D01*
G02X511231Y844971I-185J-1392D01*
G02X508423I-1404J0D01*
G02X508530Y845508I1404J-1D01*
G01X508568Y845600D01*
X507891Y846771D01*
X507793Y846784D01*
G02X506574Y848176I185J1392D01*
G37*
G36*
G01X513974D02*
G02X516782I1404J0D01*
G02X516675Y847639I-1404J1D01*
G01X516637Y847547D01*
X517314Y846376D01*
X517412Y846363D01*
G02X518631Y844971I-185J-1392D01*
G02X515823I-1404J0D01*
G02X515930Y845508I1404J-1D01*
G01X515968Y845600D01*
X515291Y846771D01*
X515193Y846784D01*
G02X513974Y848176I185J1392D01*
G37*
G36*
G01X521374D02*
G02X524182I1404J0D01*
G02X524075Y847639I-1404J1D01*
G01X524037Y847547D01*
X524714Y846376D01*
X524812Y846363D01*
G02X526031Y844971I-185J-1392D01*
G02X523223I-1404J0D01*
G02X523330Y845508I1404J-1D01*
G01X523368Y845600D01*
X522691Y846771D01*
X522593Y846784D01*
G02X521374Y848176I185J1392D01*
G37*
G36*
G01X1327316D02*
G02X1330124I1404J0D01*
G02X1330017Y847639I-1404J1D01*
G01X1329979Y847547D01*
X1330656Y846376D01*
X1330754Y846363D01*
G02X1331973Y844971I-185J-1392D01*
G02X1329165I-1404J0D01*
G02X1329272Y845508I1404J-1D01*
G01X1329310Y845600D01*
X1328633Y846771D01*
X1328535Y846784D01*
G02X1327316Y848176I185J1392D01*
G37*
G36*
G01X1334716D02*
G02X1337524I1404J0D01*
G02X1337417Y847639I-1404J1D01*
G01X1337379Y847547D01*
X1338056Y846376D01*
X1338154Y846363D01*
G02X1339373Y844971I-185J-1392D01*
G02X1336565I-1404J0D01*
G02X1336672Y845508I1404J-1D01*
G01X1336710Y845600D01*
X1336033Y846771D01*
X1335935Y846784D01*
G02X1334716Y848176I185J1392D01*
G37*
G36*
G01X1342116D02*
G02X1344924I1404J0D01*
G02X1344817Y847639I-1404J1D01*
G01X1344779Y847547D01*
X1345456Y846376D01*
X1345554Y846363D01*
G02X1346773Y844971I-185J-1392D01*
G02X1343965I-1404J0D01*
G02X1344072Y845508I1404J-1D01*
G01X1344110Y845600D01*
X1343433Y846771D01*
X1343335Y846784D01*
G02X1342116Y848176I185J1392D01*
G37*
G36*
G01X1349516D02*
G02X1352324I1404J0D01*
G02X1352217Y847639I-1404J1D01*
G01X1352179Y847547D01*
X1352856Y846376D01*
X1352954Y846363D01*
G02X1354173Y844971I-185J-1392D01*
G02X1351365I-1404J0D01*
G02X1351472Y845508I1404J-1D01*
G01X1351510Y845600D01*
X1350833Y846771D01*
X1350735Y846784D01*
G02X1349516Y848176I185J1392D01*
G37*
G36*
G01X1356916D02*
G02X1359724I1404J0D01*
G02X1359617Y847639I-1404J1D01*
G01X1359579Y847547D01*
X1360256Y846376D01*
X1360354Y846363D01*
G02X1361573Y844971I-185J-1392D01*
G02X1358765I-1404J0D01*
G02X1358872Y845508I1404J-1D01*
G01X1358910Y845600D01*
X1358233Y846771D01*
X1358135Y846784D01*
G02X1356916Y848176I185J1392D01*
G37*
G36*
G01X1364316D02*
G02X1367124I1404J0D01*
G02X1367017Y847639I-1404J1D01*
G01X1366979Y847547D01*
X1367656Y846376D01*
X1367754Y846363D01*
G02X1368973Y844971I-185J-1392D01*
G02X1366165I-1404J0D01*
G02X1366272Y845508I1404J-1D01*
G01X1366310Y845600D01*
X1365633Y846771D01*
X1365535Y846784D01*
G02X1364316Y848176I185J1392D01*
G37*
G36*
G01X1371716D02*
G02X1374524I1404J0D01*
G02X1374417Y847639I-1404J1D01*
G01X1374379Y847547D01*
X1375056Y846376D01*
X1375154Y846363D01*
G02X1376373Y844971I-185J-1392D01*
G02X1373565I-1404J0D01*
G02X1373672Y845508I1404J-1D01*
G01X1373710Y845600D01*
X1373033Y846771D01*
X1372935Y846784D01*
G02X1371716Y848176I185J1392D01*
G37*
G36*
G01X1379116D02*
G02X1381924I1404J0D01*
G02X1381817Y847639I-1404J1D01*
G01X1381779Y847547D01*
X1382456Y846376D01*
X1382554Y846363D01*
G02X1383773Y844971I-185J-1392D01*
G02X1380965I-1404J0D01*
G02X1381072Y845508I1404J-1D01*
G01X1381110Y845600D01*
X1380433Y846771D01*
X1380335Y846784D01*
G02X1379116Y848176I185J1392D01*
G37*
G36*
G01X1386516D02*
G02X1389324I1404J0D01*
G02X1389217Y847639I-1404J1D01*
G01X1389179Y847547D01*
X1389856Y846376D01*
X1389954Y846363D01*
G02X1391173Y844971I-185J-1392D01*
G02X1388365I-1404J0D01*
G02X1388472Y845508I1404J-1D01*
G01X1388510Y845600D01*
X1387833Y846771D01*
X1387735Y846784D01*
G02X1386516Y848176I185J1392D01*
G37*
G36*
G01X1393916D02*
G02X1396724I1404J0D01*
G02X1396617Y847639I-1404J1D01*
G01X1396579Y847547D01*
X1397256Y846376D01*
X1397354Y846363D01*
G02X1398573Y844971I-185J-1392D01*
G02X1395765I-1404J0D01*
G02X1395872Y845508I1404J-1D01*
G01X1395910Y845600D01*
X1395233Y846771D01*
X1395135Y846784D01*
G02X1393916Y848176I185J1392D01*
G37*
G36*
G01X1401316D02*
G02X1404124I1404J0D01*
G02X1404017Y847639I-1404J1D01*
G01X1403979Y847547D01*
X1404656Y846376D01*
X1404754Y846363D01*
G02X1405973Y844971I-185J-1392D01*
G02X1403165I-1404J0D01*
G02X1403272Y845508I1404J-1D01*
G01X1403310Y845600D01*
X1402633Y846771D01*
X1402535Y846784D01*
G02X1401316Y848176I185J1392D01*
G37*
G36*
G01X1412416D02*
G02X1415224I1404J0D01*
G02X1414005Y846784I-1404J0D01*
G01X1413907Y846771D01*
X1413229Y845598D01*
X1413267Y845507D01*
G02X1413373Y844973I-1298J-535D01*
G01Y844971D01*
G02X1410565I-1404J0D01*
G02X1411785Y846363I1404J0D01*
G01X1411883Y846376D01*
X1412560Y847549D01*
X1412522Y847640D01*
G02X1412416Y848174I1298J535D01*
G01Y848176D01*
G37*
G36*
G01X349323Y851380D02*
G02X352131I1404J0D01*
G02X350912Y849988I-1404J0D01*
G01X350814Y849975D01*
X350137Y848805D01*
X350175Y848713D01*
G02X350282Y848176I-1297J-538D01*
G02X347474I-1404J0D01*
G02X348693Y849568I1404J0D01*
G01X348791Y849581D01*
X349468Y850751D01*
X349430Y850843D01*
G02X349323Y851380I1297J538D01*
G37*
G36*
G01X1325465D02*
G02X1328273I1404J0D01*
G02X1327054Y849988I-1404J0D01*
G01X1326956Y849975D01*
X1326279Y848805D01*
X1326317Y848713D01*
G02X1326424Y848176I-1297J-538D01*
G02X1323616I-1404J0D01*
G02X1324835Y849568I1404J0D01*
G01X1324933Y849581D01*
X1325610Y850751D01*
X1325572Y850843D01*
G02X1325465Y851380I1297J538D01*
G37*
G36*
G01X353025Y857789D02*
G02X355833I1404J0D01*
G02X355726Y857252I-1404J1D01*
G01X355688Y857160D01*
X356365Y855989D01*
X356463Y855976D01*
G02X357682Y854584I-185J-1392D01*
G02X354874I-1404J0D01*
G02X354981Y855121I1404J-1D01*
G01X355019Y855213D01*
X354342Y856384D01*
X354244Y856397D01*
G02X353025Y857789I185J1392D01*
G37*
G36*
G01X360425D02*
G02X363233I1404J0D01*
G02X363126Y857252I-1404J1D01*
G01X363088Y857160D01*
X363765Y855989D01*
X363863Y855976D01*
G02X365082Y854584I-185J-1392D01*
G02X362274I-1404J0D01*
G02X362381Y855121I1404J-1D01*
G01X362419Y855213D01*
X361742Y856384D01*
X361644Y856397D01*
G02X360425Y857789I185J1392D01*
G37*
G36*
G01X367825D02*
G02X370633I1404J0D01*
G02X370526Y857252I-1404J1D01*
G01X370488Y857160D01*
X371165Y855989D01*
X371263Y855976D01*
G02X372482Y854584I-185J-1392D01*
G02X369674I-1404J0D01*
G02X369781Y855121I1404J-1D01*
G01X369819Y855213D01*
X369142Y856384D01*
X369044Y856397D01*
G02X367825Y857789I185J1392D01*
G37*
G36*
G01X375225D02*
G02X378033I1404J0D01*
G02X377926Y857252I-1404J1D01*
G01X377888Y857160D01*
X378565Y855989D01*
X378663Y855976D01*
G02X379882Y854584I-185J-1392D01*
G02X377074I-1404J0D01*
G02X377181Y855121I1404J-1D01*
G01X377219Y855213D01*
X376542Y856384D01*
X376444Y856397D01*
G02X375225Y857789I185J1392D01*
G37*
G36*
G01X382625D02*
G02X385433I1404J0D01*
G02X385326Y857252I-1404J1D01*
G01X385288Y857160D01*
X385965Y855989D01*
X386063Y855976D01*
G02X387282Y854584I-185J-1392D01*
G02X384474I-1404J0D01*
G02X384581Y855121I1404J-1D01*
G01X384619Y855213D01*
X383942Y856384D01*
X383844Y856397D01*
G02X382625Y857789I185J1392D01*
G37*
G36*
G01X390025D02*
G02X392833I1404J0D01*
G02X392726Y857252I-1404J1D01*
G01X392688Y857160D01*
X393365Y855989D01*
X393463Y855976D01*
G02X394682Y854584I-185J-1392D01*
G02X391874I-1404J0D01*
G02X391981Y855121I1404J-1D01*
G01X392019Y855213D01*
X391342Y856384D01*
X391244Y856397D01*
G02X390025Y857789I185J1392D01*
G37*
G36*
G01X397425D02*
G02X400233I1404J0D01*
G02X400126Y857252I-1404J1D01*
G01X400088Y857160D01*
X400765Y855989D01*
X400863Y855976D01*
G02X402082Y854584I-185J-1392D01*
G02X399274I-1404J0D01*
G02X399381Y855121I1404J-1D01*
G01X399419Y855213D01*
X398742Y856384D01*
X398644Y856397D01*
G02X397425Y857789I185J1392D01*
G37*
G36*
G01X404825D02*
G02X407633I1404J0D01*
G02X407526Y857252I-1404J1D01*
G01X407488Y857160D01*
X408165Y855989D01*
X408263Y855976D01*
G02X409482Y854584I-185J-1392D01*
G02X406674I-1404J0D01*
G02X406781Y855121I1404J-1D01*
G01X406819Y855213D01*
X406142Y856384D01*
X406044Y856397D01*
G02X404825Y857789I185J1392D01*
G37*
G36*
G01X412225D02*
G02X415033I1404J0D01*
G02X414926Y857252I-1404J1D01*
G01X414888Y857160D01*
X415565Y855989D01*
X415663Y855976D01*
G02X416882Y854584I-185J-1392D01*
G02X414074I-1404J0D01*
G02X414181Y855121I1404J-1D01*
G01X414219Y855213D01*
X413542Y856384D01*
X413444Y856397D01*
G02X412225Y857789I185J1392D01*
G37*
G36*
G01X419625D02*
G02X422433I1404J0D01*
G02X422326Y857252I-1404J1D01*
G01X422288Y857160D01*
X422965Y855989D01*
X423063Y855976D01*
G02X424282Y854584I-185J-1392D01*
G02X421474I-1404J0D01*
G02X421581Y855121I1404J-1D01*
G01X421619Y855213D01*
X420942Y856384D01*
X420844Y856397D01*
G02X419625Y857789I185J1392D01*
G37*
G36*
G01X427025D02*
G02X429833I1404J0D01*
G02X429726Y857252I-1404J1D01*
G01X429688Y857160D01*
X430365Y855989D01*
X430463Y855976D01*
G02X431682Y854584I-185J-1392D01*
G02X428874I-1404J0D01*
G02X428981Y855121I1404J-1D01*
G01X429019Y855213D01*
X428342Y856384D01*
X428244Y856397D01*
G02X427025Y857789I185J1392D01*
G37*
G36*
G01X434425D02*
G02X437233I1404J0D01*
G02X437126Y857252I-1404J1D01*
G01X437088Y857160D01*
X437765Y855989D01*
X437863Y855976D01*
G02X439083Y854584I-184J-1392D01*
G02X436275I-1404J0D01*
G01Y854586D01*
G02X436381Y855120I1404J-1D01*
G01X436419Y855211D01*
X435742Y856384D01*
X435644Y856397D01*
G02X434425Y857789I185J1392D01*
G37*
G36*
G01X445525D02*
G02X448333I1404J0D01*
G02X447114Y856397I-1404J0D01*
G01X447016Y856384D01*
X446338Y855211D01*
X446376Y855120D01*
G02X446482Y854586I-1298J-535D01*
G01Y854584D01*
G02X443674I-1404J0D01*
G02X444896Y855976I1404J0D01*
G01X444994Y855989D01*
X445670Y857160D01*
X445632Y857252D01*
G02X445525Y857789I1297J538D01*
G37*
G36*
G01X452925D02*
G02X455733I1404J0D01*
G02X454514Y856397I-1404J0D01*
G01X454416Y856384D01*
X453738Y855211D01*
X453776Y855120D01*
G02X453882Y854586I-1298J-535D01*
G01Y854584D01*
G02X451074I-1404J0D01*
G02X452296Y855976I1404J0D01*
G01X452394Y855989D01*
X453070Y857160D01*
X453032Y857252D01*
G02X452925Y857789I1297J538D01*
G37*
G36*
G01X460325D02*
G02X463133I1404J0D01*
G02X461914Y856397I-1404J0D01*
G01X461816Y856384D01*
X461138Y855211D01*
X461176Y855120D01*
G02X461282Y854586I-1298J-535D01*
G01Y854584D01*
G02X458474I-1404J0D01*
G02X459696Y855976I1404J0D01*
G01X459794Y855989D01*
X460470Y857160D01*
X460432Y857252D01*
G02X460325Y857789I1297J538D01*
G37*
G36*
G01X467725D02*
G02X470533I1404J0D01*
G02X469314Y856397I-1404J0D01*
G01X469216Y856384D01*
X468538Y855211D01*
X468576Y855120D01*
G02X468682Y854586I-1298J-535D01*
G01Y854584D01*
G02X465874I-1404J0D01*
G02X467096Y855976I1404J0D01*
G01X467194Y855989D01*
X467870Y857160D01*
X467832Y857252D01*
G02X467725Y857789I1297J538D01*
G37*
G36*
G01X475125D02*
G02X477933I1404J0D01*
G02X476714Y856397I-1404J0D01*
G01X476616Y856384D01*
X475938Y855211D01*
X475976Y855120D01*
G02X476082Y854586I-1298J-535D01*
G01Y854584D01*
G02X473274I-1404J0D01*
G02X474496Y855976I1404J0D01*
G01X474594Y855989D01*
X475270Y857160D01*
X475232Y857252D01*
G02X475125Y857789I1297J538D01*
G37*
G36*
G01X482525D02*
G02X485333I1404J0D01*
G02X484114Y856397I-1404J0D01*
G01X484016Y856384D01*
X483338Y855211D01*
X483376Y855120D01*
G02X483482Y854586I-1298J-535D01*
G01Y854584D01*
G02X480674I-1404J0D01*
G02X481896Y855976I1404J0D01*
G01X481994Y855989D01*
X482670Y857160D01*
X482632Y857252D01*
G02X482525Y857789I1297J538D01*
G37*
G36*
G01X489925D02*
G02X492733I1404J0D01*
G02X491514Y856397I-1404J0D01*
G01X491416Y856384D01*
X490738Y855211D01*
X490776Y855120D01*
G02X490882Y854586I-1298J-535D01*
G01Y854584D01*
G02X488074I-1404J0D01*
G02X489296Y855976I1404J0D01*
G01X489394Y855989D01*
X490070Y857160D01*
X490032Y857252D01*
G02X489925Y857789I1297J538D01*
G37*
G36*
G01X497325D02*
G02X500133I1404J0D01*
G02X498914Y856397I-1404J0D01*
G01X498816Y856384D01*
X498138Y855211D01*
X498176Y855120D01*
G02X498282Y854586I-1298J-535D01*
G01Y854584D01*
G02X495474I-1404J0D01*
G02X496696Y855976I1404J0D01*
G01X496794Y855989D01*
X497470Y857160D01*
X497432Y857252D01*
G02X497325Y857789I1297J538D01*
G37*
G36*
G01X504725D02*
G02X507533I1404J0D01*
G02X506314Y856397I-1404J0D01*
G01X506216Y856384D01*
X505538Y855211D01*
X505576Y855120D01*
G02X505682Y854586I-1298J-535D01*
G01Y854584D01*
G02X502874I-1404J0D01*
G02X504096Y855976I1404J0D01*
G01X504194Y855989D01*
X504870Y857160D01*
X504832Y857252D01*
G02X504725Y857789I1297J538D01*
G37*
G36*
G01X512125D02*
G02X514933I1404J0D01*
G02X513714Y856397I-1404J0D01*
G01X513616Y856384D01*
X512938Y855211D01*
X512976Y855120D01*
G02X513082Y854586I-1298J-535D01*
G01Y854584D01*
G02X510274I-1404J0D01*
G02X511496Y855976I1404J0D01*
G01X511594Y855989D01*
X512270Y857160D01*
X512232Y857252D01*
G02X512125Y857789I1297J538D01*
G37*
G36*
G01X519525D02*
G02X522333I1404J0D01*
G02X521114Y856397I-1404J0D01*
G01X521016Y856384D01*
X520338Y855211D01*
X520376Y855120D01*
G02X520482Y854586I-1298J-535D01*
G01Y854584D01*
G02X517674I-1404J0D01*
G02X518896Y855976I1404J0D01*
G01X518994Y855989D01*
X519670Y857160D01*
X519632Y857252D01*
G02X519525Y857789I1297J538D01*
G37*
G36*
G01X526925D02*
G02X529733I1404J0D01*
G02X528514Y856397I-1404J0D01*
G01X528416Y856384D01*
X527738Y855211D01*
X527776Y855120D01*
G02X527882Y854586I-1298J-535D01*
G01Y854584D01*
G02X525074I-1404J0D01*
G02X526296Y855976I1404J0D01*
G01X526394Y855989D01*
X527070Y857160D01*
X527032Y857252D01*
G02X526925Y857789I1297J538D01*
G37*
G36*
G01X1329167D02*
G02X1331975I1404J0D01*
G02X1331868Y857252I-1404J1D01*
G01X1331830Y857160D01*
X1332507Y855989D01*
X1332605Y855976D01*
G02X1333824Y854584I-185J-1392D01*
G02X1331016I-1404J0D01*
G02X1331123Y855121I1404J-1D01*
G01X1331161Y855213D01*
X1330484Y856384D01*
X1330386Y856397D01*
G02X1329167Y857789I185J1392D01*
G37*
G36*
G01X1336567D02*
G02X1339375I1404J0D01*
G02X1339268Y857252I-1404J1D01*
G01X1339230Y857160D01*
X1339907Y855989D01*
X1340005Y855976D01*
G02X1341224Y854584I-185J-1392D01*
G02X1338416I-1404J0D01*
G02X1338523Y855121I1404J-1D01*
G01X1338561Y855213D01*
X1337884Y856384D01*
X1337786Y856397D01*
G02X1336567Y857789I185J1392D01*
G37*
G36*
G01X1343967D02*
G02X1346775I1404J0D01*
G02X1346668Y857252I-1404J1D01*
G01X1346630Y857160D01*
X1347307Y855989D01*
X1347405Y855976D01*
G02X1348624Y854584I-185J-1392D01*
G02X1345816I-1404J0D01*
G02X1345923Y855121I1404J-1D01*
G01X1345961Y855213D01*
X1345284Y856384D01*
X1345186Y856397D01*
G02X1343967Y857789I185J1392D01*
G37*
G36*
G01X1351367D02*
G02X1354175I1404J0D01*
G02X1354068Y857252I-1404J1D01*
G01X1354030Y857160D01*
X1354707Y855989D01*
X1354805Y855976D01*
G02X1356024Y854584I-185J-1392D01*
G02X1353216I-1404J0D01*
G02X1353323Y855121I1404J-1D01*
G01X1353361Y855213D01*
X1352684Y856384D01*
X1352586Y856397D01*
G02X1351367Y857789I185J1392D01*
G37*
G36*
G01X1358767D02*
G02X1361575I1404J0D01*
G02X1361468Y857252I-1404J1D01*
G01X1361430Y857160D01*
X1362107Y855989D01*
X1362205Y855976D01*
G02X1363424Y854584I-185J-1392D01*
G02X1360616I-1404J0D01*
G02X1360723Y855121I1404J-1D01*
G01X1360761Y855213D01*
X1360084Y856384D01*
X1359986Y856397D01*
G02X1358767Y857789I185J1392D01*
G37*
G36*
G01X1366167D02*
G02X1368975I1404J0D01*
G02X1368868Y857252I-1404J1D01*
G01X1368830Y857160D01*
X1369507Y855989D01*
X1369605Y855976D01*
G02X1370824Y854584I-185J-1392D01*
G02X1368016I-1404J0D01*
G02X1368123Y855121I1404J-1D01*
G01X1368161Y855213D01*
X1367484Y856384D01*
X1367386Y856397D01*
G02X1366167Y857789I185J1392D01*
G37*
G36*
G01X1373567D02*
G02X1376375I1404J0D01*
G02X1376268Y857252I-1404J1D01*
G01X1376230Y857160D01*
X1376907Y855989D01*
X1377005Y855976D01*
G02X1378224Y854584I-185J-1392D01*
G02X1375416I-1404J0D01*
G02X1375523Y855121I1404J-1D01*
G01X1375561Y855213D01*
X1374884Y856384D01*
X1374786Y856397D01*
G02X1373567Y857789I185J1392D01*
G37*
G36*
G01X1380967D02*
G02X1383775I1404J0D01*
G02X1383668Y857252I-1404J1D01*
G01X1383630Y857160D01*
X1384307Y855989D01*
X1384405Y855976D01*
G02X1385624Y854584I-185J-1392D01*
G02X1382816I-1404J0D01*
G02X1382923Y855121I1404J-1D01*
G01X1382961Y855213D01*
X1382284Y856384D01*
X1382186Y856397D01*
G02X1380967Y857789I185J1392D01*
G37*
G36*
G01X1388367D02*
G02X1391175I1404J0D01*
G02X1391068Y857252I-1404J1D01*
G01X1391030Y857160D01*
X1391707Y855989D01*
X1391805Y855976D01*
G02X1393024Y854584I-185J-1392D01*
G02X1390216I-1404J0D01*
G02X1390323Y855121I1404J-1D01*
G01X1390361Y855213D01*
X1389684Y856384D01*
X1389586Y856397D01*
G02X1388367Y857789I185J1392D01*
G37*
G36*
G01X1395767D02*
G02X1398575I1404J0D01*
G02X1398468Y857252I-1404J1D01*
G01X1398430Y857160D01*
X1399107Y855989D01*
X1399205Y855976D01*
G02X1400424Y854584I-185J-1392D01*
G02X1397616I-1404J0D01*
G02X1397723Y855121I1404J-1D01*
G01X1397761Y855213D01*
X1397084Y856384D01*
X1396986Y856397D01*
G02X1395767Y857789I185J1392D01*
G37*
G36*
G01X1403167D02*
G02X1405975I1404J0D01*
G02X1405868Y857252I-1404J1D01*
G01X1405830Y857160D01*
X1406507Y855989D01*
X1406605Y855976D01*
G02X1407824Y854584I-185J-1392D01*
G02X1405016I-1404J0D01*
G02X1405123Y855121I1404J-1D01*
G01X1405161Y855213D01*
X1404484Y856384D01*
X1404386Y856397D01*
G02X1403167Y857789I185J1392D01*
G37*
G36*
G01X1410567D02*
G02X1413375I1404J0D01*
G02X1413268Y857252I-1404J1D01*
G01X1413230Y857160D01*
X1413907Y855989D01*
X1414005Y855976D01*
G02X1415225Y854584I-184J-1392D01*
G02X1412417I-1404J0D01*
G01Y854586D01*
G02X1412523Y855120I1404J-1D01*
G01X1412561Y855211D01*
X1411884Y856384D01*
X1411786Y856397D01*
G02X1410567Y857789I185J1392D01*
G37*
G36*
G01X1421667D02*
G02X1424475I1404J0D01*
G02X1423256Y856397I-1404J0D01*
G01X1423158Y856384D01*
X1422480Y855211D01*
X1422518Y855120D01*
G02X1422624Y854586I-1298J-535D01*
G01Y854584D01*
G02X1419816I-1404J0D01*
G02X1421038Y855976I1404J0D01*
G01X1421136Y855989D01*
X1421812Y857160D01*
X1421774Y857252D01*
G02X1421667Y857789I1297J538D01*
G37*
G36*
G01X1429067D02*
G02X1431875I1404J0D01*
G02X1430656Y856397I-1404J0D01*
G01X1430558Y856384D01*
X1429880Y855211D01*
X1429918Y855120D01*
G02X1430024Y854586I-1298J-535D01*
G01Y854584D01*
G02X1427216I-1404J0D01*
G02X1428438Y855976I1404J0D01*
G01X1428536Y855989D01*
X1429212Y857160D01*
X1429174Y857252D01*
G02X1429067Y857789I1297J538D01*
G37*
G36*
G01X1436467D02*
G02X1439275I1404J0D01*
G02X1438056Y856397I-1404J0D01*
G01X1437958Y856384D01*
X1437280Y855211D01*
X1437318Y855120D01*
G02X1437424Y854586I-1298J-535D01*
G01Y854584D01*
G02X1434616I-1404J0D01*
G02X1435838Y855976I1404J0D01*
G01X1435936Y855989D01*
X1436612Y857160D01*
X1436574Y857252D01*
G02X1436467Y857789I1297J538D01*
G37*
G36*
G01X1443867D02*
G02X1446675I1404J0D01*
G02X1445456Y856397I-1404J0D01*
G01X1445358Y856384D01*
X1444680Y855211D01*
X1444718Y855120D01*
G02X1444824Y854586I-1298J-535D01*
G01Y854584D01*
G02X1442016I-1404J0D01*
G02X1443238Y855976I1404J0D01*
G01X1443336Y855989D01*
X1444012Y857160D01*
X1443974Y857252D01*
G02X1443867Y857789I1297J538D01*
G37*
G36*
G01X1451267D02*
G02X1454075I1404J0D01*
G02X1452856Y856397I-1404J0D01*
G01X1452758Y856384D01*
X1452080Y855211D01*
X1452118Y855120D01*
G02X1452224Y854586I-1298J-535D01*
G01Y854584D01*
G02X1449416I-1404J0D01*
G02X1450638Y855976I1404J0D01*
G01X1450736Y855989D01*
X1451412Y857160D01*
X1451374Y857252D01*
G02X1451267Y857789I1297J538D01*
G37*
G36*
G01X1458667D02*
G02X1461475I1404J0D01*
G02X1460256Y856397I-1404J0D01*
G01X1460158Y856384D01*
X1459480Y855211D01*
X1459518Y855120D01*
G02X1459624Y854586I-1298J-535D01*
G01Y854584D01*
G02X1456816I-1404J0D01*
G02X1458038Y855976I1404J0D01*
G01X1458136Y855989D01*
X1458812Y857160D01*
X1458774Y857252D01*
G02X1458667Y857789I1297J538D01*
G37*
G36*
G01X1466067D02*
G02X1468875I1404J0D01*
G02X1467656Y856397I-1404J0D01*
G01X1467558Y856384D01*
X1466880Y855211D01*
X1466918Y855120D01*
G02X1467024Y854586I-1298J-535D01*
G01Y854584D01*
G02X1464216I-1404J0D01*
G02X1465438Y855976I1404J0D01*
G01X1465536Y855989D01*
X1466212Y857160D01*
X1466174Y857252D01*
G02X1466067Y857789I1297J538D01*
G37*
G36*
G01X1473467D02*
G02X1476275I1404J0D01*
G02X1475056Y856397I-1404J0D01*
G01X1474958Y856384D01*
X1474280Y855211D01*
X1474318Y855120D01*
G02X1474424Y854586I-1298J-535D01*
G01Y854584D01*
G02X1471616I-1404J0D01*
G02X1472838Y855976I1404J0D01*
G01X1472936Y855989D01*
X1473612Y857160D01*
X1473574Y857252D01*
G02X1473467Y857789I1297J538D01*
G37*
G36*
G01X1480867D02*
G02X1483675I1404J0D01*
G02X1482456Y856397I-1404J0D01*
G01X1482358Y856384D01*
X1481680Y855211D01*
X1481718Y855120D01*
G02X1481824Y854586I-1298J-535D01*
G01Y854584D01*
G02X1479016I-1404J0D01*
G02X1480238Y855976I1404J0D01*
G01X1480336Y855989D01*
X1481012Y857160D01*
X1480974Y857252D01*
G02X1480867Y857789I1297J538D01*
G37*
G36*
G01X1488267D02*
G02X1491075I1404J0D01*
G02X1489856Y856397I-1404J0D01*
G01X1489758Y856384D01*
X1489080Y855211D01*
X1489118Y855120D01*
G02X1489224Y854586I-1298J-535D01*
G01Y854584D01*
G02X1486416I-1404J0D01*
G02X1487638Y855976I1404J0D01*
G01X1487736Y855989D01*
X1488412Y857160D01*
X1488374Y857252D01*
G02X1488267Y857789I1297J538D01*
G37*
G36*
G01X1495667D02*
G02X1498475I1404J0D01*
G02X1497256Y856397I-1404J0D01*
G01X1497158Y856384D01*
X1496480Y855211D01*
X1496518Y855120D01*
G02X1496624Y854586I-1298J-535D01*
G01Y854584D01*
G02X1493816I-1404J0D01*
G02X1495038Y855976I1404J0D01*
G01X1495136Y855989D01*
X1495812Y857160D01*
X1495774Y857252D01*
G02X1495667Y857789I1297J538D01*
G37*
G36*
G01X1503067D02*
G02X1505875I1404J0D01*
G02X1504656Y856397I-1404J0D01*
G01X1504558Y856384D01*
X1503880Y855211D01*
X1503918Y855120D01*
G02X1504024Y854586I-1298J-535D01*
G01Y854584D01*
G02X1501216I-1404J0D01*
G02X1502438Y855976I1404J0D01*
G01X1502536Y855989D01*
X1503212Y857160D01*
X1503174Y857252D01*
G02X1503067Y857789I1297J538D01*
G37*
G36*
G01X351174Y860993D02*
G02X353982I1404J0D01*
G02X352763Y859601I-1404J0D01*
G01X352665Y859588D01*
X351988Y858418D01*
X352026Y858326D01*
G02X352133Y857789I-1297J-538D01*
G02X349325I-1404J0D01*
G02X350544Y859181I1404J0D01*
G01X350642Y859194D01*
X351319Y860364D01*
X351281Y860456D01*
G02X351174Y860993I1297J538D01*
G37*
G36*
G01X358574D02*
G02X361382I1404J0D01*
G02X360163Y859601I-1404J0D01*
G01X360065Y859588D01*
X359388Y858418D01*
X359426Y858326D01*
G02X359533Y857789I-1297J-538D01*
G02X356725I-1404J0D01*
G02X357944Y859181I1404J0D01*
G01X358042Y859194D01*
X358719Y860364D01*
X358681Y860456D01*
G02X358574Y860993I1297J538D01*
G37*
G36*
G01X365974D02*
G02X368782I1404J0D01*
G02X367563Y859601I-1404J0D01*
G01X367465Y859588D01*
X366788Y858418D01*
X366826Y858326D01*
G02X366933Y857789I-1297J-538D01*
G02X364125I-1404J0D01*
G02X365344Y859181I1404J0D01*
G01X365442Y859194D01*
X366119Y860364D01*
X366081Y860456D01*
G02X365974Y860993I1297J538D01*
G37*
G36*
G01X373374D02*
G02X376182I1404J0D01*
G02X374963Y859601I-1404J0D01*
G01X374865Y859588D01*
X374188Y858418D01*
X374226Y858326D01*
G02X374333Y857789I-1297J-538D01*
G02X371525I-1404J0D01*
G02X372744Y859181I1404J0D01*
G01X372842Y859194D01*
X373519Y860364D01*
X373481Y860456D01*
G02X373374Y860993I1297J538D01*
G37*
G36*
G01X380774D02*
G02X383582I1404J0D01*
G02X382363Y859601I-1404J0D01*
G01X382265Y859588D01*
X381588Y858418D01*
X381626Y858326D01*
G02X381733Y857789I-1297J-538D01*
G02X378925I-1404J0D01*
G02X380144Y859181I1404J0D01*
G01X380242Y859194D01*
X380919Y860364D01*
X380881Y860456D01*
G02X380774Y860993I1297J538D01*
G37*
G36*
G01X388174D02*
G02X390982I1404J0D01*
G02X389763Y859601I-1404J0D01*
G01X389665Y859588D01*
X388988Y858418D01*
X389026Y858326D01*
G02X389133Y857789I-1297J-538D01*
G02X386325I-1404J0D01*
G02X387544Y859181I1404J0D01*
G01X387642Y859194D01*
X388319Y860364D01*
X388281Y860456D01*
G02X388174Y860993I1297J538D01*
G37*
G36*
G01X395574D02*
G02X398382I1404J0D01*
G02X397163Y859601I-1404J0D01*
G01X397065Y859588D01*
X396388Y858418D01*
X396426Y858326D01*
G02X396533Y857789I-1297J-538D01*
G02X393725I-1404J0D01*
G02X394944Y859181I1404J0D01*
G01X395042Y859194D01*
X395719Y860364D01*
X395681Y860456D01*
G02X395574Y860993I1297J538D01*
G37*
G36*
G01X402974D02*
G02X405782I1404J0D01*
G02X404563Y859601I-1404J0D01*
G01X404465Y859588D01*
X403788Y858418D01*
X403826Y858326D01*
G02X403933Y857789I-1297J-538D01*
G02X401125I-1404J0D01*
G02X402344Y859181I1404J0D01*
G01X402442Y859194D01*
X403119Y860364D01*
X403081Y860456D01*
G02X402974Y860993I1297J538D01*
G37*
G36*
G01X410374D02*
G02X413182I1404J0D01*
G02X411963Y859601I-1404J0D01*
G01X411865Y859588D01*
X411188Y858418D01*
X411226Y858326D01*
G02X411333Y857789I-1297J-538D01*
G02X408525I-1404J0D01*
G02X409744Y859181I1404J0D01*
G01X409842Y859194D01*
X410519Y860364D01*
X410481Y860456D01*
G02X410374Y860993I1297J538D01*
G37*
G36*
G01X417774D02*
G02X420582I1404J0D01*
G02X419363Y859601I-1404J0D01*
G01X419265Y859588D01*
X418588Y858418D01*
X418626Y858326D01*
G02X418733Y857789I-1297J-538D01*
G02X415925I-1404J0D01*
G02X417144Y859181I1404J0D01*
G01X417242Y859194D01*
X417919Y860364D01*
X417881Y860456D01*
G02X417774Y860993I1297J538D01*
G37*
G36*
G01X425174D02*
G02X427982I1404J0D01*
G02X426763Y859601I-1404J0D01*
G01X426665Y859588D01*
X425988Y858418D01*
X426026Y858326D01*
G02X426133Y857789I-1297J-538D01*
G02X423325I-1404J0D01*
G02X424544Y859181I1404J0D01*
G01X424642Y859194D01*
X425319Y860364D01*
X425281Y860456D01*
G02X425174Y860993I1297J538D01*
G37*
G36*
G01X432575D02*
G02X435383I1404J0D01*
G02X434164Y859601I-1404J0D01*
G01X434066Y859588D01*
X433389Y858416D01*
X433427Y858325D01*
G02X433533Y857791I-1298J-535D01*
G01Y857789D01*
G02X430725I-1404J0D01*
G02X431945Y859181I1404J0D01*
G01X432043Y859194D01*
X432720Y860364D01*
X432682Y860456D01*
G02X432575Y860993I1297J538D01*
G37*
G36*
G01X439974D02*
G02X442782I1404J0D01*
G01Y860992D01*
G02X442675Y860455I-1404J1D01*
G01X442637Y860364D01*
X443312Y859194D01*
X443410Y859181D01*
G02X444633Y857789I-181J-1392D01*
G02X441825I-1404J0D01*
G01Y857791D01*
G02X441931Y858325I1404J-1D01*
G01X441969Y858416D01*
X441291Y859588D01*
X441193Y859601D01*
G02X439974Y860993I185J1392D01*
G37*
G36*
G01X447375D02*
G02X450183I1404J0D01*
G02X450076Y860456I-1404J1D01*
G01X450038Y860364D01*
X450714Y859194D01*
X450812Y859181D01*
G02X452033Y857789I-183J-1392D01*
G02X449225I-1404J0D01*
G01Y857791D01*
G02X449331Y858325I1404J-1D01*
G01X449369Y858416D01*
X448692Y859588D01*
X448594Y859601D01*
G02X447375Y860993I185J1392D01*
G37*
G36*
G01X454774D02*
G02X457582I1404J0D01*
G01Y860992D01*
G02X457475Y860455I-1404J1D01*
G01X457437Y860364D01*
X458112Y859194D01*
X458210Y859181D01*
G02X459433Y857789I-181J-1392D01*
G02X456625I-1404J0D01*
G01Y857791D01*
G02X456731Y858325I1404J-1D01*
G01X456769Y858416D01*
X456091Y859588D01*
X455993Y859601D01*
G02X454774Y860993I185J1392D01*
G37*
G36*
G01X462174D02*
G02X464982I1404J0D01*
G01Y860992D01*
G02X464875Y860455I-1404J1D01*
G01X464837Y860364D01*
X465512Y859194D01*
X465610Y859181D01*
G02X466833Y857789I-181J-1392D01*
G02X464025I-1404J0D01*
G01Y857791D01*
G02X464131Y858325I1404J-1D01*
G01X464169Y858416D01*
X463491Y859588D01*
X463393Y859601D01*
G02X462174Y860993I185J1392D01*
G37*
G36*
G01X469574D02*
G02X472382I1404J0D01*
G01Y860992D01*
G02X472275Y860455I-1404J1D01*
G01X472237Y860364D01*
X472912Y859194D01*
X473010Y859181D01*
G02X474233Y857789I-181J-1392D01*
G02X471425I-1404J0D01*
G01Y857791D01*
G02X471531Y858325I1404J-1D01*
G01X471569Y858416D01*
X470891Y859588D01*
X470793Y859601D01*
G02X469574Y860993I185J1392D01*
G37*
G36*
G01X476974D02*
G02X479782I1404J0D01*
G01Y860992D01*
G02X479675Y860455I-1404J1D01*
G01X479637Y860364D01*
X480312Y859194D01*
X480410Y859181D01*
G02X481633Y857789I-181J-1392D01*
G02X478825I-1404J0D01*
G01Y857791D01*
G02X478931Y858325I1404J-1D01*
G01X478969Y858416D01*
X478291Y859588D01*
X478193Y859601D01*
G02X476974Y860993I185J1392D01*
G37*
G36*
G01X484374D02*
G02X487182I1404J0D01*
G01Y860992D01*
G02X487075Y860455I-1404J1D01*
G01X487037Y860364D01*
X487712Y859194D01*
X487810Y859181D01*
G02X489033Y857789I-181J-1392D01*
G02X486225I-1404J0D01*
G01Y857791D01*
G02X486331Y858325I1404J-1D01*
G01X486369Y858416D01*
X485691Y859588D01*
X485593Y859601D01*
G02X484374Y860993I185J1392D01*
G37*
G36*
G01X491774D02*
G02X494582I1404J0D01*
G01Y860992D01*
G02X494475Y860455I-1404J1D01*
G01X494437Y860364D01*
X495112Y859194D01*
X495210Y859181D01*
G02X496433Y857789I-181J-1392D01*
G02X493625I-1404J0D01*
G01Y857791D01*
G02X493731Y858325I1404J-1D01*
G01X493769Y858416D01*
X493091Y859588D01*
X492993Y859601D01*
G02X491774Y860993I185J1392D01*
G37*
G36*
G01X499174D02*
G02X501982I1404J0D01*
G01Y860992D01*
G02X501875Y860455I-1404J1D01*
G01X501837Y860364D01*
X502512Y859194D01*
X502610Y859181D01*
G02X503833Y857789I-181J-1392D01*
G02X501025I-1404J0D01*
G01Y857791D01*
G02X501131Y858325I1404J-1D01*
G01X501169Y858416D01*
X500491Y859588D01*
X500393Y859601D01*
G02X499174Y860993I185J1392D01*
G37*
G36*
G01X506574D02*
G02X509382I1404J0D01*
G01Y860992D01*
G02X509275Y860455I-1404J1D01*
G01X509237Y860364D01*
X509912Y859194D01*
X510010Y859181D01*
G02X511233Y857789I-181J-1392D01*
G02X508425I-1404J0D01*
G01Y857791D01*
G02X508531Y858325I1404J-1D01*
G01X508569Y858416D01*
X507891Y859588D01*
X507793Y859601D01*
G02X506574Y860993I185J1392D01*
G37*
G36*
G01X513974D02*
G02X516782I1404J0D01*
G01Y860992D01*
G02X516675Y860455I-1404J1D01*
G01X516637Y860364D01*
X517312Y859194D01*
X517410Y859181D01*
G02X518633Y857789I-181J-1392D01*
G02X515825I-1404J0D01*
G01Y857791D01*
G02X515931Y858325I1404J-1D01*
G01X515969Y858416D01*
X515291Y859588D01*
X515193Y859601D01*
G02X513974Y860993I185J1392D01*
G37*
G36*
G01X521374D02*
G02X524182I1404J0D01*
G01Y860992D01*
G02X524075Y860455I-1404J1D01*
G01X524037Y860364D01*
X524712Y859194D01*
X524810Y859181D01*
G02X526033Y857789I-181J-1392D01*
G02X523225I-1404J0D01*
G01Y857791D01*
G02X523331Y858325I1404J-1D01*
G01X523369Y858416D01*
X522691Y859588D01*
X522593Y859601D01*
G02X521374Y860993I185J1392D01*
G37*
G36*
G01X1327316D02*
G02X1330124I1404J0D01*
G02X1328905Y859601I-1404J0D01*
G01X1328807Y859588D01*
X1328130Y858418D01*
X1328168Y858326D01*
G02X1328275Y857789I-1297J-538D01*
G02X1325467I-1404J0D01*
G02X1326686Y859181I1404J0D01*
G01X1326784Y859194D01*
X1327461Y860364D01*
X1327423Y860456D01*
G02X1327316Y860993I1297J538D01*
G37*
G36*
G01X1334716D02*
G02X1337524I1404J0D01*
G02X1336305Y859601I-1404J0D01*
G01X1336207Y859588D01*
X1335530Y858418D01*
X1335568Y858326D01*
G02X1335675Y857789I-1297J-538D01*
G02X1332867I-1404J0D01*
G02X1334086Y859181I1404J0D01*
G01X1334184Y859194D01*
X1334861Y860364D01*
X1334823Y860456D01*
G02X1334716Y860993I1297J538D01*
G37*
G36*
G01X1342116D02*
G02X1344924I1404J0D01*
G02X1343705Y859601I-1404J0D01*
G01X1343607Y859588D01*
X1342930Y858418D01*
X1342968Y858326D01*
G02X1343075Y857789I-1297J-538D01*
G02X1340267I-1404J0D01*
G02X1341486Y859181I1404J0D01*
G01X1341584Y859194D01*
X1342261Y860364D01*
X1342223Y860456D01*
G02X1342116Y860993I1297J538D01*
G37*
G36*
G01X1349516D02*
G02X1352324I1404J0D01*
G02X1351105Y859601I-1404J0D01*
G01X1351007Y859588D01*
X1350330Y858418D01*
X1350368Y858326D01*
G02X1350475Y857789I-1297J-538D01*
G02X1347667I-1404J0D01*
G02X1348886Y859181I1404J0D01*
G01X1348984Y859194D01*
X1349661Y860364D01*
X1349623Y860456D01*
G02X1349516Y860993I1297J538D01*
G37*
G36*
G01X1356916D02*
G02X1359724I1404J0D01*
G02X1358505Y859601I-1404J0D01*
G01X1358407Y859588D01*
X1357730Y858418D01*
X1357768Y858326D01*
G02X1357875Y857789I-1297J-538D01*
G02X1355067I-1404J0D01*
G02X1356286Y859181I1404J0D01*
G01X1356384Y859194D01*
X1357061Y860364D01*
X1357023Y860456D01*
G02X1356916Y860993I1297J538D01*
G37*
G36*
G01X1364316D02*
G02X1367124I1404J0D01*
G02X1365905Y859601I-1404J0D01*
G01X1365807Y859588D01*
X1365130Y858418D01*
X1365168Y858326D01*
G02X1365275Y857789I-1297J-538D01*
G02X1362467I-1404J0D01*
G02X1363686Y859181I1404J0D01*
G01X1363784Y859194D01*
X1364461Y860364D01*
X1364423Y860456D01*
G02X1364316Y860993I1297J538D01*
G37*
G36*
G01X1371716D02*
G02X1374524I1404J0D01*
G02X1373305Y859601I-1404J0D01*
G01X1373207Y859588D01*
X1372530Y858418D01*
X1372568Y858326D01*
G02X1372675Y857789I-1297J-538D01*
G02X1369867I-1404J0D01*
G02X1371086Y859181I1404J0D01*
G01X1371184Y859194D01*
X1371861Y860364D01*
X1371823Y860456D01*
G02X1371716Y860993I1297J538D01*
G37*
G36*
G01X1379116D02*
G02X1381924I1404J0D01*
G02X1380705Y859601I-1404J0D01*
G01X1380607Y859588D01*
X1379930Y858418D01*
X1379968Y858326D01*
G02X1380075Y857789I-1297J-538D01*
G02X1377267I-1404J0D01*
G02X1378486Y859181I1404J0D01*
G01X1378584Y859194D01*
X1379261Y860364D01*
X1379223Y860456D01*
G02X1379116Y860993I1297J538D01*
G37*
G36*
G01X1386516D02*
G02X1389324I1404J0D01*
G02X1388105Y859601I-1404J0D01*
G01X1388007Y859588D01*
X1387330Y858418D01*
X1387368Y858326D01*
G02X1387475Y857789I-1297J-538D01*
G02X1384667I-1404J0D01*
G02X1385886Y859181I1404J0D01*
G01X1385984Y859194D01*
X1386661Y860364D01*
X1386623Y860456D01*
G02X1386516Y860993I1297J538D01*
G37*
G36*
G01X1393916D02*
G02X1396724I1404J0D01*
G02X1395505Y859601I-1404J0D01*
G01X1395407Y859588D01*
X1394730Y858418D01*
X1394768Y858326D01*
G02X1394875Y857789I-1297J-538D01*
G02X1392067I-1404J0D01*
G02X1393286Y859181I1404J0D01*
G01X1393384Y859194D01*
X1394061Y860364D01*
X1394023Y860456D01*
G02X1393916Y860993I1297J538D01*
G37*
G36*
G01X1401316D02*
G02X1404124I1404J0D01*
G02X1402905Y859601I-1404J0D01*
G01X1402807Y859588D01*
X1402130Y858418D01*
X1402168Y858326D01*
G02X1402275Y857789I-1297J-538D01*
G02X1399467I-1404J0D01*
G02X1400686Y859181I1404J0D01*
G01X1400784Y859194D01*
X1401461Y860364D01*
X1401423Y860456D01*
G02X1401316Y860993I1297J538D01*
G37*
G36*
G01X1408717D02*
G02X1411525I1404J0D01*
G02X1410306Y859601I-1404J0D01*
G01X1410208Y859588D01*
X1409531Y858416D01*
X1409569Y858325D01*
G02X1409675Y857791I-1298J-535D01*
G01Y857789D01*
G02X1406867I-1404J0D01*
G02X1408087Y859181I1404J0D01*
G01X1408185Y859194D01*
X1408862Y860364D01*
X1408824Y860456D01*
G02X1408717Y860993I1297J538D01*
G37*
G36*
G01X1416116D02*
G02X1418924I1404J0D01*
G01Y860992D01*
G02X1418817Y860455I-1404J1D01*
G01X1418779Y860364D01*
X1419454Y859194D01*
X1419552Y859181D01*
G02X1420775Y857789I-181J-1392D01*
G02X1417967I-1404J0D01*
G01Y857791D01*
G02X1418073Y858325I1404J-1D01*
G01X1418111Y858416D01*
X1417433Y859588D01*
X1417335Y859601D01*
G02X1416116Y860993I185J1392D01*
G37*
G36*
G01X1423517D02*
G02X1426325I1404J0D01*
G02X1426218Y860456I-1404J1D01*
G01X1426180Y860364D01*
X1426856Y859194D01*
X1426954Y859181D01*
G02X1428175Y857789I-183J-1392D01*
G02X1425367I-1404J0D01*
G01Y857791D01*
G02X1425473Y858325I1404J-1D01*
G01X1425511Y858416D01*
X1424834Y859588D01*
X1424736Y859601D01*
G02X1423517Y860993I185J1392D01*
G37*
G36*
G01X1430916D02*
G02X1433724I1404J0D01*
G01Y860992D01*
G02X1433617Y860455I-1404J1D01*
G01X1433579Y860364D01*
X1434254Y859194D01*
X1434352Y859181D01*
G02X1435575Y857789I-181J-1392D01*
G02X1432767I-1404J0D01*
G01Y857791D01*
G02X1432873Y858325I1404J-1D01*
G01X1432911Y858416D01*
X1432233Y859588D01*
X1432135Y859601D01*
G02X1430916Y860993I185J1392D01*
G37*
G36*
G01X1438316D02*
G02X1441124I1404J0D01*
G01Y860992D01*
G02X1441017Y860455I-1404J1D01*
G01X1440979Y860364D01*
X1441654Y859194D01*
X1441752Y859181D01*
G02X1442975Y857789I-181J-1392D01*
G02X1440167I-1404J0D01*
G01Y857791D01*
G02X1440273Y858325I1404J-1D01*
G01X1440311Y858416D01*
X1439633Y859588D01*
X1439535Y859601D01*
G02X1438316Y860993I185J1392D01*
G37*
G36*
G01X1445716D02*
G02X1448524I1404J0D01*
G01Y860992D01*
G02X1448417Y860455I-1404J1D01*
G01X1448379Y860364D01*
X1449054Y859194D01*
X1449152Y859181D01*
G02X1450375Y857789I-181J-1392D01*
G02X1447567I-1404J0D01*
G01Y857791D01*
G02X1447673Y858325I1404J-1D01*
G01X1447711Y858416D01*
X1447033Y859588D01*
X1446935Y859601D01*
G02X1445716Y860993I185J1392D01*
G37*
G36*
G01X1453116D02*
G02X1455924I1404J0D01*
G01Y860992D01*
G02X1455817Y860455I-1404J1D01*
G01X1455779Y860364D01*
X1456454Y859194D01*
X1456552Y859181D01*
G02X1457775Y857789I-181J-1392D01*
G02X1454967I-1404J0D01*
G01Y857791D01*
G02X1455073Y858325I1404J-1D01*
G01X1455111Y858416D01*
X1454433Y859588D01*
X1454335Y859601D01*
G02X1453116Y860993I185J1392D01*
G37*
G36*
G01X1460516D02*
G02X1463324I1404J0D01*
G01Y860992D01*
G02X1463217Y860455I-1404J1D01*
G01X1463179Y860364D01*
X1463854Y859194D01*
X1463952Y859181D01*
G02X1465175Y857789I-181J-1392D01*
G02X1462367I-1404J0D01*
G01Y857791D01*
G02X1462473Y858325I1404J-1D01*
G01X1462511Y858416D01*
X1461833Y859588D01*
X1461735Y859601D01*
G02X1460516Y860993I185J1392D01*
G37*
G36*
G01X1467916D02*
G02X1470724I1404J0D01*
G01Y860992D01*
G02X1470617Y860455I-1404J1D01*
G01X1470579Y860364D01*
X1471254Y859194D01*
X1471352Y859181D01*
G02X1472575Y857789I-181J-1392D01*
G02X1469767I-1404J0D01*
G01Y857791D01*
G02X1469873Y858325I1404J-1D01*
G01X1469911Y858416D01*
X1469233Y859588D01*
X1469135Y859601D01*
G02X1467916Y860993I185J1392D01*
G37*
G36*
G01X1475316D02*
G02X1478124I1404J0D01*
G01Y860992D01*
G02X1478017Y860455I-1404J1D01*
G01X1477979Y860364D01*
X1478654Y859194D01*
X1478752Y859181D01*
G02X1479975Y857789I-181J-1392D01*
G02X1477167I-1404J0D01*
G01Y857791D01*
G02X1477273Y858325I1404J-1D01*
G01X1477311Y858416D01*
X1476633Y859588D01*
X1476535Y859601D01*
G02X1475316Y860993I185J1392D01*
G37*
G36*
G01X1482716D02*
G02X1485524I1404J0D01*
G01Y860992D01*
G02X1485417Y860455I-1404J1D01*
G01X1485379Y860364D01*
X1486054Y859194D01*
X1486152Y859181D01*
G02X1487375Y857789I-181J-1392D01*
G02X1484567I-1404J0D01*
G01Y857791D01*
G02X1484673Y858325I1404J-1D01*
G01X1484711Y858416D01*
X1484033Y859588D01*
X1483935Y859601D01*
G02X1482716Y860993I185J1392D01*
G37*
G36*
G01X1490116D02*
G02X1492924I1404J0D01*
G01Y860992D01*
G02X1492817Y860455I-1404J1D01*
G01X1492779Y860364D01*
X1493454Y859194D01*
X1493552Y859181D01*
G02X1494775Y857789I-181J-1392D01*
G02X1491967I-1404J0D01*
G01Y857791D01*
G02X1492073Y858325I1404J-1D01*
G01X1492111Y858416D01*
X1491433Y859588D01*
X1491335Y859601D01*
G02X1490116Y860993I185J1392D01*
G37*
G36*
G01X1497516D02*
G02X1500324I1404J0D01*
G01Y860992D01*
G02X1500217Y860455I-1404J1D01*
G01X1500179Y860364D01*
X1500854Y859194D01*
X1500952Y859181D01*
G02X1502175Y857789I-181J-1392D01*
G02X1499367I-1404J0D01*
G01Y857791D01*
G02X1499473Y858325I1404J-1D01*
G01X1499511Y858416D01*
X1498833Y859588D01*
X1498735Y859601D01*
G02X1497516Y860993I185J1392D01*
G37*
G36*
G01X429307Y1079791D02*
G02X432115I1404J0D01*
G02X430896Y1078399I-1404J0D01*
G01X430798Y1078386D01*
X430121Y1077214D01*
X430159Y1077123D01*
G02X430265Y1076589I-1298J-535D01*
G01Y1076587D01*
G02X427457I-1404J0D01*
G02X428677Y1077979I1404J0D01*
G01X428775Y1077992D01*
X429452Y1079162D01*
X429414Y1079254D01*
G02X429307Y1079791I1297J538D01*
G37*
G36*
G01X1405449D02*
G02X1408257I1404J0D01*
G02X1407038Y1078399I-1404J0D01*
G01X1406940Y1078386D01*
X1406263Y1077214D01*
X1406301Y1077123D01*
G02X1406407Y1076589I-1298J-535D01*
G01Y1076587D01*
G02X1403599I-1404J0D01*
G02X1404819Y1077979I1404J0D01*
G01X1404917Y1077992D01*
X1405594Y1079162D01*
X1405556Y1079254D01*
G02X1405449Y1079791I1297J538D01*
G37*
G36*
G01X408958Y1082995D02*
G02X411766I1404J0D01*
G02X410547Y1081603I-1404J0D01*
G01X410449Y1081590D01*
X409771Y1080418D01*
X409809Y1080327D01*
G02X409915Y1079793I-1298J-535D01*
G01Y1079791D01*
G02X407107I-1404J0D01*
G02X408329Y1081183I1404J0D01*
G01X408427Y1081196D01*
X409103Y1082366D01*
X409065Y1082458D01*
G02X408958Y1082995I1297J538D01*
G37*
G36*
G01X1385100D02*
G02X1387908I1404J0D01*
G02X1386689Y1081603I-1404J0D01*
G01X1386591Y1081590D01*
X1385913Y1080418D01*
X1385951Y1080327D01*
G02X1386057Y1079793I-1298J-535D01*
G01Y1079791D01*
G02X1383249I-1404J0D01*
G02X1384471Y1081183I1404J0D01*
G01X1384569Y1081196D01*
X1385245Y1082366D01*
X1385207Y1082458D01*
G02X1385100Y1082995I1297J538D01*
G37*
G36*
G01X410807Y1086200D02*
G02X413615I1404J0D01*
G02X413508Y1085663I-1404J1D01*
G01X413470Y1085571D01*
X414146Y1084400D01*
X414244Y1084387D01*
G02X415466Y1082995I-182J-1392D01*
G02X412658I-1404J0D01*
G01Y1082997D01*
G02X412764Y1083531I1404J-1D01*
G01X412802Y1083622D01*
X412124Y1084795D01*
X412026Y1084808D01*
G02X410807Y1086200I185J1392D01*
G37*
G36*
G01X425608D02*
G02X428416I1404J0D01*
G02X427196Y1084808I-1404J0D01*
G01X427099Y1084795D01*
X426421Y1083624D01*
X426459Y1083532D01*
G02X426566Y1082995I-1297J-538D01*
G02X423758I-1404J0D01*
G02X424978Y1084387I1404J0D01*
G01X425075Y1084400D01*
X425753Y1085571D01*
X425715Y1085663D01*
G02X425608Y1086200I1297J538D01*
G37*
G36*
G01X1386949D02*
G02X1389757I1404J0D01*
G02X1389650Y1085663I-1404J1D01*
G01X1389612Y1085571D01*
X1390288Y1084400D01*
X1390386Y1084387D01*
G02X1391608Y1082995I-182J-1392D01*
G02X1388800I-1404J0D01*
G01Y1082997D01*
G02X1388906Y1083531I1404J-1D01*
G01X1388944Y1083622D01*
X1388266Y1084795D01*
X1388168Y1084808D01*
G02X1386949Y1086200I185J1392D01*
G37*
G36*
G01X1401750D02*
G02X1404558I1404J0D01*
G02X1403338Y1084808I-1404J0D01*
G01X1403241Y1084795D01*
X1402563Y1083624D01*
X1402601Y1083532D01*
G02X1402708Y1082995I-1297J-538D01*
G02X1399900I-1404J0D01*
G02X1401120Y1084387I1404J0D01*
G01X1401217Y1084400D01*
X1401895Y1085571D01*
X1401857Y1085663D01*
G02X1401750Y1086200I1297J538D01*
G37*
G36*
G01X401557Y1089404D02*
G02X404365I1404J0D01*
G02X404258Y1088867I-1404J1D01*
G01X404220Y1088775D01*
X404897Y1087605D01*
X404995Y1087592D01*
G02X406215Y1086200I-184J-1392D01*
G02X403407I-1404J0D01*
G01Y1086202D01*
G02X403513Y1086736I1404J-1D01*
G01X403551Y1086827D01*
X402874Y1087999D01*
X402776Y1088012D01*
G02X401557Y1089404I185J1392D01*
G37*
G36*
G01X427457D02*
G02X430265I1404J0D01*
G02X430158Y1088867I-1404J1D01*
G01X430120Y1088775D01*
X430797Y1087605D01*
X430895Y1087592D01*
G02X432114Y1086200I-185J-1392D01*
G02X429306I-1404J0D01*
G02X429413Y1086737I1404J-1D01*
G01X429451Y1086829D01*
X428774Y1087999D01*
X428676Y1088012D01*
G02X427457Y1089404I185J1392D01*
G37*
G36*
G01X1377699D02*
G02X1380507I1404J0D01*
G02X1380400Y1088867I-1404J1D01*
G01X1380362Y1088775D01*
X1381039Y1087605D01*
X1381137Y1087592D01*
G02X1382357Y1086200I-184J-1392D01*
G02X1379549I-1404J0D01*
G01Y1086202D01*
G02X1379655Y1086736I1404J-1D01*
G01X1379693Y1086827D01*
X1379016Y1087999D01*
X1378918Y1088012D01*
G02X1377699Y1089404I185J1392D01*
G37*
G36*
G01X1403599D02*
G02X1406407I1404J0D01*
G02X1406300Y1088867I-1404J1D01*
G01X1406262Y1088775D01*
X1406939Y1087605D01*
X1407037Y1087592D01*
G02X1408256Y1086200I-185J-1392D01*
G02X1405448I-1404J0D01*
G02X1405555Y1086737I1404J-1D01*
G01X1405593Y1086829D01*
X1404916Y1087999D01*
X1404818Y1088012D01*
G02X1403599Y1089404I185J1392D01*
G37*
G36*
G01X407107Y1092608D02*
G02X409915I1404J0D01*
G02X408696Y1091216I-1404J0D01*
G01X408598Y1091203D01*
X407921Y1090033D01*
X407959Y1089941D01*
G02X408066Y1089404I-1297J-538D01*
G02X405258I-1404J0D01*
G02X406477Y1090796I1404J0D01*
G01X406575Y1090809D01*
X407252Y1091979D01*
X407214Y1092071D01*
G02X407107Y1092608I1297J538D01*
G37*
G36*
G01X418207D02*
G02X421015I1404J0D01*
G02X420908Y1092071I-1404J1D01*
G01X420870Y1091979D01*
X421546Y1090809D01*
X421644Y1090796D01*
G02X422866Y1089404I-182J-1392D01*
G02X420058I-1404J0D01*
G01Y1089406D01*
G02X420164Y1089940I1404J-1D01*
G01X420202Y1090031D01*
X419524Y1091203D01*
X419426Y1091216D01*
G02X418207Y1092608I185J1392D01*
G37*
G36*
G01X1383249D02*
G02X1386057I1404J0D01*
G02X1384838Y1091216I-1404J0D01*
G01X1384740Y1091203D01*
X1384063Y1090033D01*
X1384101Y1089941D01*
G02X1384208Y1089404I-1297J-538D01*
G02X1381400I-1404J0D01*
G02X1382619Y1090796I1404J0D01*
G01X1382717Y1090809D01*
X1383394Y1091979D01*
X1383356Y1092071D01*
G02X1383249Y1092608I1297J538D01*
G37*
G36*
G01X1394349D02*
G02X1397157I1404J0D01*
G02X1397050Y1092071I-1404J1D01*
G01X1397012Y1091979D01*
X1397688Y1090809D01*
X1397786Y1090796D01*
G02X1399008Y1089404I-182J-1392D01*
G02X1396200I-1404J0D01*
G01Y1089406D01*
G02X1396306Y1089940I1404J-1D01*
G01X1396344Y1090031D01*
X1395666Y1091203D01*
X1395568Y1091216D01*
G02X1394349Y1092608I185J1392D01*
G37*
G36*
G01X423758Y1095813D02*
G02X426566I1404J0D01*
G02X425347Y1094421I-1404J0D01*
G01X425249Y1094408D01*
X424571Y1093235D01*
X424609Y1093144D01*
G02X424715Y1092610I-1298J-535D01*
G01Y1092608D01*
G02X421907I-1404J0D01*
G02X423129Y1094000I1404J0D01*
G01X423227Y1094013D01*
X423903Y1095184D01*
X423865Y1095276D01*
G02X423758Y1095813I1297J538D01*
G37*
G36*
G01X1399900D02*
G02X1402708I1404J0D01*
G02X1401489Y1094421I-1404J0D01*
G01X1401391Y1094408D01*
X1400713Y1093235D01*
X1400751Y1093144D01*
G02X1400857Y1092610I-1298J-535D01*
G01Y1092608D01*
G02X1398049I-1404J0D01*
G02X1399271Y1094000I1404J0D01*
G01X1399369Y1094013D01*
X1400045Y1095184D01*
X1400007Y1095276D01*
G02X1399900Y1095813I1297J538D01*
G37*
G36*
G01X401558Y1102221D02*
G02X404366I1404J0D01*
G02X403147Y1100829I-1404J0D01*
G01X403049Y1100816D01*
X402371Y1099644D01*
X402409Y1099553D01*
G02X402515Y1099019I-1298J-535D01*
G01Y1099017D01*
G02X399707I-1404J0D01*
G02X400929Y1100409I1404J0D01*
G01X401027Y1100422D01*
X401703Y1101592D01*
X401665Y1101684D01*
G02X401558Y1102221I1297J538D01*
G37*
G36*
G01X1377700D02*
G02X1380508I1404J0D01*
G02X1379289Y1100829I-1404J0D01*
G01X1379191Y1100816D01*
X1378513Y1099644D01*
X1378551Y1099553D01*
G02X1378657Y1099019I-1298J-535D01*
G01Y1099017D01*
G02X1375849I-1404J0D01*
G02X1377071Y1100409I1404J0D01*
G01X1377169Y1100422D01*
X1377845Y1101592D01*
X1377807Y1101684D01*
G02X1377700Y1102221I1297J538D01*
G37*
G36*
G01X410807Y1105426D02*
G02X413615I1404J0D01*
G02X413508Y1104889I-1404J1D01*
G01X413470Y1104797D01*
X414146Y1103626D01*
X414244Y1103613D01*
G02X415466Y1102221I-182J-1392D01*
G02X412658I-1404J0D01*
G01Y1102223D01*
G02X412764Y1102757I1404J-1D01*
G01X412802Y1102848D01*
X412124Y1104021D01*
X412026Y1104034D01*
G02X410807Y1105426I185J1392D01*
G37*
G36*
G01X1386949D02*
G02X1389757I1404J0D01*
G02X1389650Y1104889I-1404J1D01*
G01X1389612Y1104797D01*
X1390288Y1103626D01*
X1390386Y1103613D01*
G02X1391608Y1102221I-182J-1392D01*
G02X1388800I-1404J0D01*
G01Y1102223D01*
G02X1388906Y1102757I1404J-1D01*
G01X1388944Y1102848D01*
X1388266Y1104021D01*
X1388168Y1104034D01*
G02X1386949Y1105426I185J1392D01*
G37*
G36*
G01X383058Y1108630D02*
G02X385866I1404J0D01*
G02X385759Y1108093I-1404J1D01*
G01X385721Y1108001D01*
X386398Y1106831D01*
X386496Y1106818D01*
G02X387715Y1105426I-185J-1392D01*
G02X384907I-1404J0D01*
G02X385014Y1105963I1404J-1D01*
G01X385052Y1106055D01*
X384375Y1107225D01*
X384277Y1107238D01*
G02X383058Y1108630I185J1392D01*
G37*
G36*
G01X397858D02*
G02X400666I1404J0D01*
G02X399447Y1107238I-1404J0D01*
G01X399349Y1107225D01*
X398671Y1106053D01*
X398709Y1105962D01*
G02X398815Y1105428I-1298J-535D01*
G01Y1105426D01*
G02X396007I-1404J0D01*
G02X397229Y1106818I1404J0D01*
G01X397327Y1106831D01*
X398003Y1108001D01*
X397965Y1108093D01*
G02X397858Y1108630I1297J538D01*
G37*
G36*
G01X408958D02*
G02X411766I1404J0D01*
G02X410547Y1107238I-1404J0D01*
G01X410449Y1107225D01*
X409771Y1106053D01*
X409809Y1105962D01*
G02X409915Y1105428I-1298J-535D01*
G01Y1105426D01*
G02X407107I-1404J0D01*
G02X408329Y1106818I1404J0D01*
G01X408427Y1106831D01*
X409103Y1108001D01*
X409065Y1108093D01*
G02X408958Y1108630I1297J538D01*
G37*
G36*
G01X1359200D02*
G02X1362008I1404J0D01*
G02X1361901Y1108093I-1404J1D01*
G01X1361863Y1108001D01*
X1362540Y1106831D01*
X1362638Y1106818D01*
G02X1363857Y1105426I-185J-1392D01*
G02X1361049I-1404J0D01*
G02X1361156Y1105963I1404J-1D01*
G01X1361194Y1106055D01*
X1360517Y1107225D01*
X1360419Y1107238D01*
G02X1359200Y1108630I185J1392D01*
G37*
G36*
G01X1374000D02*
G02X1376808I1404J0D01*
G02X1375589Y1107238I-1404J0D01*
G01X1375491Y1107225D01*
X1374813Y1106053D01*
X1374851Y1105962D01*
G02X1374957Y1105428I-1298J-535D01*
G01Y1105426D01*
G02X1372149I-1404J0D01*
G02X1373371Y1106818I1404J0D01*
G01X1373469Y1106831D01*
X1374145Y1108001D01*
X1374107Y1108093D01*
G02X1374000Y1108630I1297J538D01*
G37*
G36*
G01X1385100D02*
G02X1387908I1404J0D01*
G02X1386689Y1107238I-1404J0D01*
G01X1386591Y1107225D01*
X1385913Y1106053D01*
X1385951Y1105962D01*
G02X1386057Y1105428I-1298J-535D01*
G01Y1105426D01*
G02X1383249I-1404J0D01*
G02X1384471Y1106818I1404J0D01*
G01X1384569Y1106831D01*
X1385245Y1108001D01*
X1385207Y1108093D01*
G02X1385100Y1108630I1297J538D01*
G37*
G36*
G01X340508Y1111834D02*
G02X343316I1404J0D01*
G01Y1111832D01*
G02X343210Y1111298I-1404J1D01*
G01X343172Y1111207D01*
X343849Y1110035D01*
X343947Y1110022D01*
G02X345166Y1108630I-185J-1392D01*
G02X342358I-1404J0D01*
G01Y1108632D01*
G02X342464Y1109166I1404J-1D01*
G01X342502Y1109257D01*
X341825Y1110429D01*
X341727Y1110442D01*
G02X340508Y1111834I185J1392D01*
G37*
G36*
G01X366408D02*
G02X369216I1404J0D01*
G02X369109Y1111297I-1404J1D01*
G01X369071Y1111205D01*
X369748Y1110035D01*
X369846Y1110022D01*
G02X371065Y1108630I-185J-1392D01*
G02X368257I-1404J0D01*
G02X368364Y1109167I1404J-1D01*
G01X368402Y1109259D01*
X367725Y1110429D01*
X367627Y1110442D01*
G02X366408Y1111834I185J1392D01*
G37*
G36*
G01X373807D02*
G02X376615I1404J0D01*
G02X376508Y1111297I-1404J1D01*
G01X376470Y1111205D01*
X377146Y1110035D01*
X377244Y1110022D01*
G02X378466Y1108630I-182J-1392D01*
G02X375658I-1404J0D01*
G01Y1108632D01*
G02X375764Y1109166I1404J-1D01*
G01X375802Y1109257D01*
X375124Y1110429D01*
X375026Y1110442D01*
G02X373807Y1111834I185J1392D01*
G37*
G36*
G01X399707D02*
G02X402515I1404J0D01*
G02X402408Y1111297I-1404J1D01*
G01X402370Y1111205D01*
X403046Y1110035D01*
X403144Y1110022D01*
G02X404366Y1108630I-182J-1392D01*
G02X401558I-1404J0D01*
G01Y1108632D01*
G02X401664Y1109166I1404J-1D01*
G01X401702Y1109257D01*
X401024Y1110429D01*
X400926Y1110442D01*
G02X399707Y1111834I185J1392D01*
G37*
G36*
G01X418207D02*
G02X421015I1404J0D01*
G02X419796Y1110442I-1404J0D01*
G01X419698Y1110429D01*
X419021Y1109259D01*
X419059Y1109167D01*
G02X419166Y1108630I-1297J-538D01*
G02X416358I-1404J0D01*
G02X417577Y1110022I1404J0D01*
G01X417675Y1110035D01*
X418352Y1111205D01*
X418314Y1111297D01*
G02X418207Y1111834I1297J538D01*
G37*
G36*
G01X1316650D02*
G02X1319458I1404J0D01*
G01Y1111832D01*
G02X1319352Y1111298I-1404J1D01*
G01X1319314Y1111207D01*
X1319991Y1110035D01*
X1320089Y1110022D01*
G02X1321308Y1108630I-185J-1392D01*
G02X1318500I-1404J0D01*
G01Y1108632D01*
G02X1318606Y1109166I1404J-1D01*
G01X1318644Y1109257D01*
X1317967Y1110429D01*
X1317869Y1110442D01*
G02X1316650Y1111834I185J1392D01*
G37*
G36*
G01X1342550D02*
G02X1345358I1404J0D01*
G02X1345251Y1111297I-1404J1D01*
G01X1345213Y1111205D01*
X1345890Y1110035D01*
X1345988Y1110022D01*
G02X1347207Y1108630I-185J-1392D01*
G02X1344399I-1404J0D01*
G02X1344506Y1109167I1404J-1D01*
G01X1344544Y1109259D01*
X1343867Y1110429D01*
X1343769Y1110442D01*
G02X1342550Y1111834I185J1392D01*
G37*
G36*
G01X1349949D02*
G02X1352757I1404J0D01*
G02X1352650Y1111297I-1404J1D01*
G01X1352612Y1111205D01*
X1353288Y1110035D01*
X1353386Y1110022D01*
G02X1354608Y1108630I-182J-1392D01*
G02X1351800I-1404J0D01*
G01Y1108632D01*
G02X1351906Y1109166I1404J-1D01*
G01X1351944Y1109257D01*
X1351266Y1110429D01*
X1351168Y1110442D01*
G02X1349949Y1111834I185J1392D01*
G37*
G36*
G01X1375849D02*
G02X1378657I1404J0D01*
G02X1378550Y1111297I-1404J1D01*
G01X1378512Y1111205D01*
X1379188Y1110035D01*
X1379286Y1110022D01*
G02X1380508Y1108630I-182J-1392D01*
G02X1377700I-1404J0D01*
G01Y1108632D01*
G02X1377806Y1109166I1404J-1D01*
G01X1377844Y1109257D01*
X1377166Y1110429D01*
X1377068Y1110442D01*
G02X1375849Y1111834I185J1392D01*
G37*
G36*
G01X1394349D02*
G02X1397157I1404J0D01*
G02X1395938Y1110442I-1404J0D01*
G01X1395840Y1110429D01*
X1395163Y1109259D01*
X1395201Y1109167D01*
G02X1395308Y1108630I-1297J-538D01*
G02X1392500I-1404J0D01*
G02X1393719Y1110022I1404J0D01*
G01X1393817Y1110035D01*
X1394494Y1111205D01*
X1394456Y1111297D01*
G02X1394349Y1111834I1297J538D01*
G37*
G36*
G01X346057Y1115039D02*
G02X348865I1404J0D01*
G02X347645Y1113647I-1404J0D01*
G01X347548Y1113634D01*
X346870Y1112463D01*
X346908Y1112371D01*
G02X347015Y1111834I-1297J-538D01*
G02X344207I-1404J0D01*
G02X345427Y1113226I1404J0D01*
G01X345524Y1113239D01*
X346202Y1114410D01*
X346164Y1114502D01*
G02X346057Y1115039I1297J538D01*
G37*
G36*
G01X357157D02*
G02X359965I1404J0D01*
G01Y1115038D01*
G02X359859Y1114502I-1404J-1D01*
G01X359821Y1114411D01*
X360498Y1113239D01*
X360596Y1113226D01*
G02X361816Y1111834I-184J-1392D01*
G02X359008I-1404J0D01*
G01Y1111836D01*
G02X359114Y1112370I1404J-1D01*
G01X359152Y1112461D01*
X358474Y1113634D01*
X358376Y1113647D01*
G02X357157Y1115039I185J1392D01*
G37*
G36*
G01X379358D02*
G02X382166I1404J0D01*
G02X380947Y1113647I-1404J0D01*
G01X380849Y1113634D01*
X380171Y1112461D01*
X380209Y1112370D01*
G02X380315Y1111836I-1298J-535D01*
G01Y1111834D01*
G02X377507I-1404J0D01*
G02X378729Y1113226I1404J0D01*
G01X378827Y1113239D01*
X379503Y1114410D01*
X379465Y1114502D01*
G02X379358Y1115039I1297J538D01*
G37*
G36*
G01X1322199D02*
G02X1325007I1404J0D01*
G02X1323787Y1113647I-1404J0D01*
G01X1323690Y1113634D01*
X1323012Y1112463D01*
X1323050Y1112371D01*
G02X1323157Y1111834I-1297J-538D01*
G02X1320349I-1404J0D01*
G02X1321569Y1113226I1404J0D01*
G01X1321666Y1113239D01*
X1322344Y1114410D01*
X1322306Y1114502D01*
G02X1322199Y1115039I1297J538D01*
G37*
G36*
G01X1333299D02*
G02X1336107I1404J0D01*
G01Y1115038D01*
G02X1336001Y1114502I-1404J-1D01*
G01X1335963Y1114411D01*
X1336640Y1113239D01*
X1336738Y1113226D01*
G02X1337958Y1111834I-184J-1392D01*
G02X1335150I-1404J0D01*
G01Y1111836D01*
G02X1335256Y1112370I1404J-1D01*
G01X1335294Y1112461D01*
X1334616Y1113634D01*
X1334518Y1113647D01*
G02X1333299Y1115039I185J1392D01*
G37*
G36*
G01X1355500D02*
G02X1358308I1404J0D01*
G02X1357089Y1113647I-1404J0D01*
G01X1356991Y1113634D01*
X1356313Y1112461D01*
X1356351Y1112370D01*
G02X1356457Y1111836I-1298J-535D01*
G01Y1111834D01*
G02X1353649I-1404J0D01*
G02X1354871Y1113226I1404J0D01*
G01X1354969Y1113239D01*
X1355645Y1114410D01*
X1355607Y1114502D01*
G02X1355500Y1115039I1297J538D01*
G37*
G36*
G01X342357Y1121447D02*
G02X345165I1404J0D01*
G02X343946Y1120055I-1404J0D01*
G01X343848Y1120042D01*
X343171Y1118872D01*
X343209Y1118780D01*
G02X343316Y1118243I-1297J-538D01*
G02X340508I-1404J0D01*
G02X341727Y1119635I1404J0D01*
G01X341825Y1119648D01*
X342502Y1120818D01*
X342464Y1120910D01*
G02X342357Y1121447I1297J538D01*
G37*
G36*
G01X1318499D02*
G02X1321307I1404J0D01*
G02X1320088Y1120055I-1404J0D01*
G01X1319990Y1120042D01*
X1319313Y1118872D01*
X1319351Y1118780D01*
G02X1319458Y1118243I-1297J-538D01*
G02X1316650I-1404J0D01*
G02X1317869Y1119635I1404J0D01*
G01X1317967Y1119648D01*
X1318644Y1120818D01*
X1318606Y1120910D01*
G02X1318499Y1121447I1297J538D01*
G37*
G36*
G01X344207Y1124651D02*
G02X347015I1404J0D01*
G01Y1124649D01*
G02X346909Y1124115I-1404J1D01*
G01X346871Y1124024D01*
X347548Y1122852D01*
X347646Y1122839D01*
G02X348865Y1121447I-185J-1392D01*
G02X346057I-1404J0D01*
G01Y1121449D01*
G02X346163Y1121983I1404J-1D01*
G01X346201Y1122074D01*
X345524Y1123246D01*
X345426Y1123259D01*
G02X344207Y1124651I185J1392D01*
G37*
G36*
G01X1320349D02*
G02X1323157I1404J0D01*
G01Y1124649D01*
G02X1323051Y1124115I-1404J1D01*
G01X1323013Y1124024D01*
X1323690Y1122852D01*
X1323788Y1122839D01*
G02X1325007Y1121447I-185J-1392D01*
G02X1322199I-1404J0D01*
G01Y1121449D01*
G02X1322305Y1121983I1404J-1D01*
G01X1322343Y1122074D01*
X1321666Y1123246D01*
X1321568Y1123259D01*
G02X1320349Y1124651I185J1392D01*
G37*
G36*
G01X340507Y1131060D02*
G02X343315I1404J0D01*
G02X342096Y1129668I-1404J0D01*
G01X341998Y1129655D01*
X341321Y1128483D01*
X341359Y1128392D01*
G02X341465Y1127858I-1298J-535D01*
G01Y1127856D01*
G02X338657I-1404J0D01*
G02X339876Y1129248I1404J0D01*
G01X339974Y1129261D01*
X340651Y1130433D01*
X340613Y1130524D01*
G02X340507Y1131058I1298J535D01*
G01Y1131060D01*
G37*
G36*
G01X1316649D02*
G02X1319457I1404J0D01*
G02X1318238Y1129668I-1404J0D01*
G01X1318140Y1129655D01*
X1317463Y1128483D01*
X1317501Y1128392D01*
G02X1317607Y1127858I-1298J-535D01*
G01Y1127856D01*
G02X1314799I-1404J0D01*
G02X1316018Y1129248I1404J0D01*
G01X1316116Y1129261D01*
X1316793Y1130433D01*
X1316755Y1130524D01*
G02X1316649Y1131058I1298J535D01*
G01Y1131060D01*
G37*
G36*
G01X963269Y1556947D02*
G03X963539I135J148D01*
G02X965904Y1557866I2365J-2584D01*
G02X969115Y1555762I0J-3502D01*
G02X970504Y1554262I-115J-1500D01*
G02X969016Y1552758I-1504J0D01*
G02X965904Y1550862I-3112J1606D01*
G02X963539Y1551781I0J3503D01*
G03X963269I-135J-148D01*
G02X960904Y1550862I-2365J2584D01*
G02Y1557866I0J3502D01*
G02X963269Y1556947I0J-3503D01*
G37*
G36*
G01X1010001D02*
G03X1010271I135J148D01*
G02X1012636Y1557866I2365J-2584D01*
G02X1015849Y1555757I0J-3502D01*
G02X1016012Y1555766I164J-1495D01*
G02Y1552758I0J-1504D01*
G02X1015759Y1552779I-3J1504D01*
G02X1012636Y1550862I-3123J1585D01*
G02X1010271Y1551781I0J3503D01*
G03X1010001I-135J-148D01*
G02X1007636Y1550862I-2365J2584D01*
G02Y1557866I0J3502D01*
G02X1010001Y1556947I0J-3503D01*
G37*
G36*
G01X1056733D02*
G03X1057003I135J148D01*
G02X1059368Y1557866I2365J-2584D01*
G02X1062579Y1555762I0J-3502D01*
G02X1063968Y1554262I-115J-1500D01*
G02X1062480Y1552758I-1504J0D01*
G02X1059368Y1550862I-3112J1606D01*
G02X1057003Y1551781I0J3503D01*
G03X1056733I-135J-148D01*
G02X1054368Y1550862I-2365J2584D01*
G02Y1557866I0J3502D01*
G02X1056733Y1556947I0J-3503D01*
G37*
G36*
G01X1080099D02*
G03X1080369I135J148D01*
G02X1082734Y1557866I2365J-2584D01*
G02X1085945Y1555762I0J-3502D01*
G02X1087334Y1554262I-115J-1500D01*
G02X1085846Y1552758I-1504J0D01*
G02X1082734Y1550862I-3112J1606D01*
G02X1080369Y1551781I0J3503D01*
G03X1080099I-135J-148D01*
G02X1077734Y1550862I-2365J2584D01*
G02Y1557866I0J3502D01*
G02X1080099Y1556947I0J-3503D01*
G37*
G36*
G01X444392Y845448D02*
X445762D01*
G02X446927Y846071I1165J-778D01*
G02Y843271I0J-1400D01*
G02X445762Y843894I0J1401D01*
G01X444392D01*
G02X443227Y843271I-1165J778D01*
G02Y846071I0J1400D01*
G02X444392Y845448I0J-1401D01*
G37*
G36*
G01X431442Y848954D02*
X432814D01*
G02X433978Y849576I1164J-778D01*
G02Y846776I0J-1400D01*
G02X432814Y847398I0J1400D01*
G01X431442D01*
G02X430278Y846776I-1164J778D01*
G02Y849576I0J1400D01*
G02X431442Y848954I0J-1400D01*
G37*
G36*
G01X527642D02*
X529014D01*
G02X530178Y849576I1164J-778D01*
G02Y846776I0J-1400D01*
G02X529014Y847398I0J1400D01*
G01X527642D01*
G02X526478Y846776I-1164J778D01*
G02Y849576I0J1400D01*
G02X527642Y848954I0J-1400D01*
G37*
G36*
G01X532478Y848176D02*
G02X535278I1400J0D01*
G02X534022Y846783I-1400J0D01*
G01X533259Y845338D01*
G02X533428Y844671I-1232J-667D01*
G02X530628I-1400J0D01*
G02X531884Y846064I1400J0D01*
G01X532647Y847509D01*
G02X532478Y848176I1232J667D01*
G37*
G36*
G01X1407584Y848954D02*
X1408956D01*
G02X1410120Y849576I1164J-778D01*
G02Y846776I0J-1400D01*
G02X1408956Y847398I0J1400D01*
G01X1407584D01*
G02X1406420Y846776I-1164J778D01*
G02Y849576I0J1400D01*
G02X1407584Y848954I0J-1400D01*
G37*
G36*
G01X404127Y1083772D02*
X405497D01*
G02X406662Y1084395I1165J-778D01*
G02Y1081595I0J-1400D01*
G02X405497Y1082218I0J1401D01*
G01X404127D01*
G02X402962Y1081595I-1165J778D01*
G02Y1084395I0J1400D01*
G02X404127Y1083772I0J-1401D01*
G37*
G36*
G01X1380269D02*
X1381639D01*
G02X1382804Y1084395I1165J-778D01*
G02Y1081595I0J-1400D01*
G02X1381639Y1082218I0J1401D01*
G01X1380269D01*
G02X1379104Y1081595I-1165J778D01*
G02Y1084395I0J1400D01*
G02X1380269Y1083772I0J-1401D01*
G37*
G36*
G01X420775Y1086978D02*
X422147D01*
G02X423311Y1087600I1164J-778D01*
G02Y1084800I0J-1400D01*
G02X422147Y1085422I0J1400D01*
G01X420775D01*
G02X419611Y1084800I-1164J778D01*
G02Y1087600I0J1400D01*
G02X420775Y1086978I0J-1400D01*
G37*
G36*
G01X1396917D02*
X1398289D01*
G02X1399453Y1087600I1164J-778D01*
G02Y1084800I0J-1400D01*
G02X1398289Y1085422I0J1400D01*
G01X1396917D01*
G02X1395753Y1084800I-1164J778D01*
G02Y1087600I0J1400D01*
G02X1396917Y1086978I0J-1400D01*
G37*
G36*
G01X411526Y1090182D02*
X412898D01*
G02X414062Y1090804I1164J-778D01*
G02Y1088004I0J-1400D01*
G02X412898Y1088626I0J1400D01*
G01X411526D01*
G02X410362Y1088004I-1164J778D01*
G02Y1090804I0J1400D01*
G02X411526Y1090182I0J-1400D01*
G37*
G36*
G01X1387668D02*
X1389040D01*
G02X1390204Y1090804I1164J-778D01*
G02Y1088004I0J-1400D01*
G02X1389040Y1088626I0J1400D01*
G01X1387668D01*
G02X1386504Y1088004I-1164J778D01*
G02Y1090804I0J1400D01*
G02X1387668Y1090182I0J-1400D01*
G37*
G36*
G01X428175Y1093386D02*
X429547D01*
G02X430711Y1094008I1164J-778D01*
G02Y1091208I0J-1400D01*
G02X429547Y1091830I0J1400D01*
G01X428175D01*
G02X427011Y1091208I-1164J778D01*
G02Y1094008I0J1400D01*
G02X428175Y1093386I0J-1400D01*
G37*
G36*
G01X1404317D02*
X1405689D01*
G02X1406853Y1094008I1164J-778D01*
G02Y1091208I0J-1400D01*
G02X1405689Y1091830I0J1400D01*
G01X1404317D01*
G02X1403153Y1091208I-1164J778D01*
G02Y1094008I0J1400D01*
G02X1404317Y1093386I0J-1400D01*
G37*
G36*
G01X405976Y1099794D02*
X407346D01*
G02X408511Y1100417I1165J-778D01*
G02Y1097617I0J-1400D01*
G02X407346Y1098240I0J1401D01*
G01X405976D01*
G02X404811Y1097617I-1165J778D01*
G02Y1100417I0J1400D01*
G02X405976Y1099794I0J-1401D01*
G37*
G36*
G01X1382118D02*
X1383488D01*
G02X1384653Y1100417I1165J-778D01*
G02Y1097617I0J-1400D01*
G02X1383488Y1098240I0J1401D01*
G01X1382118D01*
G02X1380953Y1097617I-1165J778D01*
G02Y1100417I0J1400D01*
G02X1382118Y1099794I0J-1401D01*
G37*
G36*
G01X352326Y1102998D02*
X353696D01*
G02X354861Y1103621I1165J-778D01*
G02Y1100821I0J-1400D01*
G02X353696Y1101444I0J1401D01*
G01X352326D01*
G02X351161Y1100821I-1165J778D01*
G02Y1103621I0J1400D01*
G02X352326Y1102998I0J-1401D01*
G37*
G36*
G01X1328468D02*
X1329838D01*
G02X1331003Y1103621I1165J-778D01*
G02Y1100821I0J-1400D01*
G02X1329838Y1101444I0J1401D01*
G01X1328468D01*
G02X1327303Y1100821I-1165J778D01*
G02Y1103621I0J1400D01*
G02X1328468Y1102998I0J-1401D01*
G37*
G36*
G01X343075Y1106204D02*
X344447D01*
G02X345611Y1106826I1164J-778D01*
G02Y1104026I0J-1400D01*
G02X344447Y1104648I0J1400D01*
G01X343075D01*
G02X341911Y1104026I-1164J778D01*
G02Y1106826I0J1400D01*
G02X343075Y1106204I0J-1400D01*
G37*
G36*
G01X376375D02*
X377748D01*
G02X378912Y1106826I1164J-778D01*
G02Y1104026I0J-1400D01*
G02X377748Y1104648I0J1400D01*
G01X376375D01*
G02X375211Y1104026I-1164J778D01*
G02Y1106826I0J1400D01*
G02X376375Y1106204I0J-1400D01*
G37*
G36*
G01X417075D02*
X418447D01*
G02X419611Y1106826I1164J-778D01*
G02Y1104026I0J-1400D01*
G02X418447Y1104648I0J1400D01*
G01X417075D01*
G02X415911Y1104026I-1164J778D01*
G02Y1106826I0J1400D01*
G02X417075Y1106204I0J-1400D01*
G37*
G36*
G01X1319217D02*
X1320589D01*
G02X1321753Y1106826I1164J-778D01*
G02Y1104026I0J-1400D01*
G02X1320589Y1104648I0J1400D01*
G01X1319217D01*
G02X1318053Y1104026I-1164J778D01*
G02Y1106826I0J1400D01*
G02X1319217Y1106204I0J-1400D01*
G37*
G36*
G01X1352517D02*
X1353890D01*
G02X1355054Y1106826I1164J-778D01*
G02Y1104026I0J-1400D01*
G02X1353890Y1104648I0J1400D01*
G01X1352517D01*
G02X1351353Y1104026I-1164J778D01*
G02Y1106826I0J1400D01*
G02X1352517Y1106204I0J-1400D01*
G37*
G36*
G01X1393217D02*
X1394589D01*
G02X1395753Y1106826I1164J-778D01*
G02Y1104026I0J-1400D01*
G02X1394589Y1104648I0J1400D01*
G01X1393217D01*
G02X1392053Y1104026I-1164J778D01*
G02Y1106826I0J1400D01*
G02X1393217Y1106204I0J-1400D01*
G37*
G36*
G01X359725Y1109408D02*
X361097D01*
G02X362261Y1110030I1164J-778D01*
G02Y1107230I0J-1400D01*
G02X361097Y1107852I0J1400D01*
G01X359725D01*
G02X358561Y1107230I-1164J778D01*
G02Y1110030I0J1400D01*
G02X359725Y1109408I0J-1400D01*
G37*
G36*
G01X393026D02*
X394398D01*
G02X395562Y1110030I1164J-778D01*
G02Y1107230I0J-1400D01*
G02X394398Y1107852I0J1400D01*
G01X393026D01*
G02X391862Y1107230I-1164J778D01*
G02Y1110030I0J1400D01*
G02X393026Y1109408I0J-1400D01*
G37*
G36*
G01X1335867D02*
X1337239D01*
G02X1338403Y1110030I1164J-778D01*
G02Y1107230I0J-1400D01*
G02X1337239Y1107852I0J1400D01*
G01X1335867D01*
G02X1334703Y1107230I-1164J778D01*
G02Y1110030I0J1400D01*
G02X1335867Y1109408I0J-1400D01*
G37*
G36*
G01X1369168D02*
X1370540D01*
G02X1371704Y1110030I1164J-778D01*
G02Y1107230I0J-1400D01*
G02X1370540Y1107852I0J1400D01*
G01X1369168D01*
G02X1368004Y1107230I-1164J778D01*
G02Y1110030I0J1400D01*
G02X1369168Y1109408I0J-1400D01*
G37*
G36*
G01X350476Y1112612D02*
X351848D01*
G02X353012Y1113234I1164J-778D01*
G02Y1110434I0J-1400D01*
G02X351848Y1111056I0J1400D01*
G01X350476D01*
G02X349312Y1110434I-1164J778D01*
G02Y1113234I0J1400D01*
G02X350476Y1112612I0J-1400D01*
G37*
G36*
G01X383775D02*
X385147D01*
G02X386311Y1113234I1164J-778D01*
G02Y1110434I0J-1400D01*
G02X385147Y1111056I0J1400D01*
G01X383775D01*
G02X382611Y1110434I-1164J778D01*
G02Y1113234I0J1400D01*
G02X383775Y1112612I0J-1400D01*
G37*
G36*
G01X409675D02*
X411047D01*
G02X412211Y1113234I1164J-778D01*
G02Y1110434I0J-1400D01*
G02X411047Y1111056I0J1400D01*
G01X409675D01*
G02X408511Y1110434I-1164J778D01*
G02Y1113234I0J1400D01*
G02X409675Y1112612I0J-1400D01*
G37*
G36*
G01X1326618D02*
X1327990D01*
G02X1329154Y1113234I1164J-778D01*
G02Y1110434I0J-1400D01*
G02X1327990Y1111056I0J1400D01*
G01X1326618D01*
G02X1325454Y1110434I-1164J778D01*
G02Y1113234I0J1400D01*
G02X1326618Y1112612I0J-1400D01*
G37*
G36*
G01X1359917D02*
X1361289D01*
G02X1362453Y1113234I1164J-778D01*
G02Y1110434I0J-1400D01*
G02X1361289Y1111056I0J1400D01*
G01X1359917D01*
G02X1358753Y1110434I-1164J778D01*
G02Y1113234I0J1400D01*
G02X1359917Y1112612I0J-1400D01*
G37*
G36*
G01X1385817D02*
X1387189D01*
G02X1388353Y1113234I1164J-778D01*
G02Y1110434I0J-1400D01*
G02X1387189Y1111056I0J1400D01*
G01X1385817D01*
G02X1384653Y1110434I-1164J778D01*
G02Y1113234I0J1400D01*
G02X1385817Y1112612I0J-1400D01*
G37*
G36*
G01X367126Y1115816D02*
X368496D01*
G02X369661Y1116439I1165J-778D01*
G02Y1113639I0J-1400D01*
G02X368496Y1114262I0J1401D01*
G01X367126D01*
G02X365961Y1113639I-1165J778D01*
G02Y1116439I0J1400D01*
G02X367126Y1115816I0J-1401D01*
G37*
G36*
G01X400427D02*
X401797D01*
G02X402962Y1116439I1165J-778D01*
G02Y1113639I0J-1400D01*
G02X401797Y1114262I0J1401D01*
G01X400427D01*
G02X399262Y1113639I-1165J778D01*
G02Y1116439I0J1400D01*
G02X400427Y1115816I0J-1401D01*
G37*
G36*
G01X1343268D02*
X1344638D01*
G02X1345803Y1116439I1165J-778D01*
G02Y1113639I0J-1400D01*
G02X1344638Y1114262I0J1401D01*
G01X1343268D01*
G02X1342103Y1113639I-1165J778D01*
G02Y1116439I0J1400D01*
G02X1343268Y1115816I0J-1401D01*
G37*
G36*
G01X1376569D02*
X1377939D01*
G02X1379104Y1116439I1165J-778D01*
G02Y1113639I0J-1400D01*
G02X1377939Y1114262I0J1401D01*
G01X1376569D01*
G02X1375404Y1113639I-1165J778D01*
G02Y1116439I0J1400D01*
G02X1376569Y1115816I0J-1401D01*
G37*
G36*
G01X337526Y1122224D02*
X338896D01*
G02X340061Y1122847I1165J-778D01*
G02Y1120047I0J-1400D01*
G02X338896Y1120670I0J1401D01*
G01X337526D01*
G02X336361Y1120047I-1165J778D01*
G02Y1122847I0J1400D01*
G02X337526Y1122224I0J-1401D01*
G37*
G36*
G01X1313668D02*
X1315038D01*
G02X1316203Y1122847I1165J-778D01*
G02Y1120047I0J-1400D01*
G02X1315038Y1120670I0J1401D01*
G01X1313668D01*
G02X1312503Y1120047I-1165J778D01*
G02Y1122847I0J1400D01*
G02X1313668Y1122224I0J-1401D01*
G37*
G36*
G01X344925Y1128634D02*
X346297D01*
G02X347461Y1129256I1164J-778D01*
G02Y1126456I0J-1400D01*
G02X346297Y1127078I0J1400D01*
G01X344925D01*
G02X343761Y1126456I-1164J778D01*
G02Y1129256I0J1400D01*
G02X344925Y1128634I0J-1400D01*
G37*
G36*
G01X1321067D02*
X1322439D01*
G02X1323603Y1129256I1164J-778D01*
G02Y1126456I0J-1400D01*
G02X1322439Y1127078I0J1400D01*
G01X1321067D01*
G02X1319903Y1126456I-1164J778D01*
G02Y1129256I0J1400D01*
G02X1321067Y1128634I0J-1400D01*
G37*
G36*
G01X986635Y1556947D02*
G03X986905I135J148D01*
G02X989270Y1557866I2365J-2584D01*
G02X992481Y1555762I0J-3502D01*
G02X993966Y1554262I-15J-1500D01*
G02X992466Y1552762I-1500J0D01*
G02X992385Y1552764I-3J1500D01*
G02X989270Y1550862I-3115J1600D01*
G02X986905Y1551781I0J3503D01*
G03X986635I-135J-148D01*
G02X984270Y1550862I-2365J2584D01*
G02Y1557866I0J3502D01*
G02X986635Y1556947I0J-3503D01*
G37*
G36*
G01X1033367D02*
G03X1033637I135J148D01*
G02X1036002Y1557866I2365J-2584D01*
G02X1039214Y1555760I0J-3502D01*
G02X1039298Y1555762I78J-1498D01*
G02Y1552762I0J-1500D01*
G02X1039121Y1552772I-4J1500D01*
G02X1036002Y1550862I-3119J1592D01*
G02X1033637Y1551781I0J3503D01*
G03X1033367I-135J-148D01*
G02X1031002Y1550862I-2365J2584D01*
G02Y1557866I0J3502D01*
G02X1033367Y1556947I0J-3503D01*
G37*
G36*
G01X229206Y1656840D02*
X232906D01*
G02X233208Y1656537I-1J-303D01*
G01Y1646531D01*
G02X232906Y1646228I-302J-1D01*
G01X229206D01*
G02X228904Y1646531I1J303D01*
G01Y1648936D01*
G02X228890Y1649173I2002J237D01*
G02X228904Y1649410I2016J0D01*
G01Y1653660D01*
G02X228890Y1653897I2002J237D01*
G02X228904Y1654134I2016J0D01*
G01Y1656537D01*
G02X229206Y1656840I302J1D01*
G37*
G36*
G01X276450D02*
X280150D01*
G02X280452Y1656537I-1J-303D01*
G01Y1646531D01*
G02X280150Y1646228I-302J-1D01*
G01X276450D01*
G02X276148Y1646531I1J303D01*
G01Y1648936D01*
G02X276134Y1649173I2002J237D01*
G02X276148Y1649410I2016J0D01*
G01Y1653660D01*
G02X276134Y1653897I2002J237D01*
G02X276148Y1654134I2016J0D01*
G01Y1656537D01*
G02X276450Y1656840I302J1D01*
G37*
G36*
G01X237080Y1660776D02*
X240780D01*
G02X241082Y1660474I0J-302D01*
G01Y1650468D01*
G02X240780Y1650166I-302J0D01*
G01X237080D01*
G02X236778Y1650468I0J302D01*
G01Y1652873D01*
G02X236764Y1653110I2002J237D01*
G02X236778Y1653347I2016J0D01*
G01Y1657597D01*
G02X236764Y1657834I2002J237D01*
G02X236778Y1658071I2016J0D01*
G01Y1660474D01*
G02X237080Y1660776I302J0D01*
G37*
G36*
G01X268576D02*
X272276D01*
G02X272578Y1660474I0J-302D01*
G01Y1650468D01*
G02X272276Y1650166I-302J0D01*
G01X268576D01*
G02X268274Y1650468I0J302D01*
G01Y1652873D01*
G02X268260Y1653110I2002J237D01*
G02X268274Y1653347I2016J0D01*
G01Y1657597D01*
G02X268260Y1657834I2002J237D01*
G02X268274Y1658071I2016J0D01*
G01Y1660474D01*
G02X268576Y1660776I302J0D01*
G37*
G36*
G01X284324D02*
X288024D01*
G02X288326Y1660474I0J-302D01*
G01Y1650468D01*
G02X288024Y1650166I-302J0D01*
G01X284324D01*
G02X284022Y1650468I0J302D01*
G01Y1652873D01*
G02X284008Y1653110I2002J237D01*
G02X284022Y1653347I2016J0D01*
G01Y1657597D01*
G02X284008Y1657834I2002J237D01*
G02X284022Y1658071I2016J0D01*
G01Y1660474D01*
G02X284324Y1660776I302J0D01*
G37*
G36*
G01X229206Y1671014D02*
X232906D01*
G02X233208Y1670711I-1J-303D01*
G01Y1660705D01*
G02X232906Y1660402I-302J-1D01*
G01X229206D01*
G02X228904Y1660705I1J303D01*
G01Y1663109D01*
G02X228890Y1663346I2002J237D01*
G02X228904Y1663583I2016J0D01*
G01Y1667833D01*
G02X228890Y1668070I2002J237D01*
G02X228904Y1668307I2016J0D01*
G01Y1670711D01*
G02X229206Y1671014I302J1D01*
G37*
G36*
G01X244954D02*
X248654D01*
G02X248956Y1670711I-1J-303D01*
G01Y1660705D01*
G02X248654Y1660402I-302J-1D01*
G01X244954D01*
G02X244652Y1660705I1J303D01*
G01Y1663109D01*
G02X244638Y1663346I2002J237D01*
G02X244652Y1663583I2016J0D01*
G01Y1667833D01*
G02X244638Y1668070I2002J237D01*
G02X244652Y1668307I2016J0D01*
G01Y1670711D01*
G02X244954Y1671014I302J1D01*
G37*
G36*
G01X276450D02*
X280150D01*
G02X280452Y1670711I-1J-303D01*
G01Y1660705D01*
G02X280150Y1660402I-302J-1D01*
G01X276450D01*
G02X276148Y1660705I1J303D01*
G01Y1663109D01*
G02X276134Y1663346I2002J237D01*
G02X276148Y1663583I2016J0D01*
G01Y1667833D01*
G02X276134Y1668070I2002J237D01*
G02X276148Y1668307I2016J0D01*
G01Y1670711D01*
G02X276450Y1671014I302J1D01*
G37*
G36*
G01X252828Y1674950D02*
X256528D01*
G02X256830Y1674648I0J-302D01*
G01Y1664642D01*
G02X256528Y1664340I-302J0D01*
G01X252828D01*
G02X252526Y1664642I0J302D01*
G01Y1667046D01*
G02X252512Y1667283I2002J237D01*
G02X252526Y1667520I2016J0D01*
G01Y1671770D01*
G02X252512Y1672007I2002J237D01*
G02X252526Y1672244I2016J0D01*
G01Y1674648D01*
G02X252828Y1674950I302J0D01*
G37*
G36*
G01X268576D02*
X272276D01*
G02X272578Y1674648I0J-302D01*
G01Y1664642D01*
G02X272276Y1664340I-302J0D01*
G01X268576D01*
G02X268274Y1664642I0J302D01*
G01Y1667046D01*
G02X268260Y1667283I2002J237D01*
G02X268274Y1667520I2016J0D01*
G01Y1671770D01*
G02X268260Y1672007I2002J237D01*
G02X268274Y1672244I2016J0D01*
G01Y1674648D01*
G02X268576Y1674950I302J0D01*
G37*
G36*
G01X284324D02*
X288024D01*
G02X288326Y1674648I0J-302D01*
G01Y1664642D01*
G02X288024Y1664340I-302J0D01*
G01X284324D01*
G02X284022Y1664642I0J302D01*
G01Y1667046D01*
G02X284008Y1667283I2002J237D01*
G02X284022Y1667520I2016J0D01*
G01Y1671770D01*
G02X284008Y1672007I2002J237D01*
G02X284022Y1672244I2016J0D01*
G01Y1674648D01*
G02X284324Y1674950I302J0D01*
G37*
G36*
G01X229206Y1685186D02*
X232906D01*
G02X233208Y1684884I0J-302D01*
G01Y1674878D01*
G02X232906Y1674576I-302J0D01*
G01X229206D01*
G02X228904Y1674878I0J302D01*
G01Y1677282D01*
G02X228890Y1677519I2002J237D01*
G02X228904Y1677756I2016J0D01*
G01Y1682007D01*
G02X228890Y1682244I2002J237D01*
G02X228904Y1682481I2016J0D01*
G01Y1684884D01*
G02X229206Y1685186I302J0D01*
G37*
G36*
G01X244954D02*
X248654D01*
G02X248956Y1684884I0J-302D01*
G01Y1674878D01*
G02X248654Y1674576I-302J0D01*
G01X244954D01*
G02X244652Y1674878I0J302D01*
G01Y1677282D01*
G02X244638Y1677519I2002J237D01*
G02X244652Y1677756I2016J0D01*
G01Y1682007D01*
G02X244638Y1682244I2002J237D01*
G02X244652Y1682481I2016J0D01*
G01Y1684884D01*
G02X244954Y1685186I302J0D01*
G37*
G36*
G01X260702D02*
X264402D01*
G02X264704Y1684884I0J-302D01*
G01Y1674878D01*
G02X264402Y1674576I-302J0D01*
G01X260702D01*
G02X260400Y1674878I0J302D01*
G01Y1677282D01*
G02X260386Y1677519I2002J237D01*
G02X260400Y1677756I2016J0D01*
G01Y1682007D01*
G02X260386Y1682244I2002J237D01*
G02X260400Y1682481I2016J0D01*
G01Y1684884D01*
G02X260702Y1685186I302J0D01*
G37*
G36*
G01X276450D02*
X280150D01*
G02X280452Y1684884I0J-302D01*
G01Y1674878D01*
G02X280150Y1674576I-302J0D01*
G01X276450D01*
G02X276148Y1674878I0J302D01*
G01Y1677282D01*
G02X276134Y1677519I2002J237D01*
G02X276148Y1677756I2016J0D01*
G01Y1682007D01*
G02X276134Y1682244I2002J237D01*
G02X276148Y1682481I2016J0D01*
G01Y1684884D01*
G02X276450Y1685186I302J0D01*
G37*
G36*
G01X560308D02*
X564008D01*
G02X564310Y1684884I0J-302D01*
G01Y1674878D01*
G02X564008Y1674576I-302J0D01*
G01X560308D01*
G02X560006Y1674878I0J302D01*
G01Y1676909D01*
G02X559915Y1677519I2002J610D01*
G02X560637Y1679101I2094J0D01*
G01X560956Y1679751D01*
G03Y1680013I-267J131D01*
G01X560638Y1680662D01*
G02X559915Y1682244I1369J1582D01*
G02X560006Y1682854I2093J0D01*
G01Y1684884D01*
G02X560308Y1685186I302J0D01*
G37*
G36*
G01X576056D02*
X579756D01*
G02X580058Y1684884I0J-302D01*
G01Y1674878D01*
G02X579756Y1674576I-302J0D01*
G01X576056D01*
G02X575754Y1674878I0J302D01*
G01Y1676909D01*
G02X575663Y1677519I2002J610D01*
G02X576385Y1679101I2094J0D01*
G01X576704Y1679751D01*
G03Y1680013I-267J131D01*
G01X576386Y1680662D01*
G02X575663Y1682244I1369J1582D01*
G02X575754Y1682854I2093J0D01*
G01Y1684884D01*
G02X576056Y1685186I302J0D01*
G37*
G36*
G01X591804D02*
X595504D01*
G02X595806Y1684884I0J-302D01*
G01Y1674878D01*
G02X595504Y1674576I-302J0D01*
G01X591804D01*
G02X591502Y1674878I0J302D01*
G01Y1676909D01*
G02X591411Y1677519I2002J610D01*
G02X592133Y1679101I2094J0D01*
G01X592452Y1679751D01*
G03Y1680013I-267J131D01*
G01X592134Y1680662D01*
G02X591411Y1682244I1369J1582D01*
G02X591502Y1682854I2093J0D01*
G01Y1684884D01*
G02X591804Y1685186I302J0D01*
G37*
G36*
G01X607552D02*
X611252D01*
G02X611554Y1684884I0J-302D01*
G01Y1674878D01*
G02X611252Y1674576I-302J0D01*
G01X607552D01*
G02X607250Y1674878I0J302D01*
G01Y1676909D01*
G02X607159Y1677519I2002J610D01*
G02X607881Y1679101I2094J0D01*
G01X608200Y1679751D01*
G03Y1680013I-267J131D01*
G01X607882Y1680662D01*
G02X607159Y1682244I1369J1582D01*
G02X607250Y1682854I2093J0D01*
G01Y1684884D01*
G02X607552Y1685186I302J0D01*
G37*
G36*
G01X1237080D02*
X1240780D01*
G02X1241082Y1684884I0J-302D01*
G01Y1674878D01*
G02X1240780Y1674576I-302J0D01*
G01X1237080D01*
G02X1236778Y1674878I0J302D01*
G01Y1677282D01*
G02X1236764Y1677519I2002J237D01*
G02X1236778Y1677756I2016J0D01*
G01Y1682007D01*
G02X1236764Y1682244I2002J237D01*
G02X1236778Y1682481I2016J0D01*
G01Y1684884D01*
G02X1237080Y1685186I302J0D01*
G37*
G36*
G01X1252828D02*
X1256528D01*
G02X1256830Y1684884I0J-302D01*
G01Y1674878D01*
G02X1256528Y1674576I-302J0D01*
G01X1252828D01*
G02X1252526Y1674878I0J302D01*
G01Y1677282D01*
G02X1252512Y1677519I2002J237D01*
G02X1252526Y1677756I2016J0D01*
G01Y1682007D01*
G02X1252512Y1682244I2002J237D01*
G02X1252526Y1682481I2016J0D01*
G01Y1684884D01*
G02X1252828Y1685186I302J0D01*
G37*
G36*
G01X1268576D02*
X1272276D01*
G02X1272578Y1684884I0J-302D01*
G01Y1674878D01*
G02X1272276Y1674576I-302J0D01*
G01X1268576D01*
G02X1268274Y1674878I0J302D01*
G01Y1677282D01*
G02X1268260Y1677519I2002J237D01*
G02X1268274Y1677756I2016J0D01*
G01Y1682007D01*
G02X1268260Y1682244I2002J237D01*
G02X1268274Y1682481I2016J0D01*
G01Y1684884D01*
G02X1268576Y1685186I302J0D01*
G37*
G36*
G01X1284324D02*
X1288024D01*
G02X1288326Y1684884I0J-302D01*
G01Y1674878D01*
G02X1288024Y1674576I-302J0D01*
G01X1284324D01*
G02X1284022Y1674878I0J302D01*
G01Y1677282D01*
G02X1284008Y1677519I2002J237D01*
G02X1284022Y1677756I2016J0D01*
G01Y1682007D01*
G02X1284008Y1682244I2002J237D01*
G02X1284022Y1682481I2016J0D01*
G01Y1684884D01*
G02X1284324Y1685186I302J0D01*
G37*
G36*
G01X1568182D02*
X1571882D01*
G02X1572184Y1684884I0J-302D01*
G01Y1674878D01*
G02X1571882Y1674576I-302J0D01*
G01X1568182D01*
G02X1567880Y1674878I0J302D01*
G01Y1676909D01*
G02X1567789Y1677519I2002J610D01*
G02X1568511Y1679101I2094J0D01*
G01X1568830Y1679751D01*
G03Y1680013I-267J131D01*
G01X1568512Y1680662D01*
G02X1567789Y1682244I1369J1582D01*
G02X1567880Y1682854I2093J0D01*
G01Y1684884D01*
G02X1568182Y1685186I302J0D01*
G37*
G36*
G01X1583930D02*
X1587630D01*
G02X1587932Y1684884I0J-302D01*
G01Y1674878D01*
G02X1587630Y1674576I-302J0D01*
G01X1583930D01*
G02X1583628Y1674878I0J302D01*
G01Y1676909D01*
G02X1583537Y1677519I2002J610D01*
G02X1584259Y1679101I2094J0D01*
G01X1584578Y1679751D01*
G03Y1680013I-267J131D01*
G01X1584260Y1680662D01*
G02X1583537Y1682244I1369J1582D01*
G02X1583628Y1682854I2093J0D01*
G01Y1684884D01*
G02X1583930Y1685186I302J0D01*
G37*
G36*
G01X1599678D02*
X1603378D01*
G02X1603680Y1684884I0J-302D01*
G01Y1674878D01*
G02X1603378Y1674576I-302J0D01*
G01X1599678D01*
G02X1599376Y1674878I0J302D01*
G01Y1676909D01*
G02X1599285Y1677519I2002J610D01*
G02X1600007Y1679101I2094J0D01*
G01X1600326Y1679751D01*
G03Y1680013I-267J131D01*
G01X1600008Y1680662D01*
G02X1599285Y1682244I1369J1582D01*
G02X1599376Y1682854I2093J0D01*
G01Y1684884D01*
G02X1599678Y1685186I302J0D01*
G37*
G36*
G01X1615426D02*
X1619126D01*
G02X1619428Y1684884I0J-302D01*
G01Y1674878D01*
G02X1619126Y1674576I-302J0D01*
G01X1615426D01*
G02X1615124Y1674878I0J302D01*
G01Y1676909D01*
G02X1615033Y1677519I2002J610D01*
G02X1615755Y1679101I2094J0D01*
G01X1616074Y1679751D01*
G03Y1680013I-267J131D01*
G01X1615756Y1680662D01*
G02X1615033Y1682244I1369J1582D01*
G02X1615124Y1682854I2093J0D01*
G01Y1684884D01*
G02X1615426Y1685186I302J0D01*
G37*
G36*
G01X296135D02*
X299835D01*
G02X300138Y1684884I1J-302D01*
G01Y1674878D01*
G02X299835Y1674576I-303J1D01*
G01X296135D01*
G02X295832Y1674878I-1J302D01*
G01Y1677290D01*
G02X295819Y1677519I2003J229D01*
G02X295832Y1677748I2016J0D01*
G01Y1682015D01*
G02X295819Y1682244I2003J229D01*
G02X295832Y1682473I2016J0D01*
G01Y1684884D01*
G02X296135Y1685186I303J-1D01*
G37*
G36*
G01X311883D02*
X315583D01*
G02X315886Y1684884I1J-302D01*
G01Y1674878D01*
G02X315583Y1674576I-303J1D01*
G01X311883D01*
G02X311580Y1674878I-1J302D01*
G01Y1677290D01*
G02X311567Y1677519I2003J229D01*
G02X311580Y1677748I2016J0D01*
G01Y1682015D01*
G02X311567Y1682244I2003J229D01*
G02X311580Y1682473I2016J0D01*
G01Y1684884D01*
G02X311883Y1685186I303J-1D01*
G37*
G36*
G01X327631D02*
X331331D01*
G02X331634Y1684884I1J-302D01*
G01Y1674878D01*
G02X331331Y1674576I-303J1D01*
G01X327631D01*
G02X327328Y1674878I-1J302D01*
G01Y1677290D01*
G02X327315Y1677519I2003J229D01*
G02X327328Y1677748I2016J0D01*
G01Y1682015D01*
G02X327315Y1682244I2003J229D01*
G02X327328Y1682473I2016J0D01*
G01Y1684884D01*
G02X327631Y1685186I303J-1D01*
G37*
G36*
G01X343379D02*
X347079D01*
G02X347382Y1684884I1J-302D01*
G01Y1674878D01*
G02X347079Y1674576I-303J1D01*
G01X343379D01*
G02X343076Y1674878I-1J302D01*
G01Y1677290D01*
G02X343063Y1677519I2003J229D01*
G02X343076Y1677748I2016J0D01*
G01Y1682015D01*
G02X343063Y1682244I2003J229D01*
G02X343076Y1682473I2016J0D01*
G01Y1684884D01*
G02X343379Y1685186I303J-1D01*
G37*
G36*
G01X493379D02*
X497079D01*
G02X497382Y1684884I1J-302D01*
G01Y1674878D01*
G02X497079Y1674576I-303J1D01*
G01X493379D01*
G02X493076Y1674878I-1J302D01*
G01Y1676912D01*
G02X492986Y1677519I2002J607D01*
G02X493708Y1679101I2094J0D01*
G01X494027Y1679751D01*
G03Y1680013I-267J131D01*
G01X493709Y1680662D01*
G02X492986Y1682244I1369J1582D01*
G02X493076Y1682851I2092J0D01*
G01Y1684884D01*
G02X493379Y1685186I303J-1D01*
G37*
G36*
G01X509127D02*
X512827D01*
G02X513130Y1684884I1J-302D01*
G01Y1674878D01*
G02X512827Y1674576I-303J1D01*
G01X509127D01*
G02X508824Y1674878I-1J302D01*
G01Y1676912D01*
G02X508734Y1677519I2002J607D01*
G02X509456Y1679101I2094J0D01*
G01X509775Y1679751D01*
G03Y1680013I-267J131D01*
G01X509457Y1680662D01*
G02X508734Y1682244I1369J1582D01*
G02X508824Y1682851I2092J0D01*
G01Y1684884D01*
G02X509127Y1685186I303J-1D01*
G37*
G36*
G01X524875D02*
X528575D01*
G02X528878Y1684884I1J-302D01*
G01Y1674878D01*
G02X528575Y1674576I-303J1D01*
G01X524875D01*
G02X524572Y1674878I-1J302D01*
G01Y1676912D01*
G02X524482Y1677519I2002J607D01*
G02X525204Y1679101I2094J0D01*
G01X525523Y1679751D01*
G03Y1680013I-267J131D01*
G01X525205Y1680662D01*
G02X524482Y1682244I1369J1582D01*
G02X524572Y1682851I2092J0D01*
G01Y1684884D01*
G02X524875Y1685186I303J-1D01*
G37*
G36*
G01X540623D02*
X544323D01*
G02X544626Y1684884I1J-302D01*
G01Y1674878D01*
G02X544323Y1674576I-303J1D01*
G01X540623D01*
G02X540320Y1674878I-1J302D01*
G01Y1676912D01*
G02X540230Y1677519I2002J607D01*
G02X540952Y1679101I2094J0D01*
G01X541271Y1679751D01*
G03Y1680013I-267J131D01*
G01X540953Y1680662D01*
G02X540230Y1682244I1369J1582D01*
G02X540320Y1682851I2092J0D01*
G01Y1684884D01*
G02X540623Y1685186I303J-1D01*
G37*
G36*
G01X1304009D02*
X1307709D01*
G02X1308012Y1684884I1J-302D01*
G01Y1674878D01*
G02X1307709Y1674576I-303J1D01*
G01X1304009D01*
G02X1303706Y1674878I-1J302D01*
G01Y1677290D01*
G02X1303693Y1677519I2003J229D01*
G02X1303706Y1677748I2016J0D01*
G01Y1682015D01*
G02X1303693Y1682244I2003J229D01*
G02X1303706Y1682473I2016J0D01*
G01Y1684884D01*
G02X1304009Y1685186I303J-1D01*
G37*
G36*
G01X1319757D02*
X1323457D01*
G02X1323760Y1684884I1J-302D01*
G01Y1674878D01*
G02X1323457Y1674576I-303J1D01*
G01X1319757D01*
G02X1319454Y1674878I-1J302D01*
G01Y1677290D01*
G02X1319441Y1677519I2003J229D01*
G02X1319454Y1677748I2016J0D01*
G01Y1682015D01*
G02X1319441Y1682244I2003J229D01*
G02X1319454Y1682473I2016J0D01*
G01Y1684884D01*
G02X1319757Y1685186I303J-1D01*
G37*
G36*
G01X1335505D02*
X1339205D01*
G02X1339508Y1684884I1J-302D01*
G01Y1674878D01*
G02X1339205Y1674576I-303J1D01*
G01X1335505D01*
G02X1335202Y1674878I-1J302D01*
G01Y1677290D01*
G02X1335189Y1677519I2003J229D01*
G02X1335202Y1677748I2016J0D01*
G01Y1682015D01*
G02X1335189Y1682244I2003J229D01*
G02X1335202Y1682473I2016J0D01*
G01Y1684884D01*
G02X1335505Y1685186I303J-1D01*
G37*
G36*
G01X1351253D02*
X1354953D01*
G02X1355256Y1684884I1J-302D01*
G01Y1674878D01*
G02X1354953Y1674576I-303J1D01*
G01X1351253D01*
G02X1350950Y1674878I-1J302D01*
G01Y1677290D01*
G02X1350937Y1677519I2003J229D01*
G02X1350950Y1677748I2016J0D01*
G01Y1682015D01*
G02X1350937Y1682244I2003J229D01*
G02X1350950Y1682473I2016J0D01*
G01Y1684884D01*
G02X1351253Y1685186I303J-1D01*
G37*
G36*
G01X1501253D02*
X1504953D01*
G02X1505256Y1684884I1J-302D01*
G01Y1674878D01*
G02X1504953Y1674576I-303J1D01*
G01X1501253D01*
G02X1500950Y1674878I-1J302D01*
G01Y1676912D01*
G02X1500860Y1677519I2002J607D01*
G02X1501582Y1679101I2094J0D01*
G01X1501901Y1679751D01*
G03Y1680013I-267J131D01*
G01X1501583Y1680662D01*
G02X1500860Y1682244I1369J1582D01*
G02X1500950Y1682851I2092J0D01*
G01Y1684884D01*
G02X1501253Y1685186I303J-1D01*
G37*
G36*
G01X1517001D02*
X1520701D01*
G02X1521004Y1684884I1J-302D01*
G01Y1674878D01*
G02X1520701Y1674576I-303J1D01*
G01X1517001D01*
G02X1516698Y1674878I-1J302D01*
G01Y1676912D01*
G02X1516608Y1677519I2002J607D01*
G02X1517330Y1679101I2094J0D01*
G01X1517649Y1679751D01*
G03Y1680013I-267J131D01*
G01X1517331Y1680662D01*
G02X1516608Y1682244I1369J1582D01*
G02X1516698Y1682851I2092J0D01*
G01Y1684884D01*
G02X1517001Y1685186I303J-1D01*
G37*
G36*
G01X1532749D02*
X1536449D01*
G02X1536752Y1684884I1J-302D01*
G01Y1674878D01*
G02X1536449Y1674576I-303J1D01*
G01X1532749D01*
G02X1532446Y1674878I-1J302D01*
G01Y1676912D01*
G02X1532356Y1677519I2002J607D01*
G02X1533078Y1679101I2094J0D01*
G01X1533397Y1679751D01*
G03Y1680013I-267J131D01*
G01X1533079Y1680662D01*
G02X1532356Y1682244I1369J1582D01*
G02X1532446Y1682851I2092J0D01*
G01Y1684884D01*
G02X1532749Y1685186I303J-1D01*
G37*
G36*
G01X1548497D02*
X1552197D01*
G02X1552500Y1684884I1J-302D01*
G01Y1674878D01*
G02X1552197Y1674576I-303J1D01*
G01X1548497D01*
G02X1548194Y1674878I-1J302D01*
G01Y1676912D01*
G02X1548104Y1677519I2002J607D01*
G02X1548826Y1679101I2094J0D01*
G01X1549145Y1679751D01*
G03Y1680013I-267J131D01*
G01X1548827Y1680662D01*
G02X1548104Y1682244I1369J1582D01*
G02X1548194Y1682851I2092J0D01*
G01Y1684884D01*
G02X1548497Y1685186I303J-1D01*
G37*
G36*
G01X237080Y1689124D02*
X240780D01*
G02X241082Y1688821I-1J-303D01*
G01Y1678815D01*
G02X240780Y1678512I-302J-1D01*
G01X237080D01*
G02X236778Y1678815I1J303D01*
G01Y1681219D01*
G02X236764Y1681456I2002J237D01*
G02X236778Y1681693I2016J0D01*
G01Y1685943D01*
G02X236764Y1686180I2002J237D01*
G02X236778Y1686417I2016J0D01*
G01Y1688821D01*
G02X237080Y1689124I302J1D01*
G37*
G36*
G01X252828D02*
X256528D01*
G02X256830Y1688821I-1J-303D01*
G01Y1678815D01*
G02X256528Y1678512I-302J-1D01*
G01X252828D01*
G02X252526Y1678815I1J303D01*
G01Y1681219D01*
G02X252512Y1681456I2002J237D01*
G02X252526Y1681693I2016J0D01*
G01Y1685943D01*
G02X252512Y1686180I2002J237D01*
G02X252526Y1686417I2016J0D01*
G01Y1688821D01*
G02X252828Y1689124I302J1D01*
G37*
G36*
G01X268576D02*
X272276D01*
G02X272578Y1688821I-1J-303D01*
G01Y1678815D01*
G02X272276Y1678512I-302J-1D01*
G01X268576D01*
G02X268274Y1678815I1J303D01*
G01Y1681219D01*
G02X268260Y1681456I2002J237D01*
G02X268274Y1681693I2016J0D01*
G01Y1685943D01*
G02X268260Y1686180I2002J237D01*
G02X268274Y1686417I2016J0D01*
G01Y1688821D01*
G02X268576Y1689124I302J1D01*
G37*
G36*
G01X284324D02*
X288024D01*
G02X288326Y1688821I-1J-303D01*
G01Y1678815D01*
G02X288024Y1678512I-302J-1D01*
G01X284324D01*
G02X284022Y1678815I1J303D01*
G01Y1681219D01*
G02X284008Y1681456I2002J237D01*
G02X284022Y1681693I2016J0D01*
G01Y1685943D01*
G02X284008Y1686180I2002J237D01*
G02X284022Y1686417I2016J0D01*
G01Y1688821D01*
G02X284324Y1689124I302J1D01*
G37*
G36*
G01X304009D02*
X307709D01*
G02X308012Y1688821I0J-303D01*
G01Y1678815D01*
G02X307709Y1678512I-303J0D01*
G01X304009D01*
G02X303706Y1678815I0J303D01*
G01Y1681227D01*
G02X303693Y1681456I2003J229D01*
G02X303706Y1681685I2016J0D01*
G01Y1685951D01*
G02X303693Y1686180I2003J229D01*
G02X303706Y1686409I2016J0D01*
G01Y1688821D01*
G02X304009Y1689124I303J0D01*
G37*
G36*
G01X319757D02*
X323457D01*
G02X323760Y1688821I0J-303D01*
G01Y1678815D01*
G02X323457Y1678512I-303J0D01*
G01X319757D01*
G02X319454Y1678815I0J303D01*
G01Y1681227D01*
G02X319441Y1681456I2003J229D01*
G02X319454Y1681685I2016J0D01*
G01Y1685951D01*
G02X319441Y1686180I2003J229D01*
G02X319454Y1686409I2016J0D01*
G01Y1688821D01*
G02X319757Y1689124I303J0D01*
G37*
G36*
G01X335505D02*
X339205D01*
G02X339508Y1688821I0J-303D01*
G01Y1678815D01*
G02X339205Y1678512I-303J0D01*
G01X335505D01*
G02X335202Y1678815I0J303D01*
G01Y1681227D01*
G02X335189Y1681456I2003J229D01*
G02X335202Y1681685I2016J0D01*
G01Y1685951D01*
G02X335189Y1686180I2003J229D01*
G02X335202Y1686409I2016J0D01*
G01Y1688821D01*
G02X335505Y1689124I303J0D01*
G37*
G36*
G01X351253D02*
X354953D01*
G02X355256Y1688821I0J-303D01*
G01Y1678815D01*
G02X354953Y1678512I-303J0D01*
G01X351253D01*
G02X350950Y1678815I0J303D01*
G01Y1681227D01*
G02X350937Y1681456I2003J229D01*
G02X350950Y1681685I2016J0D01*
G01Y1685951D01*
G02X350937Y1686180I2003J229D01*
G02X350950Y1686409I2016J0D01*
G01Y1688821D01*
G02X351253Y1689124I303J0D01*
G37*
G36*
G01X501253D02*
X504953D01*
G02X505256Y1688821I0J-303D01*
G01Y1678815D01*
G02X504953Y1678512I-303J0D01*
G01X501253D01*
G02X500950Y1678815I0J303D01*
G01Y1680849D01*
G02X500860Y1681456I2002J607D01*
G02X501582Y1683038I2094J0D01*
G01X501901Y1683688D01*
G03Y1683950I-267J131D01*
G01X501584Y1684597D01*
G02X500860Y1686180I1369J1583D01*
G02X500950Y1686787I2092J0D01*
G01Y1688821D01*
G02X501253Y1689124I303J0D01*
G37*
G36*
G01X517001D02*
X520701D01*
G02X521004Y1688821I0J-303D01*
G01Y1678815D01*
G02X520701Y1678512I-303J0D01*
G01X517001D01*
G02X516698Y1678815I0J303D01*
G01Y1680849D01*
G02X516608Y1681456I2002J607D01*
G02X517330Y1683038I2094J0D01*
G01X517649Y1683688D01*
G03Y1683950I-267J131D01*
G01X517332Y1684597D01*
G02X516608Y1686180I1369J1583D01*
G02X516698Y1686787I2092J0D01*
G01Y1688821D01*
G02X517001Y1689124I303J0D01*
G37*
G36*
G01X532749D02*
X536449D01*
G02X536752Y1688821I0J-303D01*
G01Y1678815D01*
G02X536449Y1678512I-303J0D01*
G01X532749D01*
G02X532446Y1678815I0J303D01*
G01Y1680849D01*
G02X532356Y1681456I2002J607D01*
G02X533078Y1683038I2094J0D01*
G01X533397Y1683688D01*
G03Y1683950I-267J131D01*
G01X533080Y1684597D01*
G02X532356Y1686180I1369J1583D01*
G02X532446Y1686787I2092J0D01*
G01Y1688821D01*
G02X532749Y1689124I303J0D01*
G37*
G36*
G01X548497D02*
X552197D01*
G02X552500Y1688821I0J-303D01*
G01Y1678815D01*
G02X552197Y1678512I-303J0D01*
G01X548497D01*
G02X548194Y1678815I0J303D01*
G01Y1680849D01*
G02X548104Y1681456I2002J607D01*
G02X548826Y1683038I2094J0D01*
G01X549145Y1683688D01*
G03Y1683950I-267J131D01*
G01X548828Y1684597D01*
G02X548104Y1686180I1369J1583D01*
G02X548194Y1686787I2092J0D01*
G01Y1688821D01*
G02X548497Y1689124I303J0D01*
G37*
G36*
G01X568182D02*
X571882D01*
G02X572184Y1688821I-1J-303D01*
G01Y1678815D01*
G02X571882Y1678512I-302J-1D01*
G01X568182D01*
G02X567880Y1678815I1J303D01*
G01Y1680846D01*
G02X567789Y1681456I2002J610D01*
G02X568511Y1683038I2094J0D01*
G01X568830Y1683688D01*
G03Y1683950I-267J131D01*
G01X568513Y1684597D01*
G02X567789Y1686180I1369J1583D01*
G02X567880Y1686790I2093J0D01*
G01Y1688821D01*
G02X568182Y1689124I302J1D01*
G37*
G36*
G01X583930D02*
X587630D01*
G02X587932Y1688821I-1J-303D01*
G01Y1678815D01*
G02X587630Y1678512I-302J-1D01*
G01X583930D01*
G02X583628Y1678815I1J303D01*
G01Y1680846D01*
G02X583537Y1681456I2002J610D01*
G02X584259Y1683038I2094J0D01*
G01X584578Y1683688D01*
G03Y1683950I-267J131D01*
G01X584261Y1684597D01*
G02X583537Y1686180I1369J1583D01*
G02X583628Y1686790I2093J0D01*
G01Y1688821D01*
G02X583930Y1689124I302J1D01*
G37*
G36*
G01X599678D02*
X603378D01*
G02X603680Y1688821I-1J-303D01*
G01Y1678815D01*
G02X603378Y1678512I-302J-1D01*
G01X599678D01*
G02X599376Y1678815I1J303D01*
G01Y1680846D01*
G02X599285Y1681456I2002J610D01*
G02X600007Y1683038I2094J0D01*
G01X600326Y1683688D01*
G03Y1683950I-267J131D01*
G01X600009Y1684597D01*
G02X599285Y1686180I1369J1583D01*
G02X599376Y1686790I2093J0D01*
G01Y1688821D01*
G02X599678Y1689124I302J1D01*
G37*
G36*
G01X615426D02*
X619126D01*
G02X619428Y1688821I-1J-303D01*
G01Y1678815D01*
G02X619126Y1678512I-302J-1D01*
G01X615426D01*
G02X615124Y1678815I1J303D01*
G01Y1680846D01*
G02X615033Y1681456I2002J610D01*
G02X615755Y1683038I2094J0D01*
G01X616074Y1683688D01*
G03Y1683950I-267J131D01*
G01X615757Y1684597D01*
G02X615033Y1686180I1369J1583D01*
G02X615124Y1686790I2093J0D01*
G01Y1688821D01*
G02X615426Y1689124I302J1D01*
G37*
G36*
G01X1244954D02*
X1248654D01*
G02X1248956Y1688821I-1J-303D01*
G01Y1678815D01*
G02X1248654Y1678512I-302J-1D01*
G01X1244954D01*
G02X1244652Y1678815I1J303D01*
G01Y1681219D01*
G02X1244638Y1681456I2002J237D01*
G02X1244652Y1681693I2016J0D01*
G01Y1685943D01*
G02X1244638Y1686180I2002J237D01*
G02X1244652Y1686417I2016J0D01*
G01Y1688821D01*
G02X1244954Y1689124I302J1D01*
G37*
G36*
G01X1260702D02*
X1264402D01*
G02X1264704Y1688821I-1J-303D01*
G01Y1678815D01*
G02X1264402Y1678512I-302J-1D01*
G01X1260702D01*
G02X1260400Y1678815I1J303D01*
G01Y1681219D01*
G02X1260386Y1681456I2002J237D01*
G02X1260400Y1681693I2016J0D01*
G01Y1685943D01*
G02X1260386Y1686180I2002J237D01*
G02X1260400Y1686417I2016J0D01*
G01Y1688821D01*
G02X1260702Y1689124I302J1D01*
G37*
G36*
G01X1276450D02*
X1280150D01*
G02X1280452Y1688821I-1J-303D01*
G01Y1678815D01*
G02X1280150Y1678512I-302J-1D01*
G01X1276450D01*
G02X1276148Y1678815I1J303D01*
G01Y1681219D01*
G02X1276134Y1681456I2002J237D01*
G02X1276148Y1681693I2016J0D01*
G01Y1685943D01*
G02X1276134Y1686180I2002J237D01*
G02X1276148Y1686417I2016J0D01*
G01Y1688821D01*
G02X1276450Y1689124I302J1D01*
G37*
G36*
G01X1292198D02*
X1295898D01*
G02X1296200Y1688821I-1J-303D01*
G01Y1678815D01*
G02X1295898Y1678512I-302J-1D01*
G01X1292198D01*
G02X1291896Y1678815I1J303D01*
G01Y1681219D01*
G02X1291882Y1681456I2002J237D01*
G02X1291896Y1681693I2016J0D01*
G01Y1685943D01*
G02X1291882Y1686180I2002J237D01*
G02X1291896Y1686417I2016J0D01*
G01Y1688821D01*
G02X1292198Y1689124I302J1D01*
G37*
G36*
G01X1311883D02*
X1315583D01*
G02X1315886Y1688821I0J-303D01*
G01Y1678815D01*
G02X1315583Y1678512I-303J0D01*
G01X1311883D01*
G02X1311580Y1678815I0J303D01*
G01Y1681227D01*
G02X1311567Y1681456I2003J229D01*
G02X1311580Y1681685I2016J0D01*
G01Y1685951D01*
G02X1311567Y1686180I2003J229D01*
G02X1311580Y1686409I2016J0D01*
G01Y1688821D01*
G02X1311883Y1689124I303J0D01*
G37*
G36*
G01X1327631D02*
X1331331D01*
G02X1331634Y1688821I0J-303D01*
G01Y1678815D01*
G02X1331331Y1678512I-303J0D01*
G01X1327631D01*
G02X1327328Y1678815I0J303D01*
G01Y1681227D01*
G02X1327315Y1681456I2003J229D01*
G02X1327328Y1681685I2016J0D01*
G01Y1685951D01*
G02X1327315Y1686180I2003J229D01*
G02X1327328Y1686409I2016J0D01*
G01Y1688821D01*
G02X1327631Y1689124I303J0D01*
G37*
G36*
G01X1343379D02*
X1347079D01*
G02X1347382Y1688821I0J-303D01*
G01Y1678815D01*
G02X1347079Y1678512I-303J0D01*
G01X1343379D01*
G02X1343076Y1678815I0J303D01*
G01Y1681227D01*
G02X1343063Y1681456I2003J229D01*
G02X1343076Y1681685I2016J0D01*
G01Y1685951D01*
G02X1343063Y1686180I2003J229D01*
G02X1343076Y1686409I2016J0D01*
G01Y1688821D01*
G02X1343379Y1689124I303J0D01*
G37*
G36*
G01X1359127D02*
X1362827D01*
G02X1363130Y1688821I0J-303D01*
G01Y1678815D01*
G02X1362827Y1678512I-303J0D01*
G01X1359127D01*
G02X1358824Y1678815I0J303D01*
G01Y1681227D01*
G02X1358811Y1681456I2003J229D01*
G02X1358824Y1681685I2016J0D01*
G01Y1685951D01*
G02X1358811Y1686180I2003J229D01*
G02X1358824Y1686409I2016J0D01*
G01Y1688821D01*
G02X1359127Y1689124I303J0D01*
G37*
G36*
G01X1509127D02*
X1512827D01*
G02X1513130Y1688821I0J-303D01*
G01Y1678815D01*
G02X1512827Y1678512I-303J0D01*
G01X1509127D01*
G02X1508824Y1678815I0J303D01*
G01Y1680849D01*
G02X1508734Y1681456I2002J607D01*
G02X1509456Y1683038I2094J0D01*
G01X1509775Y1683688D01*
G03Y1683950I-267J131D01*
G01X1509458Y1684597D01*
G02X1508734Y1686180I1369J1583D01*
G02X1508824Y1686787I2092J0D01*
G01Y1688821D01*
G02X1509127Y1689124I303J0D01*
G37*
G36*
G01X1524875D02*
X1528575D01*
G02X1528878Y1688821I0J-303D01*
G01Y1678815D01*
G02X1528575Y1678512I-303J0D01*
G01X1524875D01*
G02X1524572Y1678815I0J303D01*
G01Y1680849D01*
G02X1524482Y1681456I2002J607D01*
G02X1525204Y1683038I2094J0D01*
G01X1525523Y1683688D01*
G03Y1683950I-267J131D01*
G01X1525206Y1684597D01*
G02X1524482Y1686180I1369J1583D01*
G02X1524572Y1686787I2092J0D01*
G01Y1688821D01*
G02X1524875Y1689124I303J0D01*
G37*
G36*
G01X1540623D02*
X1544323D01*
G02X1544626Y1688821I0J-303D01*
G01Y1678815D01*
G02X1544323Y1678512I-303J0D01*
G01X1540623D01*
G02X1540320Y1678815I0J303D01*
G01Y1680849D01*
G02X1540230Y1681456I2002J607D01*
G02X1540952Y1683038I2094J0D01*
G01X1541271Y1683688D01*
G03Y1683950I-267J131D01*
G01X1540954Y1684597D01*
G02X1540230Y1686180I1369J1583D01*
G02X1540320Y1686787I2092J0D01*
G01Y1688821D01*
G02X1540623Y1689124I303J0D01*
G37*
G36*
G01X1556371D02*
X1560071D01*
G02X1560374Y1688821I0J-303D01*
G01Y1678815D01*
G02X1560071Y1678512I-303J0D01*
G01X1556371D01*
G02X1556068Y1678815I0J303D01*
G01Y1680849D01*
G02X1555978Y1681456I2002J607D01*
G02X1556700Y1683038I2094J0D01*
G01X1557019Y1683688D01*
G03Y1683950I-267J131D01*
G01X1556702Y1684597D01*
G02X1555978Y1686180I1369J1583D01*
G02X1556068Y1686787I2092J0D01*
G01Y1688821D01*
G02X1556371Y1689124I303J0D01*
G37*
G36*
G01X1576056D02*
X1579756D01*
G02X1580058Y1688821I-1J-303D01*
G01Y1678815D01*
G02X1579756Y1678512I-302J-1D01*
G01X1576056D01*
G02X1575754Y1678815I1J303D01*
G01Y1680846D01*
G02X1575663Y1681456I2002J610D01*
G02X1576385Y1683038I2094J0D01*
G01X1576704Y1683688D01*
G03Y1683950I-267J131D01*
G01X1576387Y1684597D01*
G02X1575663Y1686180I1369J1583D01*
G02X1575754Y1686790I2093J0D01*
G01Y1688821D01*
G02X1576056Y1689124I302J1D01*
G37*
G36*
G01X1591804D02*
X1595504D01*
G02X1595806Y1688821I-1J-303D01*
G01Y1678815D01*
G02X1595504Y1678512I-302J-1D01*
G01X1591804D01*
G02X1591502Y1678815I1J303D01*
G01Y1680846D01*
G02X1591411Y1681456I2002J610D01*
G02X1592133Y1683038I2094J0D01*
G01X1592452Y1683688D01*
G03Y1683950I-267J131D01*
G01X1592135Y1684597D01*
G02X1591411Y1686180I1369J1583D01*
G02X1591502Y1686790I2093J0D01*
G01Y1688821D01*
G02X1591804Y1689124I302J1D01*
G37*
G36*
G01X1607552D02*
X1611252D01*
G02X1611554Y1688821I-1J-303D01*
G01Y1678815D01*
G02X1611252Y1678512I-302J-1D01*
G01X1607552D01*
G02X1607250Y1678815I1J303D01*
G01Y1680846D01*
G02X1607159Y1681456I2002J610D01*
G02X1607881Y1683038I2094J0D01*
G01X1608200Y1683688D01*
G03Y1683950I-267J131D01*
G01X1607883Y1684597D01*
G02X1607159Y1686180I1369J1583D01*
G02X1607250Y1686790I2093J0D01*
G01Y1688821D01*
G02X1607552Y1689124I302J1D01*
G37*
G36*
G01X1623300D02*
X1627000D01*
G02X1627302Y1688821I-1J-303D01*
G01Y1678815D01*
G02X1627000Y1678512I-302J-1D01*
G01X1623300D01*
G02X1622998Y1678815I1J303D01*
G01Y1680846D01*
G02X1622907Y1681456I2002J610D01*
G02X1623629Y1683038I2094J0D01*
G01X1623948Y1683688D01*
G03Y1683950I-267J131D01*
G01X1623631Y1684597D01*
G02X1622907Y1686180I1369J1583D01*
G02X1622998Y1686790I2093J0D01*
G01Y1688821D01*
G02X1623300Y1689124I302J1D01*
G37*
G36*
G01X229206Y1699360D02*
X232906D01*
G02X233208Y1699057I-1J-303D01*
G01Y1689051D01*
G02X232906Y1688748I-302J-1D01*
G01X229206D01*
G02X228904Y1689051I1J303D01*
G01Y1691082D01*
G02X228813Y1691692I2002J610D01*
G02X229535Y1693274I2094J0D01*
G01X229854Y1693924D01*
G03Y1694186I-267J131D01*
G01X229536Y1694835D01*
G02X228813Y1696417I1369J1582D01*
G02X228904Y1697027I2093J0D01*
G01Y1699057D01*
G02X229206Y1699360I302J1D01*
G37*
G36*
G01X244954D02*
X248654D01*
G02X248956Y1699057I-1J-303D01*
G01Y1689051D01*
G02X248654Y1688748I-302J-1D01*
G01X244954D01*
G02X244652Y1689051I1J303D01*
G01Y1691082D01*
G02X244561Y1691692I2002J610D01*
G02X245283Y1693274I2094J0D01*
G01X245602Y1693924D01*
G03Y1694186I-267J131D01*
G01X245284Y1694835D01*
G02X244561Y1696417I1369J1582D01*
G02X244652Y1697027I2093J0D01*
G01Y1699057D01*
G02X244954Y1699360I302J1D01*
G37*
G36*
G01X260702D02*
X264402D01*
G02X264704Y1699057I-1J-303D01*
G01Y1689051D01*
G02X264402Y1688748I-302J-1D01*
G01X260702D01*
G02X260400Y1689051I1J303D01*
G01Y1691082D01*
G02X260309Y1691692I2002J610D01*
G02X261031Y1693274I2094J0D01*
G01X261350Y1693924D01*
G03Y1694186I-267J131D01*
G01X261032Y1694835D01*
G02X260309Y1696417I1369J1582D01*
G02X260400Y1697027I2093J0D01*
G01Y1699057D01*
G02X260702Y1699360I302J1D01*
G37*
G36*
G01X276450D02*
X280150D01*
G02X280452Y1699057I-1J-303D01*
G01Y1689051D01*
G02X280150Y1688748I-302J-1D01*
G01X276450D01*
G02X276148Y1689051I1J303D01*
G01Y1691082D01*
G02X276057Y1691692I2002J610D01*
G02X276779Y1693274I2094J0D01*
G01X277098Y1693924D01*
G03Y1694186I-267J131D01*
G01X276780Y1694835D01*
G02X276057Y1696417I1369J1582D01*
G02X276148Y1697027I2093J0D01*
G01Y1699057D01*
G02X276450Y1699360I302J1D01*
G37*
G36*
G01X296135D02*
X299835D01*
G02X300138Y1699057I0J-303D01*
G01Y1689051D01*
G02X299835Y1688748I-303J0D01*
G01X296135D01*
G02X295832Y1689051I0J303D01*
G01Y1691085D01*
G02X295742Y1691692I2002J607D01*
G02X296464Y1693274I2094J0D01*
G01X296783Y1693924D01*
G03Y1694186I-267J131D01*
G01X296465Y1694835D01*
G02X295742Y1696417I1369J1582D01*
G02X295832Y1697024I2092J0D01*
G01Y1699057D01*
G02X296135Y1699360I303J0D01*
G37*
G36*
G01X311883D02*
X315583D01*
G02X315886Y1699057I0J-303D01*
G01Y1689051D01*
G02X315583Y1688748I-303J0D01*
G01X311883D01*
G02X311580Y1689051I0J303D01*
G01Y1691085D01*
G02X311490Y1691692I2002J607D01*
G02X312212Y1693274I2094J0D01*
G01X312531Y1693924D01*
G03Y1694186I-267J131D01*
G01X312213Y1694835D01*
G02X311490Y1696417I1369J1582D01*
G02X311580Y1697024I2092J0D01*
G01Y1699057D01*
G02X311883Y1699360I303J0D01*
G37*
G36*
G01X327631D02*
X331331D01*
G02X331634Y1699057I0J-303D01*
G01Y1689051D01*
G02X331331Y1688748I-303J0D01*
G01X327631D01*
G02X327328Y1689051I0J303D01*
G01Y1691085D01*
G02X327238Y1691692I2002J607D01*
G02X327960Y1693274I2094J0D01*
G01X328279Y1693924D01*
G03Y1694186I-267J131D01*
G01X327961Y1694835D01*
G02X327238Y1696417I1369J1582D01*
G02X327328Y1697024I2092J0D01*
G01Y1699057D01*
G02X327631Y1699360I303J0D01*
G37*
G36*
G01X343379D02*
X347079D01*
G02X347382Y1699057I0J-303D01*
G01Y1689051D01*
G02X347079Y1688748I-303J0D01*
G01X343379D01*
G02X343076Y1689051I0J303D01*
G01Y1691085D01*
G02X342986Y1691692I2002J607D01*
G02X343708Y1693274I2094J0D01*
G01X344027Y1693924D01*
G03Y1694186I-267J131D01*
G01X343709Y1694835D01*
G02X342986Y1696417I1369J1582D01*
G02X343076Y1697024I2092J0D01*
G01Y1699057D01*
G02X343379Y1699360I303J0D01*
G37*
G36*
G01X493379D02*
X497079D01*
G02X497382Y1699057I0J-303D01*
G01Y1689051D01*
G02X497079Y1688748I-303J0D01*
G01X493379D01*
G02X493076Y1689051I0J303D01*
G01Y1691463D01*
G02X493063Y1691692I2003J229D01*
G02X493076Y1691921I2016J0D01*
G01Y1696188D01*
G02X493063Y1696417I2003J229D01*
G02X493076Y1696646I2016J0D01*
G01Y1699057D01*
G02X493379Y1699360I303J0D01*
G37*
G36*
G01X509127D02*
X512827D01*
G02X513130Y1699057I0J-303D01*
G01Y1689051D01*
G02X512827Y1688748I-303J0D01*
G01X509127D01*
G02X508824Y1689051I0J303D01*
G01Y1691463D01*
G02X508811Y1691692I2003J229D01*
G02X508824Y1691921I2016J0D01*
G01Y1696188D01*
G02X508811Y1696417I2003J229D01*
G02X508824Y1696646I2016J0D01*
G01Y1699057D01*
G02X509127Y1699360I303J0D01*
G37*
G36*
G01X524875D02*
X528575D01*
G02X528878Y1699057I0J-303D01*
G01Y1689051D01*
G02X528575Y1688748I-303J0D01*
G01X524875D01*
G02X524572Y1689051I0J303D01*
G01Y1691463D01*
G02X524559Y1691692I2003J229D01*
G02X524572Y1691921I2016J0D01*
G01Y1696188D01*
G02X524559Y1696417I2003J229D01*
G02X524572Y1696646I2016J0D01*
G01Y1699057D01*
G02X524875Y1699360I303J0D01*
G37*
G36*
G01X540623D02*
X544323D01*
G02X544626Y1699057I0J-303D01*
G01Y1689051D01*
G02X544323Y1688748I-303J0D01*
G01X540623D01*
G02X540320Y1689051I0J303D01*
G01Y1691463D01*
G02X540307Y1691692I2003J229D01*
G02X540320Y1691921I2016J0D01*
G01Y1696188D01*
G02X540307Y1696417I2003J229D01*
G02X540320Y1696646I2016J0D01*
G01Y1699057D01*
G02X540623Y1699360I303J0D01*
G37*
G36*
G01X560308D02*
X564008D01*
G02X564310Y1699057I-1J-303D01*
G01Y1689051D01*
G02X564008Y1688748I-302J-1D01*
G01X560308D01*
G02X560006Y1689051I1J303D01*
G01Y1691455D01*
G02X559992Y1691692I2002J237D01*
G02X560006Y1691929I2016J0D01*
G01Y1696180D01*
G02X559992Y1696417I2002J237D01*
G02X560006Y1696654I2016J0D01*
G01Y1699057D01*
G02X560308Y1699360I302J1D01*
G37*
G36*
G01X576056D02*
X579756D01*
G02X580058Y1699057I-1J-303D01*
G01Y1689051D01*
G02X579756Y1688748I-302J-1D01*
G01X576056D01*
G02X575754Y1689051I1J303D01*
G01Y1691455D01*
G02X575740Y1691692I2002J237D01*
G02X575754Y1691929I2016J0D01*
G01Y1696180D01*
G02X575740Y1696417I2002J237D01*
G02X575754Y1696654I2016J0D01*
G01Y1699057D01*
G02X576056Y1699360I302J1D01*
G37*
G36*
G01X591804D02*
X595504D01*
G02X595806Y1699057I-1J-303D01*
G01Y1689051D01*
G02X595504Y1688748I-302J-1D01*
G01X591804D01*
G02X591502Y1689051I1J303D01*
G01Y1691455D01*
G02X591488Y1691692I2002J237D01*
G02X591502Y1691929I2016J0D01*
G01Y1696180D01*
G02X591488Y1696417I2002J237D01*
G02X591502Y1696654I2016J0D01*
G01Y1699057D01*
G02X591804Y1699360I302J1D01*
G37*
G36*
G01X607552D02*
X611252D01*
G02X611554Y1699057I-1J-303D01*
G01Y1689051D01*
G02X611252Y1688748I-302J-1D01*
G01X607552D01*
G02X607250Y1689051I1J303D01*
G01Y1691455D01*
G02X607236Y1691692I2002J237D01*
G02X607250Y1691929I2016J0D01*
G01Y1696180D01*
G02X607236Y1696417I2002J237D01*
G02X607250Y1696654I2016J0D01*
G01Y1699057D01*
G02X607552Y1699360I302J1D01*
G37*
G36*
G01X1237080D02*
X1240780D01*
G02X1241082Y1699057I-1J-303D01*
G01Y1689051D01*
G02X1240780Y1688748I-302J-1D01*
G01X1237080D01*
G02X1236778Y1689051I1J303D01*
G01Y1691082D01*
G02X1236687Y1691692I2002J610D01*
G02X1237409Y1693274I2094J0D01*
G01X1237728Y1693924D01*
G03Y1694186I-267J131D01*
G01X1237410Y1694835D01*
G02X1236687Y1696417I1369J1582D01*
G02X1236778Y1697027I2093J0D01*
G01Y1699057D01*
G02X1237080Y1699360I302J1D01*
G37*
G36*
G01X1252828D02*
X1256528D01*
G02X1256830Y1699057I-1J-303D01*
G01Y1689051D01*
G02X1256528Y1688748I-302J-1D01*
G01X1252828D01*
G02X1252526Y1689051I1J303D01*
G01Y1691082D01*
G02X1252435Y1691692I2002J610D01*
G02X1253157Y1693274I2094J0D01*
G01X1253476Y1693924D01*
G03Y1694186I-267J131D01*
G01X1253158Y1694835D01*
G02X1252435Y1696417I1369J1582D01*
G02X1252526Y1697027I2093J0D01*
G01Y1699057D01*
G02X1252828Y1699360I302J1D01*
G37*
G36*
G01X1268576D02*
X1272276D01*
G02X1272578Y1699057I-1J-303D01*
G01Y1689051D01*
G02X1272276Y1688748I-302J-1D01*
G01X1268576D01*
G02X1268274Y1689051I1J303D01*
G01Y1691082D01*
G02X1268183Y1691692I2002J610D01*
G02X1268905Y1693274I2094J0D01*
G01X1269224Y1693924D01*
G03Y1694186I-267J131D01*
G01X1268906Y1694835D01*
G02X1268183Y1696417I1369J1582D01*
G02X1268274Y1697027I2093J0D01*
G01Y1699057D01*
G02X1268576Y1699360I302J1D01*
G37*
G36*
G01X1284324D02*
X1288024D01*
G02X1288326Y1699057I-1J-303D01*
G01Y1689051D01*
G02X1288024Y1688748I-302J-1D01*
G01X1284324D01*
G02X1284022Y1689051I1J303D01*
G01Y1691082D01*
G02X1283931Y1691692I2002J610D01*
G02X1284653Y1693274I2094J0D01*
G01X1284972Y1693924D01*
G03Y1694186I-267J131D01*
G01X1284654Y1694835D01*
G02X1283931Y1696417I1369J1582D01*
G02X1284022Y1697027I2093J0D01*
G01Y1699057D01*
G02X1284324Y1699360I302J1D01*
G37*
G36*
G01X1304009D02*
X1307709D01*
G02X1308012Y1699057I0J-303D01*
G01Y1689051D01*
G02X1307709Y1688748I-303J0D01*
G01X1304009D01*
G02X1303706Y1689051I0J303D01*
G01Y1691085D01*
G02X1303616Y1691692I2002J607D01*
G02X1304338Y1693274I2094J0D01*
G01X1304657Y1693924D01*
G03Y1694186I-267J131D01*
G01X1304339Y1694835D01*
G02X1303616Y1696417I1369J1582D01*
G02X1303706Y1697024I2092J0D01*
G01Y1699057D01*
G02X1304009Y1699360I303J0D01*
G37*
G36*
G01X1319757D02*
X1323457D01*
G02X1323760Y1699057I0J-303D01*
G01Y1689051D01*
G02X1323457Y1688748I-303J0D01*
G01X1319757D01*
G02X1319454Y1689051I0J303D01*
G01Y1691085D01*
G02X1319364Y1691692I2002J607D01*
G02X1320086Y1693274I2094J0D01*
G01X1320405Y1693924D01*
G03Y1694186I-267J131D01*
G01X1320087Y1694835D01*
G02X1319364Y1696417I1369J1582D01*
G02X1319454Y1697024I2092J0D01*
G01Y1699057D01*
G02X1319757Y1699360I303J0D01*
G37*
G36*
G01X1335505D02*
X1339205D01*
G02X1339508Y1699057I0J-303D01*
G01Y1689051D01*
G02X1339205Y1688748I-303J0D01*
G01X1335505D01*
G02X1335202Y1689051I0J303D01*
G01Y1691085D01*
G02X1335112Y1691692I2002J607D01*
G02X1335834Y1693274I2094J0D01*
G01X1336153Y1693924D01*
G03Y1694186I-267J131D01*
G01X1335835Y1694835D01*
G02X1335112Y1696417I1369J1582D01*
G02X1335202Y1697024I2092J0D01*
G01Y1699057D01*
G02X1335505Y1699360I303J0D01*
G37*
G36*
G01X1351253D02*
X1354953D01*
G02X1355256Y1699057I0J-303D01*
G01Y1689051D01*
G02X1354953Y1688748I-303J0D01*
G01X1351253D01*
G02X1350950Y1689051I0J303D01*
G01Y1691085D01*
G02X1350860Y1691692I2002J607D01*
G02X1351582Y1693274I2094J0D01*
G01X1351901Y1693924D01*
G03Y1694186I-267J131D01*
G01X1351583Y1694835D01*
G02X1350860Y1696417I1369J1582D01*
G02X1350950Y1697024I2092J0D01*
G01Y1699057D01*
G02X1351253Y1699360I303J0D01*
G37*
G36*
G01X1501253D02*
X1504953D01*
G02X1505256Y1699057I0J-303D01*
G01Y1689051D01*
G02X1504953Y1688748I-303J0D01*
G01X1501253D01*
G02X1500950Y1689051I0J303D01*
G01Y1691463D01*
G02X1500937Y1691692I2003J229D01*
G02X1500950Y1691921I2016J0D01*
G01Y1696188D01*
G02X1500937Y1696417I2003J229D01*
G02X1500950Y1696646I2016J0D01*
G01Y1699057D01*
G02X1501253Y1699360I303J0D01*
G37*
G36*
G01X1517001D02*
X1520701D01*
G02X1521004Y1699057I0J-303D01*
G01Y1689051D01*
G02X1520701Y1688748I-303J0D01*
G01X1517001D01*
G02X1516698Y1689051I0J303D01*
G01Y1691463D01*
G02X1516685Y1691692I2003J229D01*
G02X1516698Y1691921I2016J0D01*
G01Y1696188D01*
G02X1516685Y1696417I2003J229D01*
G02X1516698Y1696646I2016J0D01*
G01Y1699057D01*
G02X1517001Y1699360I303J0D01*
G37*
G36*
G01X1532749D02*
X1536449D01*
G02X1536752Y1699057I0J-303D01*
G01Y1689051D01*
G02X1536449Y1688748I-303J0D01*
G01X1532749D01*
G02X1532446Y1689051I0J303D01*
G01Y1691463D01*
G02X1532433Y1691692I2003J229D01*
G02X1532446Y1691921I2016J0D01*
G01Y1696188D01*
G02X1532433Y1696417I2003J229D01*
G02X1532446Y1696646I2016J0D01*
G01Y1699057D01*
G02X1532749Y1699360I303J0D01*
G37*
G36*
G01X1548497D02*
X1552197D01*
G02X1552500Y1699057I0J-303D01*
G01Y1689051D01*
G02X1552197Y1688748I-303J0D01*
G01X1548497D01*
G02X1548194Y1689051I0J303D01*
G01Y1691463D01*
G02X1548181Y1691692I2003J229D01*
G02X1548194Y1691921I2016J0D01*
G01Y1696188D01*
G02X1548181Y1696417I2003J229D01*
G02X1548194Y1696646I2016J0D01*
G01Y1699057D01*
G02X1548497Y1699360I303J0D01*
G37*
G36*
G01X1568182D02*
X1571882D01*
G02X1572184Y1699057I-1J-303D01*
G01Y1689051D01*
G02X1571882Y1688748I-302J-1D01*
G01X1568182D01*
G02X1567880Y1689051I1J303D01*
G01Y1691455D01*
G02X1567866Y1691692I2002J237D01*
G02X1567880Y1691929I2016J0D01*
G01Y1696180D01*
G02X1567866Y1696417I2002J237D01*
G02X1567880Y1696654I2016J0D01*
G01Y1699057D01*
G02X1568182Y1699360I302J1D01*
G37*
G36*
G01X1583930D02*
X1587630D01*
G02X1587932Y1699057I-1J-303D01*
G01Y1689051D01*
G02X1587630Y1688748I-302J-1D01*
G01X1583930D01*
G02X1583628Y1689051I1J303D01*
G01Y1691455D01*
G02X1583614Y1691692I2002J237D01*
G02X1583628Y1691929I2016J0D01*
G01Y1696180D01*
G02X1583614Y1696417I2002J237D01*
G02X1583628Y1696654I2016J0D01*
G01Y1699057D01*
G02X1583930Y1699360I302J1D01*
G37*
G36*
G01X1599678D02*
X1603378D01*
G02X1603680Y1699057I-1J-303D01*
G01Y1689051D01*
G02X1603378Y1688748I-302J-1D01*
G01X1599678D01*
G02X1599376Y1689051I1J303D01*
G01Y1691455D01*
G02X1599362Y1691692I2002J237D01*
G02X1599376Y1691929I2016J0D01*
G01Y1696180D01*
G02X1599362Y1696417I2002J237D01*
G02X1599376Y1696654I2016J0D01*
G01Y1699057D01*
G02X1599678Y1699360I302J1D01*
G37*
G36*
G01X1615426D02*
X1619126D01*
G02X1619428Y1699057I-1J-303D01*
G01Y1689051D01*
G02X1619126Y1688748I-302J-1D01*
G01X1615426D01*
G02X1615124Y1689051I1J303D01*
G01Y1691455D01*
G02X1615110Y1691692I2002J237D01*
G02X1615124Y1691929I2016J0D01*
G01Y1696180D01*
G02X1615110Y1696417I2002J237D01*
G02X1615124Y1696654I2016J0D01*
G01Y1699057D01*
G02X1615426Y1699360I302J1D01*
G37*
G36*
G01X237080Y1703296D02*
X240780D01*
G02X241082Y1702994I0J-302D01*
G01Y1692988D01*
G02X240780Y1692686I-302J0D01*
G01X237080D01*
G02X236778Y1692988I0J302D01*
G01Y1695019D01*
G02X236687Y1695629I2002J610D01*
G02X237409Y1697211I2094J0D01*
G01X237728Y1697861D01*
G03Y1698123I-267J131D01*
G01X237410Y1698772D01*
G02X236687Y1700354I1369J1582D01*
G02X236778Y1700964I2093J0D01*
G01Y1702994D01*
G02X237080Y1703296I302J0D01*
G37*
G36*
G01X252828D02*
X256528D01*
G02X256830Y1702994I0J-302D01*
G01Y1692988D01*
G02X256528Y1692686I-302J0D01*
G01X252828D01*
G02X252526Y1692988I0J302D01*
G01Y1695019D01*
G02X252435Y1695629I2002J610D01*
G02X253157Y1697211I2094J0D01*
G01X253476Y1697861D01*
G03Y1698123I-267J131D01*
G01X253158Y1698772D01*
G02X252435Y1700354I1369J1582D01*
G02X252526Y1700964I2093J0D01*
G01Y1702994D01*
G02X252828Y1703296I302J0D01*
G37*
G36*
G01X268576D02*
X272276D01*
G02X272578Y1702994I0J-302D01*
G01Y1692988D01*
G02X272276Y1692686I-302J0D01*
G01X268576D01*
G02X268274Y1692988I0J302D01*
G01Y1695019D01*
G02X268183Y1695629I2002J610D01*
G02X268905Y1697211I2094J0D01*
G01X269224Y1697861D01*
G03Y1698123I-267J131D01*
G01X268906Y1698772D01*
G02X268183Y1700354I1369J1582D01*
G02X268274Y1700964I2093J0D01*
G01Y1702994D01*
G02X268576Y1703296I302J0D01*
G37*
G36*
G01X284324D02*
X288024D01*
G02X288326Y1702994I0J-302D01*
G01Y1692988D01*
G02X288024Y1692686I-302J0D01*
G01X284324D01*
G02X284022Y1692988I0J302D01*
G01Y1695019D01*
G02X283931Y1695629I2002J610D01*
G02X284653Y1697211I2094J0D01*
G01X284972Y1697861D01*
G03Y1698123I-267J131D01*
G01X284654Y1698772D01*
G02X283931Y1700354I1369J1582D01*
G02X284022Y1700964I2093J0D01*
G01Y1702994D01*
G02X284324Y1703296I302J0D01*
G37*
G36*
G01X568182D02*
X571882D01*
G02X572184Y1702994I0J-302D01*
G01Y1692988D01*
G02X571882Y1692686I-302J0D01*
G01X568182D01*
G02X567880Y1692988I0J302D01*
G01Y1695392D01*
G02X567866Y1695629I2002J237D01*
G02X567880Y1695866I2016J0D01*
G01Y1700117D01*
G02X567866Y1700354I2002J237D01*
G02X567880Y1700591I2016J0D01*
G01Y1702994D01*
G02X568182Y1703296I302J0D01*
G37*
G36*
G01X583930D02*
X587630D01*
G02X587932Y1702994I0J-302D01*
G01Y1692988D01*
G02X587630Y1692686I-302J0D01*
G01X583930D01*
G02X583628Y1692988I0J302D01*
G01Y1695392D01*
G02X583614Y1695629I2002J237D01*
G02X583628Y1695866I2016J0D01*
G01Y1700117D01*
G02X583614Y1700354I2002J237D01*
G02X583628Y1700591I2016J0D01*
G01Y1702994D01*
G02X583930Y1703296I302J0D01*
G37*
G36*
G01X599678D02*
X603378D01*
G02X603680Y1702994I0J-302D01*
G01Y1692988D01*
G02X603378Y1692686I-302J0D01*
G01X599678D01*
G02X599376Y1692988I0J302D01*
G01Y1695392D01*
G02X599362Y1695629I2002J237D01*
G02X599376Y1695866I2016J0D01*
G01Y1700117D01*
G02X599362Y1700354I2002J237D01*
G02X599376Y1700591I2016J0D01*
G01Y1702994D01*
G02X599678Y1703296I302J0D01*
G37*
G36*
G01X615426D02*
X619126D01*
G02X619428Y1702994I0J-302D01*
G01Y1692988D01*
G02X619126Y1692686I-302J0D01*
G01X615426D01*
G02X615124Y1692988I0J302D01*
G01Y1695392D01*
G02X615110Y1695629I2002J237D01*
G02X615124Y1695866I2016J0D01*
G01Y1700117D01*
G02X615110Y1700354I2002J237D01*
G02X615124Y1700591I2016J0D01*
G01Y1702994D01*
G02X615426Y1703296I302J0D01*
G37*
G36*
G01X1244954D02*
X1248654D01*
G02X1248956Y1702994I0J-302D01*
G01Y1692988D01*
G02X1248654Y1692686I-302J0D01*
G01X1244954D01*
G02X1244652Y1692988I0J302D01*
G01Y1695019D01*
G02X1244561Y1695629I2002J610D01*
G02X1245283Y1697211I2094J0D01*
G01X1245602Y1697861D01*
G03Y1698123I-267J131D01*
G01X1245284Y1698772D01*
G02X1244561Y1700354I1369J1582D01*
G02X1244652Y1700964I2093J0D01*
G01Y1702994D01*
G02X1244954Y1703296I302J0D01*
G37*
G36*
G01X1260702D02*
X1264402D01*
G02X1264704Y1702994I0J-302D01*
G01Y1692988D01*
G02X1264402Y1692686I-302J0D01*
G01X1260702D01*
G02X1260400Y1692988I0J302D01*
G01Y1695019D01*
G02X1260309Y1695629I2002J610D01*
G02X1261031Y1697211I2094J0D01*
G01X1261350Y1697861D01*
G03Y1698123I-267J131D01*
G01X1261032Y1698772D01*
G02X1260309Y1700354I1369J1582D01*
G02X1260400Y1700964I2093J0D01*
G01Y1702994D01*
G02X1260702Y1703296I302J0D01*
G37*
G36*
G01X1276450D02*
X1280150D01*
G02X1280452Y1702994I0J-302D01*
G01Y1692988D01*
G02X1280150Y1692686I-302J0D01*
G01X1276450D01*
G02X1276148Y1692988I0J302D01*
G01Y1695019D01*
G02X1276057Y1695629I2002J610D01*
G02X1276779Y1697211I2094J0D01*
G01X1277098Y1697861D01*
G03Y1698123I-267J131D01*
G01X1276780Y1698772D01*
G02X1276057Y1700354I1369J1582D01*
G02X1276148Y1700964I2093J0D01*
G01Y1702994D01*
G02X1276450Y1703296I302J0D01*
G37*
G36*
G01X1292198D02*
X1295898D01*
G02X1296200Y1702994I0J-302D01*
G01Y1692988D01*
G02X1295898Y1692686I-302J0D01*
G01X1292198D01*
G02X1291896Y1692988I0J302D01*
G01Y1695019D01*
G02X1291805Y1695629I2002J610D01*
G02X1292527Y1697211I2094J0D01*
G01X1292846Y1697861D01*
G03Y1698123I-267J131D01*
G01X1292528Y1698772D01*
G02X1291805Y1700354I1369J1582D01*
G02X1291896Y1700964I2093J0D01*
G01Y1702994D01*
G02X1292198Y1703296I302J0D01*
G37*
G36*
G01X1576056D02*
X1579756D01*
G02X1580058Y1702994I0J-302D01*
G01Y1692988D01*
G02X1579756Y1692686I-302J0D01*
G01X1576056D01*
G02X1575754Y1692988I0J302D01*
G01Y1695392D01*
G02X1575740Y1695629I2002J237D01*
G02X1575754Y1695866I2016J0D01*
G01Y1700117D01*
G02X1575740Y1700354I2002J237D01*
G02X1575754Y1700591I2016J0D01*
G01Y1702994D01*
G02X1576056Y1703296I302J0D01*
G37*
G36*
G01X1591804D02*
X1595504D01*
G02X1595806Y1702994I0J-302D01*
G01Y1692988D01*
G02X1595504Y1692686I-302J0D01*
G01X1591804D01*
G02X1591502Y1692988I0J302D01*
G01Y1695392D01*
G02X1591488Y1695629I2002J237D01*
G02X1591502Y1695866I2016J0D01*
G01Y1700117D01*
G02X1591488Y1700354I2002J237D01*
G02X1591502Y1700591I2016J0D01*
G01Y1702994D01*
G02X1591804Y1703296I302J0D01*
G37*
G36*
G01X1607552D02*
X1611252D01*
G02X1611554Y1702994I0J-302D01*
G01Y1692988D01*
G02X1611252Y1692686I-302J0D01*
G01X1607552D01*
G02X1607250Y1692988I0J302D01*
G01Y1695392D01*
G02X1607236Y1695629I2002J237D01*
G02X1607250Y1695866I2016J0D01*
G01Y1700117D01*
G02X1607236Y1700354I2002J237D01*
G02X1607250Y1700591I2016J0D01*
G01Y1702994D01*
G02X1607552Y1703296I302J0D01*
G37*
G36*
G01X1623300D02*
X1627000D01*
G02X1627302Y1702994I0J-302D01*
G01Y1692988D01*
G02X1627000Y1692686I-302J0D01*
G01X1623300D01*
G02X1622998Y1692988I0J302D01*
G01Y1695392D01*
G02X1622984Y1695629I2002J237D01*
G02X1622998Y1695866I2016J0D01*
G01Y1700117D01*
G02X1622984Y1700354I2002J237D01*
G02X1622998Y1700591I2016J0D01*
G01Y1702994D01*
G02X1623300Y1703296I302J0D01*
G37*
G36*
G01X304009D02*
X307709D01*
G02X308012Y1702994I1J-302D01*
G01Y1692988D01*
G02X307709Y1692686I-303J1D01*
G01X304009D01*
G02X303706Y1692988I-1J302D01*
G01Y1695022D01*
G02X303616Y1695629I2002J607D01*
G02X304338Y1697211I2094J0D01*
G01X304657Y1697861D01*
G03Y1698123I-267J131D01*
G01X304339Y1698772D01*
G02X303616Y1700354I1369J1582D01*
G02X303706Y1700961I2092J0D01*
G01Y1702994D01*
G02X304009Y1703296I303J-1D01*
G37*
G36*
G01X319757D02*
X323457D01*
G02X323760Y1702994I1J-302D01*
G01Y1692988D01*
G02X323457Y1692686I-303J1D01*
G01X319757D01*
G02X319454Y1692988I-1J302D01*
G01Y1695022D01*
G02X319364Y1695629I2002J607D01*
G02X320086Y1697211I2094J0D01*
G01X320405Y1697861D01*
G03Y1698123I-267J131D01*
G01X320087Y1698772D01*
G02X319364Y1700354I1369J1582D01*
G02X319454Y1700961I2092J0D01*
G01Y1702994D01*
G02X319757Y1703296I303J-1D01*
G37*
G36*
G01X335505D02*
X339205D01*
G02X339508Y1702994I1J-302D01*
G01Y1692988D01*
G02X339205Y1692686I-303J1D01*
G01X335505D01*
G02X335202Y1692988I-1J302D01*
G01Y1695022D01*
G02X335112Y1695629I2002J607D01*
G02X335834Y1697211I2094J0D01*
G01X336153Y1697861D01*
G03Y1698123I-267J131D01*
G01X335835Y1698772D01*
G02X335112Y1700354I1369J1582D01*
G02X335202Y1700961I2092J0D01*
G01Y1702994D01*
G02X335505Y1703296I303J-1D01*
G37*
G36*
G01X351253D02*
X354953D01*
G02X355256Y1702994I1J-302D01*
G01Y1692988D01*
G02X354953Y1692686I-303J1D01*
G01X351253D01*
G02X350950Y1692988I-1J302D01*
G01Y1695022D01*
G02X350860Y1695629I2002J607D01*
G02X351582Y1697211I2094J0D01*
G01X351901Y1697861D01*
G03Y1698123I-267J131D01*
G01X351583Y1698772D01*
G02X350860Y1700354I1369J1582D01*
G02X350950Y1700961I2092J0D01*
G01Y1702994D01*
G02X351253Y1703296I303J-1D01*
G37*
G36*
G01X501253D02*
X504953D01*
G02X505256Y1702994I1J-302D01*
G01Y1692988D01*
G02X504953Y1692686I-303J1D01*
G01X501253D01*
G02X500950Y1692988I-1J302D01*
G01Y1695400D01*
G02X500937Y1695629I2003J229D01*
G02X500950Y1695858I2016J0D01*
G01Y1700125D01*
G02X500937Y1700354I2003J229D01*
G02X500950Y1700583I2016J0D01*
G01Y1702994D01*
G02X501253Y1703296I303J-1D01*
G37*
G36*
G01X517001D02*
X520701D01*
G02X521004Y1702994I1J-302D01*
G01Y1692988D01*
G02X520701Y1692686I-303J1D01*
G01X517001D01*
G02X516698Y1692988I-1J302D01*
G01Y1695400D01*
G02X516685Y1695629I2003J229D01*
G02X516698Y1695858I2016J0D01*
G01Y1700125D01*
G02X516685Y1700354I2003J229D01*
G02X516698Y1700583I2016J0D01*
G01Y1702994D01*
G02X517001Y1703296I303J-1D01*
G37*
G36*
G01X532749D02*
X536449D01*
G02X536752Y1702994I1J-302D01*
G01Y1692988D01*
G02X536449Y1692686I-303J1D01*
G01X532749D01*
G02X532446Y1692988I-1J302D01*
G01Y1695400D01*
G02X532433Y1695629I2003J229D01*
G02X532446Y1695858I2016J0D01*
G01Y1700125D01*
G02X532433Y1700354I2003J229D01*
G02X532446Y1700583I2016J0D01*
G01Y1702994D01*
G02X532749Y1703296I303J-1D01*
G37*
G36*
G01X548497D02*
X552197D01*
G02X552500Y1702994I1J-302D01*
G01Y1692988D01*
G02X552197Y1692686I-303J1D01*
G01X548497D01*
G02X548194Y1692988I-1J302D01*
G01Y1695400D01*
G02X548181Y1695629I2003J229D01*
G02X548194Y1695858I2016J0D01*
G01Y1700125D01*
G02X548181Y1700354I2003J229D01*
G02X548194Y1700583I2016J0D01*
G01Y1702994D01*
G02X548497Y1703296I303J-1D01*
G37*
G36*
G01X1311883D02*
X1315583D01*
G02X1315886Y1702994I1J-302D01*
G01Y1692988D01*
G02X1315583Y1692686I-303J1D01*
G01X1311883D01*
G02X1311580Y1692988I-1J302D01*
G01Y1695022D01*
G02X1311490Y1695629I2002J607D01*
G02X1312212Y1697211I2094J0D01*
G01X1312531Y1697861D01*
G03Y1698123I-267J131D01*
G01X1312213Y1698772D01*
G02X1311490Y1700354I1369J1582D01*
G02X1311580Y1700961I2092J0D01*
G01Y1702994D01*
G02X1311883Y1703296I303J-1D01*
G37*
G36*
G01X1327631D02*
X1331331D01*
G02X1331634Y1702994I1J-302D01*
G01Y1692988D01*
G02X1331331Y1692686I-303J1D01*
G01X1327631D01*
G02X1327328Y1692988I-1J302D01*
G01Y1695022D01*
G02X1327238Y1695629I2002J607D01*
G02X1327960Y1697211I2094J0D01*
G01X1328279Y1697861D01*
G03Y1698123I-267J131D01*
G01X1327961Y1698772D01*
G02X1327238Y1700354I1369J1582D01*
G02X1327328Y1700961I2092J0D01*
G01Y1702994D01*
G02X1327631Y1703296I303J-1D01*
G37*
G36*
G01X1343379D02*
X1347079D01*
G02X1347382Y1702994I1J-302D01*
G01Y1692988D01*
G02X1347079Y1692686I-303J1D01*
G01X1343379D01*
G02X1343076Y1692988I-1J302D01*
G01Y1695022D01*
G02X1342986Y1695629I2002J607D01*
G02X1343708Y1697211I2094J0D01*
G01X1344027Y1697861D01*
G03Y1698123I-267J131D01*
G01X1343709Y1698772D01*
G02X1342986Y1700354I1369J1582D01*
G02X1343076Y1700961I2092J0D01*
G01Y1702994D01*
G02X1343379Y1703296I303J-1D01*
G37*
G36*
G01X1359127D02*
X1362827D01*
G02X1363130Y1702994I1J-302D01*
G01Y1692988D01*
G02X1362827Y1692686I-303J1D01*
G01X1359127D01*
G02X1358824Y1692988I-1J302D01*
G01Y1695022D01*
G02X1358734Y1695629I2002J607D01*
G02X1359456Y1697211I2094J0D01*
G01X1359775Y1697861D01*
G03Y1698123I-267J131D01*
G01X1359457Y1698772D01*
G02X1358734Y1700354I1369J1582D01*
G02X1358824Y1700961I2092J0D01*
G01Y1702994D01*
G02X1359127Y1703296I303J-1D01*
G37*
G36*
G01X1509127D02*
X1512827D01*
G02X1513130Y1702994I1J-302D01*
G01Y1692988D01*
G02X1512827Y1692686I-303J1D01*
G01X1509127D01*
G02X1508824Y1692988I-1J302D01*
G01Y1695400D01*
G02X1508811Y1695629I2003J229D01*
G02X1508824Y1695858I2016J0D01*
G01Y1700125D01*
G02X1508811Y1700354I2003J229D01*
G02X1508824Y1700583I2016J0D01*
G01Y1702994D01*
G02X1509127Y1703296I303J-1D01*
G37*
G36*
G01X1524875D02*
X1528575D01*
G02X1528878Y1702994I1J-302D01*
G01Y1692988D01*
G02X1528575Y1692686I-303J1D01*
G01X1524875D01*
G02X1524572Y1692988I-1J302D01*
G01Y1695400D01*
G02X1524559Y1695629I2003J229D01*
G02X1524572Y1695858I2016J0D01*
G01Y1700125D01*
G02X1524559Y1700354I2003J229D01*
G02X1524572Y1700583I2016J0D01*
G01Y1702994D01*
G02X1524875Y1703296I303J-1D01*
G37*
G36*
G01X1540623D02*
X1544323D01*
G02X1544626Y1702994I1J-302D01*
G01Y1692988D01*
G02X1544323Y1692686I-303J1D01*
G01X1540623D01*
G02X1540320Y1692988I-1J302D01*
G01Y1695400D01*
G02X1540307Y1695629I2003J229D01*
G02X1540320Y1695858I2016J0D01*
G01Y1700125D01*
G02X1540307Y1700354I2003J229D01*
G02X1540320Y1700583I2016J0D01*
G01Y1702994D01*
G02X1540623Y1703296I303J-1D01*
G37*
G36*
G01X1556371D02*
X1560071D01*
G02X1560374Y1702994I1J-302D01*
G01Y1692988D01*
G02X1560071Y1692686I-303J1D01*
G01X1556371D01*
G02X1556068Y1692988I-1J302D01*
G01Y1695400D01*
G02X1556055Y1695629I2003J229D01*
G02X1556068Y1695858I2016J0D01*
G01Y1700125D01*
G02X1556055Y1700354I2003J229D01*
G02X1556068Y1700583I2016J0D01*
G01Y1702994D01*
G02X1556371Y1703296I303J-1D01*
G37*
G36*
G01X229206Y1713532D02*
X232906D01*
G02X233208Y1713230I0J-302D01*
G01Y1703224D01*
G02X232906Y1702922I-302J0D01*
G01X229206D01*
G02X228904Y1703224I0J302D01*
G01Y1705629D01*
G02X228890Y1705866I2002J237D01*
G02X228904Y1706103I2016J0D01*
G01Y1710353D01*
G02X228890Y1710590I2002J237D01*
G02X228904Y1710827I2016J0D01*
G01Y1713230D01*
G02X229206Y1713532I302J0D01*
G37*
G36*
G01X244954D02*
X248654D01*
G02X248956Y1713230I0J-302D01*
G01Y1703224D01*
G02X248654Y1702922I-302J0D01*
G01X244954D01*
G02X244652Y1703224I0J302D01*
G01Y1705629D01*
G02X244638Y1705866I2002J237D01*
G02X244652Y1706103I2016J0D01*
G01Y1710353D01*
G02X244638Y1710590I2002J237D01*
G02X244652Y1710827I2016J0D01*
G01Y1713230D01*
G02X244954Y1713532I302J0D01*
G37*
G36*
G01X260702D02*
X264402D01*
G02X264704Y1713230I0J-302D01*
G01Y1703224D01*
G02X264402Y1702922I-302J0D01*
G01X260702D01*
G02X260400Y1703224I0J302D01*
G01Y1705629D01*
G02X260386Y1705866I2002J237D01*
G02X260400Y1706103I2016J0D01*
G01Y1710353D01*
G02X260386Y1710590I2002J237D01*
G02X260400Y1710827I2016J0D01*
G01Y1713230D01*
G02X260702Y1713532I302J0D01*
G37*
G36*
G01X276450D02*
X280150D01*
G02X280452Y1713230I0J-302D01*
G01Y1703224D01*
G02X280150Y1702922I-302J0D01*
G01X276450D01*
G02X276148Y1703224I0J302D01*
G01Y1705629D01*
G02X276134Y1705866I2002J237D01*
G02X276148Y1706103I2016J0D01*
G01Y1710353D01*
G02X276134Y1710590I2002J237D01*
G02X276148Y1710827I2016J0D01*
G01Y1713230D01*
G02X276450Y1713532I302J0D01*
G37*
G36*
G01X560308D02*
X564008D01*
G02X564310Y1713230I0J-302D01*
G01Y1703224D01*
G02X564008Y1702922I-302J0D01*
G01X560308D01*
G02X560006Y1703224I0J302D01*
G01Y1705629D01*
G02X559992Y1705866I2002J237D01*
G02X560006Y1706103I2016J0D01*
G01Y1710353D01*
G02X559992Y1710590I2002J237D01*
G02X560006Y1710827I2016J0D01*
G01Y1713230D01*
G02X560308Y1713532I302J0D01*
G37*
G36*
G01X576056D02*
X579756D01*
G02X580058Y1713230I0J-302D01*
G01Y1703224D01*
G02X579756Y1702922I-302J0D01*
G01X576056D01*
G02X575754Y1703224I0J302D01*
G01Y1705629D01*
G02X575740Y1705866I2002J237D01*
G02X575754Y1706103I2016J0D01*
G01Y1710353D01*
G02X575740Y1710590I2002J237D01*
G02X575754Y1710827I2016J0D01*
G01Y1713230D01*
G02X576056Y1713532I302J0D01*
G37*
G36*
G01X591804D02*
X595504D01*
G02X595806Y1713230I0J-302D01*
G01Y1703224D01*
G02X595504Y1702922I-302J0D01*
G01X591804D01*
G02X591502Y1703224I0J302D01*
G01Y1705629D01*
G02X591488Y1705866I2002J237D01*
G02X591502Y1706103I2016J0D01*
G01Y1710353D01*
G02X591488Y1710590I2002J237D01*
G02X591502Y1710827I2016J0D01*
G01Y1713230D01*
G02X591804Y1713532I302J0D01*
G37*
G36*
G01X607552D02*
X611252D01*
G02X611554Y1713230I0J-302D01*
G01Y1703224D01*
G02X611252Y1702922I-302J0D01*
G01X607552D01*
G02X607250Y1703224I0J302D01*
G01Y1705629D01*
G02X607236Y1705866I2002J237D01*
G02X607250Y1706103I2016J0D01*
G01Y1710353D01*
G02X607236Y1710590I2002J237D01*
G02X607250Y1710827I2016J0D01*
G01Y1713230D01*
G02X607552Y1713532I302J0D01*
G37*
G36*
G01X1237080D02*
X1240780D01*
G02X1241082Y1713230I0J-302D01*
G01Y1703224D01*
G02X1240780Y1702922I-302J0D01*
G01X1237080D01*
G02X1236778Y1703224I0J302D01*
G01Y1705629D01*
G02X1236764Y1705866I2002J237D01*
G02X1236778Y1706103I2016J0D01*
G01Y1710353D01*
G02X1236764Y1710590I2002J237D01*
G02X1236778Y1710827I2016J0D01*
G01Y1713230D01*
G02X1237080Y1713532I302J0D01*
G37*
G36*
G01X1252828D02*
X1256528D01*
G02X1256830Y1713230I0J-302D01*
G01Y1703224D01*
G02X1256528Y1702922I-302J0D01*
G01X1252828D01*
G02X1252526Y1703224I0J302D01*
G01Y1705629D01*
G02X1252512Y1705866I2002J237D01*
G02X1252526Y1706103I2016J0D01*
G01Y1710353D01*
G02X1252512Y1710590I2002J237D01*
G02X1252526Y1710827I2016J0D01*
G01Y1713230D01*
G02X1252828Y1713532I302J0D01*
G37*
G36*
G01X1268576D02*
X1272276D01*
G02X1272578Y1713230I0J-302D01*
G01Y1703224D01*
G02X1272276Y1702922I-302J0D01*
G01X1268576D01*
G02X1268274Y1703224I0J302D01*
G01Y1705629D01*
G02X1268260Y1705866I2002J237D01*
G02X1268274Y1706103I2016J0D01*
G01Y1710353D01*
G02X1268260Y1710590I2002J237D01*
G02X1268274Y1710827I2016J0D01*
G01Y1713230D01*
G02X1268576Y1713532I302J0D01*
G37*
G36*
G01X1284324D02*
X1288024D01*
G02X1288326Y1713230I0J-302D01*
G01Y1703224D01*
G02X1288024Y1702922I-302J0D01*
G01X1284324D01*
G02X1284022Y1703224I0J302D01*
G01Y1705629D01*
G02X1284008Y1705866I2002J237D01*
G02X1284022Y1706103I2016J0D01*
G01Y1710353D01*
G02X1284008Y1710590I2002J237D01*
G02X1284022Y1710827I2016J0D01*
G01Y1713230D01*
G02X1284324Y1713532I302J0D01*
G37*
G36*
G01X1568182D02*
X1571882D01*
G02X1572184Y1713230I0J-302D01*
G01Y1703224D01*
G02X1571882Y1702922I-302J0D01*
G01X1568182D01*
G02X1567880Y1703224I0J302D01*
G01Y1705629D01*
G02X1567866Y1705866I2002J237D01*
G02X1567880Y1706103I2016J0D01*
G01Y1710353D01*
G02X1567866Y1710590I2002J237D01*
G02X1567880Y1710827I2016J0D01*
G01Y1713230D01*
G02X1568182Y1713532I302J0D01*
G37*
G36*
G01X1583930D02*
X1587630D01*
G02X1587932Y1713230I0J-302D01*
G01Y1703224D01*
G02X1587630Y1702922I-302J0D01*
G01X1583930D01*
G02X1583628Y1703224I0J302D01*
G01Y1705629D01*
G02X1583614Y1705866I2002J237D01*
G02X1583628Y1706103I2016J0D01*
G01Y1710353D01*
G02X1583614Y1710590I2002J237D01*
G02X1583628Y1710827I2016J0D01*
G01Y1713230D01*
G02X1583930Y1713532I302J0D01*
G37*
G36*
G01X1599678D02*
X1603378D01*
G02X1603680Y1713230I0J-302D01*
G01Y1703224D01*
G02X1603378Y1702922I-302J0D01*
G01X1599678D01*
G02X1599376Y1703224I0J302D01*
G01Y1705629D01*
G02X1599362Y1705866I2002J237D01*
G02X1599376Y1706103I2016J0D01*
G01Y1710353D01*
G02X1599362Y1710590I2002J237D01*
G02X1599376Y1710827I2016J0D01*
G01Y1713230D01*
G02X1599678Y1713532I302J0D01*
G37*
G36*
G01X1615426D02*
X1619126D01*
G02X1619428Y1713230I0J-302D01*
G01Y1703224D01*
G02X1619126Y1702922I-302J0D01*
G01X1615426D01*
G02X1615124Y1703224I0J302D01*
G01Y1705629D01*
G02X1615110Y1705866I2002J237D01*
G02X1615124Y1706103I2016J0D01*
G01Y1710353D01*
G02X1615110Y1710590I2002J237D01*
G02X1615124Y1710827I2016J0D01*
G01Y1713230D01*
G02X1615426Y1713532I302J0D01*
G37*
G36*
G01X296135D02*
X299835D01*
G02X300138Y1713230I1J-302D01*
G01Y1703224D01*
G02X299835Y1702922I-303J1D01*
G01X296135D01*
G02X295832Y1703224I-1J302D01*
G01Y1705637D01*
G02X295819Y1705866I2003J229D01*
G02X295832Y1706095I2016J0D01*
G01Y1710361D01*
G02X295819Y1710590I2003J229D01*
G02X295832Y1710819I2016J0D01*
G01Y1713230D01*
G02X296135Y1713532I303J-1D01*
G37*
G36*
G01X311883D02*
X315583D01*
G02X315886Y1713230I1J-302D01*
G01Y1703224D01*
G02X315583Y1702922I-303J1D01*
G01X311883D01*
G02X311580Y1703224I-1J302D01*
G01Y1705637D01*
G02X311567Y1705866I2003J229D01*
G02X311580Y1706095I2016J0D01*
G01Y1710361D01*
G02X311567Y1710590I2003J229D01*
G02X311580Y1710819I2016J0D01*
G01Y1713230D01*
G02X311883Y1713532I303J-1D01*
G37*
G36*
G01X327631D02*
X331331D01*
G02X331634Y1713230I1J-302D01*
G01Y1703224D01*
G02X331331Y1702922I-303J1D01*
G01X327631D01*
G02X327328Y1703224I-1J302D01*
G01Y1705637D01*
G02X327315Y1705866I2003J229D01*
G02X327328Y1706095I2016J0D01*
G01Y1710361D01*
G02X327315Y1710590I2003J229D01*
G02X327328Y1710819I2016J0D01*
G01Y1713230D01*
G02X327631Y1713532I303J-1D01*
G37*
G36*
G01X343379D02*
X347079D01*
G02X347382Y1713230I1J-302D01*
G01Y1703224D01*
G02X347079Y1702922I-303J1D01*
G01X343379D01*
G02X343076Y1703224I-1J302D01*
G01Y1705637D01*
G02X343063Y1705866I2003J229D01*
G02X343076Y1706095I2016J0D01*
G01Y1710361D01*
G02X343063Y1710590I2003J229D01*
G02X343076Y1710819I2016J0D01*
G01Y1713230D01*
G02X343379Y1713532I303J-1D01*
G37*
G36*
G01X493379D02*
X497079D01*
G02X497382Y1713230I1J-302D01*
G01Y1703224D01*
G02X497079Y1702922I-303J1D01*
G01X493379D01*
G02X493076Y1703224I-1J302D01*
G01Y1705637D01*
G02X493063Y1705866I2003J229D01*
G02X493076Y1706095I2016J0D01*
G01Y1710361D01*
G02X493063Y1710590I2003J229D01*
G02X493076Y1710819I2016J0D01*
G01Y1713230D01*
G02X493379Y1713532I303J-1D01*
G37*
G36*
G01X509127D02*
X512827D01*
G02X513130Y1713230I1J-302D01*
G01Y1703224D01*
G02X512827Y1702922I-303J1D01*
G01X509127D01*
G02X508824Y1703224I-1J302D01*
G01Y1705637D01*
G02X508811Y1705866I2003J229D01*
G02X508824Y1706095I2016J0D01*
G01Y1710361D01*
G02X508811Y1710590I2003J229D01*
G02X508824Y1710819I2016J0D01*
G01Y1713230D01*
G02X509127Y1713532I303J-1D01*
G37*
G36*
G01X524875D02*
X528575D01*
G02X528878Y1713230I1J-302D01*
G01Y1703224D01*
G02X528575Y1702922I-303J1D01*
G01X524875D01*
G02X524572Y1703224I-1J302D01*
G01Y1705637D01*
G02X524559Y1705866I2003J229D01*
G02X524572Y1706095I2016J0D01*
G01Y1710361D01*
G02X524559Y1710590I2003J229D01*
G02X524572Y1710819I2016J0D01*
G01Y1713230D01*
G02X524875Y1713532I303J-1D01*
G37*
G36*
G01X540623D02*
X544323D01*
G02X544626Y1713230I1J-302D01*
G01Y1703224D01*
G02X544323Y1702922I-303J1D01*
G01X540623D01*
G02X540320Y1703224I-1J302D01*
G01Y1705637D01*
G02X540307Y1705866I2003J229D01*
G02X540320Y1706095I2016J0D01*
G01Y1710361D01*
G02X540307Y1710590I2003J229D01*
G02X540320Y1710819I2016J0D01*
G01Y1713230D01*
G02X540623Y1713532I303J-1D01*
G37*
G36*
G01X1304009D02*
X1307709D01*
G02X1308012Y1713230I1J-302D01*
G01Y1703224D01*
G02X1307709Y1702922I-303J1D01*
G01X1304009D01*
G02X1303706Y1703224I-1J302D01*
G01Y1705637D01*
G02X1303693Y1705866I2003J229D01*
G02X1303706Y1706095I2016J0D01*
G01Y1710361D01*
G02X1303693Y1710590I2003J229D01*
G02X1303706Y1710819I2016J0D01*
G01Y1713230D01*
G02X1304009Y1713532I303J-1D01*
G37*
G36*
G01X1319757D02*
X1323457D01*
G02X1323760Y1713230I1J-302D01*
G01Y1703224D01*
G02X1323457Y1702922I-303J1D01*
G01X1319757D01*
G02X1319454Y1703224I-1J302D01*
G01Y1705637D01*
G02X1319441Y1705866I2003J229D01*
G02X1319454Y1706095I2016J0D01*
G01Y1710361D01*
G02X1319441Y1710590I2003J229D01*
G02X1319454Y1710819I2016J0D01*
G01Y1713230D01*
G02X1319757Y1713532I303J-1D01*
G37*
G36*
G01X1335505D02*
X1339205D01*
G02X1339508Y1713230I1J-302D01*
G01Y1703224D01*
G02X1339205Y1702922I-303J1D01*
G01X1335505D01*
G02X1335202Y1703224I-1J302D01*
G01Y1705637D01*
G02X1335189Y1705866I2003J229D01*
G02X1335202Y1706095I2016J0D01*
G01Y1710361D01*
G02X1335189Y1710590I2003J229D01*
G02X1335202Y1710819I2016J0D01*
G01Y1713230D01*
G02X1335505Y1713532I303J-1D01*
G37*
G36*
G01X1351253D02*
X1354953D01*
G02X1355256Y1713230I1J-302D01*
G01Y1703224D01*
G02X1354953Y1702922I-303J1D01*
G01X1351253D01*
G02X1350950Y1703224I-1J302D01*
G01Y1705637D01*
G02X1350937Y1705866I2003J229D01*
G02X1350950Y1706095I2016J0D01*
G01Y1710361D01*
G02X1350937Y1710590I2003J229D01*
G02X1350950Y1710819I2016J0D01*
G01Y1713230D01*
G02X1351253Y1713532I303J-1D01*
G37*
G36*
G01X1501253D02*
X1504953D01*
G02X1505256Y1713230I1J-302D01*
G01Y1703224D01*
G02X1504953Y1702922I-303J1D01*
G01X1501253D01*
G02X1500950Y1703224I-1J302D01*
G01Y1705637D01*
G02X1500937Y1705866I2003J229D01*
G02X1500950Y1706095I2016J0D01*
G01Y1710361D01*
G02X1500937Y1710590I2003J229D01*
G02X1500950Y1710819I2016J0D01*
G01Y1713230D01*
G02X1501253Y1713532I303J-1D01*
G37*
G36*
G01X1517001D02*
X1520701D01*
G02X1521004Y1713230I1J-302D01*
G01Y1703224D01*
G02X1520701Y1702922I-303J1D01*
G01X1517001D01*
G02X1516698Y1703224I-1J302D01*
G01Y1705637D01*
G02X1516685Y1705866I2003J229D01*
G02X1516698Y1706095I2016J0D01*
G01Y1710361D01*
G02X1516685Y1710590I2003J229D01*
G02X1516698Y1710819I2016J0D01*
G01Y1713230D01*
G02X1517001Y1713532I303J-1D01*
G37*
G36*
G01X1532749D02*
X1536449D01*
G02X1536752Y1713230I1J-302D01*
G01Y1703224D01*
G02X1536449Y1702922I-303J1D01*
G01X1532749D01*
G02X1532446Y1703224I-1J302D01*
G01Y1705637D01*
G02X1532433Y1705866I2003J229D01*
G02X1532446Y1706095I2016J0D01*
G01Y1710361D01*
G02X1532433Y1710590I2003J229D01*
G02X1532446Y1710819I2016J0D01*
G01Y1713230D01*
G02X1532749Y1713532I303J-1D01*
G37*
G36*
G01X1548497D02*
X1552197D01*
G02X1552500Y1713230I1J-302D01*
G01Y1703224D01*
G02X1552197Y1702922I-303J1D01*
G01X1548497D01*
G02X1548194Y1703224I-1J302D01*
G01Y1705637D01*
G02X1548181Y1705866I2003J229D01*
G02X1548194Y1706095I2016J0D01*
G01Y1710361D01*
G02X1548181Y1710590I2003J229D01*
G02X1548194Y1710819I2016J0D01*
G01Y1713230D01*
G02X1548497Y1713532I303J-1D01*
G37*
G36*
G01X237080Y1717470D02*
X240780D01*
G02X241082Y1717167I-1J-303D01*
G01Y1707161D01*
G02X240780Y1706858I-302J-1D01*
G01X237080D01*
G02X236778Y1707161I1J303D01*
G01Y1709566D01*
G02X236764Y1709803I2002J237D01*
G02X236778Y1710040I2016J0D01*
G01Y1714290D01*
G02X236764Y1714527I2002J237D01*
G02X236778Y1714764I2016J0D01*
G01Y1717167D01*
G02X237080Y1717470I302J1D01*
G37*
G36*
G01X252828D02*
X256528D01*
G02X256830Y1717167I-1J-303D01*
G01Y1707161D01*
G02X256528Y1706858I-302J-1D01*
G01X252828D01*
G02X252526Y1707161I1J303D01*
G01Y1709566D01*
G02X252512Y1709803I2002J237D01*
G02X252526Y1710040I2016J0D01*
G01Y1714290D01*
G02X252512Y1714527I2002J237D01*
G02X252526Y1714764I2016J0D01*
G01Y1717167D01*
G02X252828Y1717470I302J1D01*
G37*
G36*
G01X268576D02*
X272276D01*
G02X272578Y1717167I-1J-303D01*
G01Y1707161D01*
G02X272276Y1706858I-302J-1D01*
G01X268576D01*
G02X268274Y1707161I1J303D01*
G01Y1709566D01*
G02X268260Y1709803I2002J237D01*
G02X268274Y1710040I2016J0D01*
G01Y1714290D01*
G02X268260Y1714527I2002J237D01*
G02X268274Y1714764I2016J0D01*
G01Y1717167D01*
G02X268576Y1717470I302J1D01*
G37*
G36*
G01X284324D02*
X288024D01*
G02X288326Y1717167I-1J-303D01*
G01Y1707161D01*
G02X288024Y1706858I-302J-1D01*
G01X284324D01*
G02X284022Y1707161I1J303D01*
G01Y1709566D01*
G02X284008Y1709803I2002J237D01*
G02X284022Y1710040I2016J0D01*
G01Y1714290D01*
G02X284008Y1714527I2002J237D01*
G02X284022Y1714764I2016J0D01*
G01Y1717167D01*
G02X284324Y1717470I302J1D01*
G37*
G36*
G01X304009D02*
X307709D01*
G02X308012Y1717167I0J-303D01*
G01Y1707161D01*
G02X307709Y1706858I-303J0D01*
G01X304009D01*
G02X303706Y1707161I0J303D01*
G01Y1709574D01*
G02X303693Y1709803I2003J229D01*
G02X303706Y1710032I2016J0D01*
G01Y1714298D01*
G02X303693Y1714527I2003J229D01*
G02X303706Y1714756I2016J0D01*
G01Y1717167D01*
G02X304009Y1717470I303J0D01*
G37*
G36*
G01X319757D02*
X323457D01*
G02X323760Y1717167I0J-303D01*
G01Y1707161D01*
G02X323457Y1706858I-303J0D01*
G01X319757D01*
G02X319454Y1707161I0J303D01*
G01Y1709574D01*
G02X319441Y1709803I2003J229D01*
G02X319454Y1710032I2016J0D01*
G01Y1714298D01*
G02X319441Y1714527I2003J229D01*
G02X319454Y1714756I2016J0D01*
G01Y1717167D01*
G02X319757Y1717470I303J0D01*
G37*
G36*
G01X335505D02*
X339205D01*
G02X339508Y1717167I0J-303D01*
G01Y1707161D01*
G02X339205Y1706858I-303J0D01*
G01X335505D01*
G02X335202Y1707161I0J303D01*
G01Y1709574D01*
G02X335189Y1709803I2003J229D01*
G02X335202Y1710032I2016J0D01*
G01Y1714298D01*
G02X335189Y1714527I2003J229D01*
G02X335202Y1714756I2016J0D01*
G01Y1717167D01*
G02X335505Y1717470I303J0D01*
G37*
G36*
G01X351253D02*
X354953D01*
G02X355256Y1717167I0J-303D01*
G01Y1707161D01*
G02X354953Y1706858I-303J0D01*
G01X351253D01*
G02X350950Y1707161I0J303D01*
G01Y1709574D01*
G02X350937Y1709803I2003J229D01*
G02X350950Y1710032I2016J0D01*
G01Y1714298D01*
G02X350937Y1714527I2003J229D01*
G02X350950Y1714756I2016J0D01*
G01Y1717167D01*
G02X351253Y1717470I303J0D01*
G37*
G36*
G01X501253D02*
X504953D01*
G02X505256Y1717167I0J-303D01*
G01Y1707161D01*
G02X504953Y1706858I-303J0D01*
G01X501253D01*
G02X500950Y1707161I0J303D01*
G01Y1709574D01*
G02X500937Y1709803I2003J229D01*
G02X500950Y1710032I2016J0D01*
G01Y1714298D01*
G02X500937Y1714527I2003J229D01*
G02X500950Y1714756I2016J0D01*
G01Y1717167D01*
G02X501253Y1717470I303J0D01*
G37*
G36*
G01X517001D02*
X520701D01*
G02X521004Y1717167I0J-303D01*
G01Y1707161D01*
G02X520701Y1706858I-303J0D01*
G01X517001D01*
G02X516698Y1707161I0J303D01*
G01Y1709574D01*
G02X516685Y1709803I2003J229D01*
G02X516698Y1710032I2016J0D01*
G01Y1714298D01*
G02X516685Y1714527I2003J229D01*
G02X516698Y1714756I2016J0D01*
G01Y1717167D01*
G02X517001Y1717470I303J0D01*
G37*
G36*
G01X532749D02*
X536449D01*
G02X536752Y1717167I0J-303D01*
G01Y1707161D01*
G02X536449Y1706858I-303J0D01*
G01X532749D01*
G02X532446Y1707161I0J303D01*
G01Y1709574D01*
G02X532433Y1709803I2003J229D01*
G02X532446Y1710032I2016J0D01*
G01Y1714298D01*
G02X532433Y1714527I2003J229D01*
G02X532446Y1714756I2016J0D01*
G01Y1717167D01*
G02X532749Y1717470I303J0D01*
G37*
G36*
G01X548497D02*
X552197D01*
G02X552500Y1717167I0J-303D01*
G01Y1707161D01*
G02X552197Y1706858I-303J0D01*
G01X548497D01*
G02X548194Y1707161I0J303D01*
G01Y1709574D01*
G02X548181Y1709803I2003J229D01*
G02X548194Y1710032I2016J0D01*
G01Y1714298D01*
G02X548181Y1714527I2003J229D01*
G02X548194Y1714756I2016J0D01*
G01Y1717167D01*
G02X548497Y1717470I303J0D01*
G37*
G36*
G01X568182D02*
X571882D01*
G02X572184Y1717167I-1J-303D01*
G01Y1707161D01*
G02X571882Y1706858I-302J-1D01*
G01X568182D01*
G02X567880Y1707161I1J303D01*
G01Y1709566D01*
G02X567866Y1709803I2002J237D01*
G02X567880Y1710040I2016J0D01*
G01Y1714290D01*
G02X567866Y1714527I2002J237D01*
G02X567880Y1714764I2016J0D01*
G01Y1717167D01*
G02X568182Y1717470I302J1D01*
G37*
G36*
G01X583930D02*
X587630D01*
G02X587932Y1717167I-1J-303D01*
G01Y1707161D01*
G02X587630Y1706858I-302J-1D01*
G01X583930D01*
G02X583628Y1707161I1J303D01*
G01Y1709566D01*
G02X583614Y1709803I2002J237D01*
G02X583628Y1710040I2016J0D01*
G01Y1714290D01*
G02X583614Y1714527I2002J237D01*
G02X583628Y1714764I2016J0D01*
G01Y1717167D01*
G02X583930Y1717470I302J1D01*
G37*
G36*
G01X599678D02*
X603378D01*
G02X603680Y1717167I-1J-303D01*
G01Y1707161D01*
G02X603378Y1706858I-302J-1D01*
G01X599678D01*
G02X599376Y1707161I1J303D01*
G01Y1709566D01*
G02X599362Y1709803I2002J237D01*
G02X599376Y1710040I2016J0D01*
G01Y1714290D01*
G02X599362Y1714527I2002J237D01*
G02X599376Y1714764I2016J0D01*
G01Y1717167D01*
G02X599678Y1717470I302J1D01*
G37*
G36*
G01X615426D02*
X619126D01*
G02X619428Y1717167I-1J-303D01*
G01Y1707161D01*
G02X619126Y1706858I-302J-1D01*
G01X615426D01*
G02X615124Y1707161I1J303D01*
G01Y1709566D01*
G02X615110Y1709803I2002J237D01*
G02X615124Y1710040I2016J0D01*
G01Y1714290D01*
G02X615110Y1714527I2002J237D01*
G02X615124Y1714764I2016J0D01*
G01Y1717167D01*
G02X615426Y1717470I302J1D01*
G37*
G36*
G01X1244954D02*
X1248654D01*
G02X1248956Y1717167I-1J-303D01*
G01Y1707161D01*
G02X1248654Y1706858I-302J-1D01*
G01X1244954D01*
G02X1244652Y1707161I1J303D01*
G01Y1709566D01*
G02X1244638Y1709803I2002J237D01*
G02X1244652Y1710040I2016J0D01*
G01Y1714290D01*
G02X1244638Y1714527I2002J237D01*
G02X1244652Y1714764I2016J0D01*
G01Y1717167D01*
G02X1244954Y1717470I302J1D01*
G37*
G36*
G01X1260702D02*
X1264402D01*
G02X1264704Y1717167I-1J-303D01*
G01Y1707161D01*
G02X1264402Y1706858I-302J-1D01*
G01X1260702D01*
G02X1260400Y1707161I1J303D01*
G01Y1709566D01*
G02X1260386Y1709803I2002J237D01*
G02X1260400Y1710040I2016J0D01*
G01Y1714290D01*
G02X1260386Y1714527I2002J237D01*
G02X1260400Y1714764I2016J0D01*
G01Y1717167D01*
G02X1260702Y1717470I302J1D01*
G37*
G36*
G01X1276450D02*
X1280150D01*
G02X1280452Y1717167I-1J-303D01*
G01Y1707161D01*
G02X1280150Y1706858I-302J-1D01*
G01X1276450D01*
G02X1276148Y1707161I1J303D01*
G01Y1709566D01*
G02X1276134Y1709803I2002J237D01*
G02X1276148Y1710040I2016J0D01*
G01Y1714290D01*
G02X1276134Y1714527I2002J237D01*
G02X1276148Y1714764I2016J0D01*
G01Y1717167D01*
G02X1276450Y1717470I302J1D01*
G37*
G36*
G01X1292198D02*
X1295898D01*
G02X1296200Y1717167I-1J-303D01*
G01Y1707161D01*
G02X1295898Y1706858I-302J-1D01*
G01X1292198D01*
G02X1291896Y1707161I1J303D01*
G01Y1709566D01*
G02X1291882Y1709803I2002J237D01*
G02X1291896Y1710040I2016J0D01*
G01Y1714290D01*
G02X1291882Y1714527I2002J237D01*
G02X1291896Y1714764I2016J0D01*
G01Y1717167D01*
G02X1292198Y1717470I302J1D01*
G37*
G36*
G01X1311883D02*
X1315583D01*
G02X1315886Y1717167I0J-303D01*
G01Y1707161D01*
G02X1315583Y1706858I-303J0D01*
G01X1311883D01*
G02X1311580Y1707161I0J303D01*
G01Y1709574D01*
G02X1311567Y1709803I2003J229D01*
G02X1311580Y1710032I2016J0D01*
G01Y1714298D01*
G02X1311567Y1714527I2003J229D01*
G02X1311580Y1714756I2016J0D01*
G01Y1717167D01*
G02X1311883Y1717470I303J0D01*
G37*
G36*
G01X1327631D02*
X1331331D01*
G02X1331634Y1717167I0J-303D01*
G01Y1707161D01*
G02X1331331Y1706858I-303J0D01*
G01X1327631D01*
G02X1327328Y1707161I0J303D01*
G01Y1709574D01*
G02X1327315Y1709803I2003J229D01*
G02X1327328Y1710032I2016J0D01*
G01Y1714298D01*
G02X1327315Y1714527I2003J229D01*
G02X1327328Y1714756I2016J0D01*
G01Y1717167D01*
G02X1327631Y1717470I303J0D01*
G37*
G36*
G01X1343379D02*
X1347079D01*
G02X1347382Y1717167I0J-303D01*
G01Y1707161D01*
G02X1347079Y1706858I-303J0D01*
G01X1343379D01*
G02X1343076Y1707161I0J303D01*
G01Y1709574D01*
G02X1343063Y1709803I2003J229D01*
G02X1343076Y1710032I2016J0D01*
G01Y1714298D01*
G02X1343063Y1714527I2003J229D01*
G02X1343076Y1714756I2016J0D01*
G01Y1717167D01*
G02X1343379Y1717470I303J0D01*
G37*
G36*
G01X1359127D02*
X1362827D01*
G02X1363130Y1717167I0J-303D01*
G01Y1707161D01*
G02X1362827Y1706858I-303J0D01*
G01X1359127D01*
G02X1358824Y1707161I0J303D01*
G01Y1709574D01*
G02X1358811Y1709803I2003J229D01*
G02X1358824Y1710032I2016J0D01*
G01Y1714298D01*
G02X1358811Y1714527I2003J229D01*
G02X1358824Y1714756I2016J0D01*
G01Y1717167D01*
G02X1359127Y1717470I303J0D01*
G37*
G36*
G01X1509127D02*
X1512827D01*
G02X1513130Y1717167I0J-303D01*
G01Y1707161D01*
G02X1512827Y1706858I-303J0D01*
G01X1509127D01*
G02X1508824Y1707161I0J303D01*
G01Y1709574D01*
G02X1508811Y1709803I2003J229D01*
G02X1508824Y1710032I2016J0D01*
G01Y1714298D01*
G02X1508811Y1714527I2003J229D01*
G02X1508824Y1714756I2016J0D01*
G01Y1717167D01*
G02X1509127Y1717470I303J0D01*
G37*
G36*
G01X1524875D02*
X1528575D01*
G02X1528878Y1717167I0J-303D01*
G01Y1707161D01*
G02X1528575Y1706858I-303J0D01*
G01X1524875D01*
G02X1524572Y1707161I0J303D01*
G01Y1709574D01*
G02X1524559Y1709803I2003J229D01*
G02X1524572Y1710032I2016J0D01*
G01Y1714298D01*
G02X1524559Y1714527I2003J229D01*
G02X1524572Y1714756I2016J0D01*
G01Y1717167D01*
G02X1524875Y1717470I303J0D01*
G37*
G36*
G01X1540623D02*
X1544323D01*
G02X1544626Y1717167I0J-303D01*
G01Y1707161D01*
G02X1544323Y1706858I-303J0D01*
G01X1540623D01*
G02X1540320Y1707161I0J303D01*
G01Y1709574D01*
G02X1540307Y1709803I2003J229D01*
G02X1540320Y1710032I2016J0D01*
G01Y1714298D01*
G02X1540307Y1714527I2003J229D01*
G02X1540320Y1714756I2016J0D01*
G01Y1717167D01*
G02X1540623Y1717470I303J0D01*
G37*
G36*
G01X1556371D02*
X1560071D01*
G02X1560374Y1717167I0J-303D01*
G01Y1707161D01*
G02X1560071Y1706858I-303J0D01*
G01X1556371D01*
G02X1556068Y1707161I0J303D01*
G01Y1709574D01*
G02X1556055Y1709803I2003J229D01*
G02X1556068Y1710032I2016J0D01*
G01Y1714298D01*
G02X1556055Y1714527I2003J229D01*
G02X1556068Y1714756I2016J0D01*
G01Y1717167D01*
G02X1556371Y1717470I303J0D01*
G37*
G36*
G01X1576056D02*
X1579756D01*
G02X1580058Y1717167I-1J-303D01*
G01Y1707161D01*
G02X1579756Y1706858I-302J-1D01*
G01X1576056D01*
G02X1575754Y1707161I1J303D01*
G01Y1709566D01*
G02X1575740Y1709803I2002J237D01*
G02X1575754Y1710040I2016J0D01*
G01Y1714290D01*
G02X1575740Y1714527I2002J237D01*
G02X1575754Y1714764I2016J0D01*
G01Y1717167D01*
G02X1576056Y1717470I302J1D01*
G37*
G36*
G01X1591804D02*
X1595504D01*
G02X1595806Y1717167I-1J-303D01*
G01Y1707161D01*
G02X1595504Y1706858I-302J-1D01*
G01X1591804D01*
G02X1591502Y1707161I1J303D01*
G01Y1709566D01*
G02X1591488Y1709803I2002J237D01*
G02X1591502Y1710040I2016J0D01*
G01Y1714290D01*
G02X1591488Y1714527I2002J237D01*
G02X1591502Y1714764I2016J0D01*
G01Y1717167D01*
G02X1591804Y1717470I302J1D01*
G37*
G36*
G01X1607552D02*
X1611252D01*
G02X1611554Y1717167I-1J-303D01*
G01Y1707161D01*
G02X1611252Y1706858I-302J-1D01*
G01X1607552D01*
G02X1607250Y1707161I1J303D01*
G01Y1709566D01*
G02X1607236Y1709803I2002J237D01*
G02X1607250Y1710040I2016J0D01*
G01Y1714290D01*
G02X1607236Y1714527I2002J237D01*
G02X1607250Y1714764I2016J0D01*
G01Y1717167D01*
G02X1607552Y1717470I302J1D01*
G37*
G36*
G01X1623300D02*
X1627000D01*
G02X1627302Y1717167I-1J-303D01*
G01Y1707161D01*
G02X1627000Y1706858I-302J-1D01*
G01X1623300D01*
G02X1622998Y1707161I1J303D01*
G01Y1709566D01*
G02X1622984Y1709803I2002J237D01*
G02X1622998Y1710040I2016J0D01*
G01Y1714290D01*
G02X1622984Y1714527I2002J237D01*
G02X1622998Y1714764I2016J0D01*
G01Y1717167D01*
G02X1623300Y1717470I302J1D01*
G37*
G36*
G01X229206Y1727706D02*
X232906D01*
G02X233208Y1727404I0J-302D01*
G01Y1717398D01*
G02X232906Y1717096I-302J0D01*
G01X229206D01*
G02X228904Y1717398I0J302D01*
G01Y1719802D01*
G02X228890Y1720039I2002J237D01*
G02X228904Y1720276I2016J0D01*
G01Y1724526D01*
G02X228890Y1724763I2002J237D01*
G02X228904Y1725000I2016J0D01*
G01Y1727404D01*
G02X229206Y1727706I302J0D01*
G37*
G36*
G01X244954D02*
X248654D01*
G02X248956Y1727404I0J-302D01*
G01Y1717398D01*
G02X248654Y1717096I-302J0D01*
G01X244954D01*
G02X244652Y1717398I0J302D01*
G01Y1719802D01*
G02X244638Y1720039I2002J237D01*
G02X244652Y1720276I2016J0D01*
G01Y1724526D01*
G02X244638Y1724763I2002J237D01*
G02X244652Y1725000I2016J0D01*
G01Y1727404D01*
G02X244954Y1727706I302J0D01*
G37*
G36*
G01X260702D02*
X264402D01*
G02X264704Y1727404I0J-302D01*
G01Y1717398D01*
G02X264402Y1717096I-302J0D01*
G01X260702D01*
G02X260400Y1717398I0J302D01*
G01Y1719802D01*
G02X260386Y1720039I2002J237D01*
G02X260400Y1720276I2016J0D01*
G01Y1724526D01*
G02X260386Y1724763I2002J237D01*
G02X260400Y1725000I2016J0D01*
G01Y1727404D01*
G02X260702Y1727706I302J0D01*
G37*
G36*
G01X276450D02*
X280150D01*
G02X280452Y1727404I0J-302D01*
G01Y1717398D01*
G02X280150Y1717096I-302J0D01*
G01X276450D01*
G02X276148Y1717398I0J302D01*
G01Y1719802D01*
G02X276134Y1720039I2002J237D01*
G02X276148Y1720276I2016J0D01*
G01Y1724526D01*
G02X276134Y1724763I2002J237D01*
G02X276148Y1725000I2016J0D01*
G01Y1727404D01*
G02X276450Y1727706I302J0D01*
G37*
G36*
G01X560308D02*
X564008D01*
G02X564310Y1727404I0J-302D01*
G01Y1717398D01*
G02X564008Y1717096I-302J0D01*
G01X560308D01*
G02X560006Y1717398I0J302D01*
G01Y1719802D01*
G02X559992Y1720039I2002J237D01*
G02X560006Y1720276I2016J0D01*
G01Y1724526D01*
G02X559992Y1724763I2002J237D01*
G02X560006Y1725000I2016J0D01*
G01Y1727404D01*
G02X560308Y1727706I302J0D01*
G37*
G36*
G01X576056D02*
X579756D01*
G02X580058Y1727404I0J-302D01*
G01Y1717398D01*
G02X579756Y1717096I-302J0D01*
G01X576056D01*
G02X575754Y1717398I0J302D01*
G01Y1719802D01*
G02X575740Y1720039I2002J237D01*
G02X575754Y1720276I2016J0D01*
G01Y1724526D01*
G02X575740Y1724763I2002J237D01*
G02X575754Y1725000I2016J0D01*
G01Y1727404D01*
G02X576056Y1727706I302J0D01*
G37*
G36*
G01X591804D02*
X595504D01*
G02X595806Y1727404I0J-302D01*
G01Y1717398D01*
G02X595504Y1717096I-302J0D01*
G01X591804D01*
G02X591502Y1717398I0J302D01*
G01Y1719802D01*
G02X591488Y1720039I2002J237D01*
G02X591502Y1720276I2016J0D01*
G01Y1724526D01*
G02X591488Y1724763I2002J237D01*
G02X591502Y1725000I2016J0D01*
G01Y1727404D01*
G02X591804Y1727706I302J0D01*
G37*
G36*
G01X607552D02*
X611252D01*
G02X611554Y1727404I0J-302D01*
G01Y1717398D01*
G02X611252Y1717096I-302J0D01*
G01X607552D01*
G02X607250Y1717398I0J302D01*
G01Y1719802D01*
G02X607236Y1720039I2002J237D01*
G02X607250Y1720276I2016J0D01*
G01Y1724526D01*
G02X607236Y1724763I2002J237D01*
G02X607250Y1725000I2016J0D01*
G01Y1727404D01*
G02X607552Y1727706I302J0D01*
G37*
G36*
G01X1237080D02*
X1240780D01*
G02X1241082Y1727404I0J-302D01*
G01Y1717398D01*
G02X1240780Y1717096I-302J0D01*
G01X1237080D01*
G02X1236778Y1717398I0J302D01*
G01Y1719802D01*
G02X1236764Y1720039I2002J237D01*
G02X1236778Y1720276I2016J0D01*
G01Y1724526D01*
G02X1236764Y1724763I2002J237D01*
G02X1236778Y1725000I2016J0D01*
G01Y1727404D01*
G02X1237080Y1727706I302J0D01*
G37*
G36*
G01X1252828D02*
X1256528D01*
G02X1256830Y1727404I0J-302D01*
G01Y1717398D01*
G02X1256528Y1717096I-302J0D01*
G01X1252828D01*
G02X1252526Y1717398I0J302D01*
G01Y1719802D01*
G02X1252512Y1720039I2002J237D01*
G02X1252526Y1720276I2016J0D01*
G01Y1724526D01*
G02X1252512Y1724763I2002J237D01*
G02X1252526Y1725000I2016J0D01*
G01Y1727404D01*
G02X1252828Y1727706I302J0D01*
G37*
G36*
G01X1268576D02*
X1272276D01*
G02X1272578Y1727404I0J-302D01*
G01Y1717398D01*
G02X1272276Y1717096I-302J0D01*
G01X1268576D01*
G02X1268274Y1717398I0J302D01*
G01Y1719802D01*
G02X1268260Y1720039I2002J237D01*
G02X1268274Y1720276I2016J0D01*
G01Y1724526D01*
G02X1268260Y1724763I2002J237D01*
G02X1268274Y1725000I2016J0D01*
G01Y1727404D01*
G02X1268576Y1727706I302J0D01*
G37*
G36*
G01X1284324D02*
X1288024D01*
G02X1288326Y1727404I0J-302D01*
G01Y1717398D01*
G02X1288024Y1717096I-302J0D01*
G01X1284324D01*
G02X1284022Y1717398I0J302D01*
G01Y1719802D01*
G02X1284008Y1720039I2002J237D01*
G02X1284022Y1720276I2016J0D01*
G01Y1724526D01*
G02X1284008Y1724763I2002J237D01*
G02X1284022Y1725000I2016J0D01*
G01Y1727404D01*
G02X1284324Y1727706I302J0D01*
G37*
G36*
G01X1568182D02*
X1571882D01*
G02X1572184Y1727404I0J-302D01*
G01Y1717398D01*
G02X1571882Y1717096I-302J0D01*
G01X1568182D01*
G02X1567880Y1717398I0J302D01*
G01Y1719802D01*
G02X1567866Y1720039I2002J237D01*
G02X1567880Y1720276I2016J0D01*
G01Y1724526D01*
G02X1567866Y1724763I2002J237D01*
G02X1567880Y1725000I2016J0D01*
G01Y1727404D01*
G02X1568182Y1727706I302J0D01*
G37*
G36*
G01X1583930D02*
X1587630D01*
G02X1587932Y1727404I0J-302D01*
G01Y1717398D01*
G02X1587630Y1717096I-302J0D01*
G01X1583930D01*
G02X1583628Y1717398I0J302D01*
G01Y1719802D01*
G02X1583614Y1720039I2002J237D01*
G02X1583628Y1720276I2016J0D01*
G01Y1724526D01*
G02X1583614Y1724763I2002J237D01*
G02X1583628Y1725000I2016J0D01*
G01Y1727404D01*
G02X1583930Y1727706I302J0D01*
G37*
G36*
G01X1599678D02*
X1603378D01*
G02X1603680Y1727404I0J-302D01*
G01Y1717398D01*
G02X1603378Y1717096I-302J0D01*
G01X1599678D01*
G02X1599376Y1717398I0J302D01*
G01Y1719802D01*
G02X1599362Y1720039I2002J237D01*
G02X1599376Y1720276I2016J0D01*
G01Y1724526D01*
G02X1599362Y1724763I2002J237D01*
G02X1599376Y1725000I2016J0D01*
G01Y1727404D01*
G02X1599678Y1727706I302J0D01*
G37*
G36*
G01X1615426D02*
X1619126D01*
G02X1619428Y1727404I0J-302D01*
G01Y1717398D01*
G02X1619126Y1717096I-302J0D01*
G01X1615426D01*
G02X1615124Y1717398I0J302D01*
G01Y1719802D01*
G02X1615110Y1720039I2002J237D01*
G02X1615124Y1720276I2016J0D01*
G01Y1724526D01*
G02X1615110Y1724763I2002J237D01*
G02X1615124Y1725000I2016J0D01*
G01Y1727404D01*
G02X1615426Y1727706I302J0D01*
G37*
G36*
G01X296135D02*
X299835D01*
G02X300138Y1727404I1J-302D01*
G01Y1717398D01*
G02X299835Y1717096I-303J1D01*
G01X296135D01*
G02X295832Y1717398I-1J302D01*
G01Y1719810D01*
G02X295819Y1720039I2003J229D01*
G02X295832Y1720268I2016J0D01*
G01Y1724534D01*
G02X295819Y1724763I2003J229D01*
G02X295832Y1724992I2016J0D01*
G01Y1727404D01*
G02X296135Y1727706I303J-1D01*
G37*
G36*
G01X311883D02*
X315583D01*
G02X315886Y1727404I1J-302D01*
G01Y1717398D01*
G02X315583Y1717096I-303J1D01*
G01X311883D01*
G02X311580Y1717398I-1J302D01*
G01Y1719810D01*
G02X311567Y1720039I2003J229D01*
G02X311580Y1720268I2016J0D01*
G01Y1724534D01*
G02X311567Y1724763I2003J229D01*
G02X311580Y1724992I2016J0D01*
G01Y1727404D01*
G02X311883Y1727706I303J-1D01*
G37*
G36*
G01X327631D02*
X331331D01*
G02X331634Y1727404I1J-302D01*
G01Y1717398D01*
G02X331331Y1717096I-303J1D01*
G01X327631D01*
G02X327328Y1717398I-1J302D01*
G01Y1719810D01*
G02X327315Y1720039I2003J229D01*
G02X327328Y1720268I2016J0D01*
G01Y1724534D01*
G02X327315Y1724763I2003J229D01*
G02X327328Y1724992I2016J0D01*
G01Y1727404D01*
G02X327631Y1727706I303J-1D01*
G37*
G36*
G01X343379D02*
X347079D01*
G02X347382Y1727404I1J-302D01*
G01Y1717398D01*
G02X347079Y1717096I-303J1D01*
G01X343379D01*
G02X343076Y1717398I-1J302D01*
G01Y1719810D01*
G02X343063Y1720039I2003J229D01*
G02X343076Y1720268I2016J0D01*
G01Y1724534D01*
G02X343063Y1724763I2003J229D01*
G02X343076Y1724992I2016J0D01*
G01Y1727404D01*
G02X343379Y1727706I303J-1D01*
G37*
G36*
G01X493379D02*
X497079D01*
G02X497382Y1727404I1J-302D01*
G01Y1717398D01*
G02X497079Y1717096I-303J1D01*
G01X493379D01*
G02X493076Y1717398I-1J302D01*
G01Y1719810D01*
G02X493063Y1720039I2003J229D01*
G02X493076Y1720268I2016J0D01*
G01Y1724534D01*
G02X493063Y1724763I2003J229D01*
G02X493076Y1724992I2016J0D01*
G01Y1727404D01*
G02X493379Y1727706I303J-1D01*
G37*
G36*
G01X509127D02*
X512827D01*
G02X513130Y1727404I1J-302D01*
G01Y1717398D01*
G02X512827Y1717096I-303J1D01*
G01X509127D01*
G02X508824Y1717398I-1J302D01*
G01Y1719810D01*
G02X508811Y1720039I2003J229D01*
G02X508824Y1720268I2016J0D01*
G01Y1724534D01*
G02X508811Y1724763I2003J229D01*
G02X508824Y1724992I2016J0D01*
G01Y1727404D01*
G02X509127Y1727706I303J-1D01*
G37*
G36*
G01X524875D02*
X528575D01*
G02X528878Y1727404I1J-302D01*
G01Y1717398D01*
G02X528575Y1717096I-303J1D01*
G01X524875D01*
G02X524572Y1717398I-1J302D01*
G01Y1719810D01*
G02X524559Y1720039I2003J229D01*
G02X524572Y1720268I2016J0D01*
G01Y1724534D01*
G02X524559Y1724763I2003J229D01*
G02X524572Y1724992I2016J0D01*
G01Y1727404D01*
G02X524875Y1727706I303J-1D01*
G37*
G36*
G01X540623D02*
X544323D01*
G02X544626Y1727404I1J-302D01*
G01Y1717398D01*
G02X544323Y1717096I-303J1D01*
G01X540623D01*
G02X540320Y1717398I-1J302D01*
G01Y1719810D01*
G02X540307Y1720039I2003J229D01*
G02X540320Y1720268I2016J0D01*
G01Y1724534D01*
G02X540307Y1724763I2003J229D01*
G02X540320Y1724992I2016J0D01*
G01Y1727404D01*
G02X540623Y1727706I303J-1D01*
G37*
G36*
G01X1304009D02*
X1307709D01*
G02X1308012Y1727404I1J-302D01*
G01Y1717398D01*
G02X1307709Y1717096I-303J1D01*
G01X1304009D01*
G02X1303706Y1717398I-1J302D01*
G01Y1719810D01*
G02X1303693Y1720039I2003J229D01*
G02X1303706Y1720268I2016J0D01*
G01Y1724534D01*
G02X1303693Y1724763I2003J229D01*
G02X1303706Y1724992I2016J0D01*
G01Y1727404D01*
G02X1304009Y1727706I303J-1D01*
G37*
G36*
G01X1319757D02*
X1323457D01*
G02X1323760Y1727404I1J-302D01*
G01Y1717398D01*
G02X1323457Y1717096I-303J1D01*
G01X1319757D01*
G02X1319454Y1717398I-1J302D01*
G01Y1719810D01*
G02X1319441Y1720039I2003J229D01*
G02X1319454Y1720268I2016J0D01*
G01Y1724534D01*
G02X1319441Y1724763I2003J229D01*
G02X1319454Y1724992I2016J0D01*
G01Y1727404D01*
G02X1319757Y1727706I303J-1D01*
G37*
G36*
G01X1335505D02*
X1339205D01*
G02X1339508Y1727404I1J-302D01*
G01Y1717398D01*
G02X1339205Y1717096I-303J1D01*
G01X1335505D01*
G02X1335202Y1717398I-1J302D01*
G01Y1719810D01*
G02X1335189Y1720039I2003J229D01*
G02X1335202Y1720268I2016J0D01*
G01Y1724534D01*
G02X1335189Y1724763I2003J229D01*
G02X1335202Y1724992I2016J0D01*
G01Y1727404D01*
G02X1335505Y1727706I303J-1D01*
G37*
G36*
G01X1351253D02*
X1354953D01*
G02X1355256Y1727404I1J-302D01*
G01Y1717398D01*
G02X1354953Y1717096I-303J1D01*
G01X1351253D01*
G02X1350950Y1717398I-1J302D01*
G01Y1719810D01*
G02X1350937Y1720039I2003J229D01*
G02X1350950Y1720268I2016J0D01*
G01Y1724534D01*
G02X1350937Y1724763I2003J229D01*
G02X1350950Y1724992I2016J0D01*
G01Y1727404D01*
G02X1351253Y1727706I303J-1D01*
G37*
G36*
G01X1501253D02*
X1504953D01*
G02X1505256Y1727404I1J-302D01*
G01Y1717398D01*
G02X1504953Y1717096I-303J1D01*
G01X1501253D01*
G02X1500950Y1717398I-1J302D01*
G01Y1719810D01*
G02X1500937Y1720039I2003J229D01*
G02X1500950Y1720268I2016J0D01*
G01Y1724534D01*
G02X1500937Y1724763I2003J229D01*
G02X1500950Y1724992I2016J0D01*
G01Y1727404D01*
G02X1501253Y1727706I303J-1D01*
G37*
G36*
G01X1517001D02*
X1520701D01*
G02X1521004Y1727404I1J-302D01*
G01Y1717398D01*
G02X1520701Y1717096I-303J1D01*
G01X1517001D01*
G02X1516698Y1717398I-1J302D01*
G01Y1719810D01*
G02X1516685Y1720039I2003J229D01*
G02X1516698Y1720268I2016J0D01*
G01Y1724534D01*
G02X1516685Y1724763I2003J229D01*
G02X1516698Y1724992I2016J0D01*
G01Y1727404D01*
G02X1517001Y1727706I303J-1D01*
G37*
G36*
G01X1532749D02*
X1536449D01*
G02X1536752Y1727404I1J-302D01*
G01Y1717398D01*
G02X1536449Y1717096I-303J1D01*
G01X1532749D01*
G02X1532446Y1717398I-1J302D01*
G01Y1719810D01*
G02X1532433Y1720039I2003J229D01*
G02X1532446Y1720268I2016J0D01*
G01Y1724534D01*
G02X1532433Y1724763I2003J229D01*
G02X1532446Y1724992I2016J0D01*
G01Y1727404D01*
G02X1532749Y1727706I303J-1D01*
G37*
G36*
G01X1548497D02*
X1552197D01*
G02X1552500Y1727404I1J-302D01*
G01Y1717398D01*
G02X1552197Y1717096I-303J1D01*
G01X1548497D01*
G02X1548194Y1717398I-1J302D01*
G01Y1719810D01*
G02X1548181Y1720039I2003J229D01*
G02X1548194Y1720268I2016J0D01*
G01Y1724534D01*
G02X1548181Y1724763I2003J229D01*
G02X1548194Y1724992I2016J0D01*
G01Y1727404D01*
G02X1548497Y1727706I303J-1D01*
G37*
G36*
G01X237080Y1731644D02*
X240780D01*
G02X241082Y1731341I-1J-303D01*
G01Y1721335D01*
G02X240780Y1721032I-302J-1D01*
G01X237080D01*
G02X236778Y1721335I1J303D01*
G01Y1723739D01*
G02X236764Y1723976I2002J237D01*
G02X236778Y1724213I2016J0D01*
G01Y1728463D01*
G02X236764Y1728700I2002J237D01*
G02X236778Y1728937I2016J0D01*
G01Y1731341D01*
G02X237080Y1731644I302J1D01*
G37*
G36*
G01X252828D02*
X256528D01*
G02X256830Y1731341I-1J-303D01*
G01Y1721335D01*
G02X256528Y1721032I-302J-1D01*
G01X252828D01*
G02X252526Y1721335I1J303D01*
G01Y1723739D01*
G02X252512Y1723976I2002J237D01*
G02X252526Y1724213I2016J0D01*
G01Y1728463D01*
G02X252512Y1728700I2002J237D01*
G02X252526Y1728937I2016J0D01*
G01Y1731341D01*
G02X252828Y1731644I302J1D01*
G37*
G36*
G01X268576D02*
X272276D01*
G02X272578Y1731341I-1J-303D01*
G01Y1721335D01*
G02X272276Y1721032I-302J-1D01*
G01X268576D01*
G02X268274Y1721335I1J303D01*
G01Y1723739D01*
G02X268260Y1723976I2002J237D01*
G02X268274Y1724213I2016J0D01*
G01Y1728463D01*
G02X268260Y1728700I2002J237D01*
G02X268274Y1728937I2016J0D01*
G01Y1731341D01*
G02X268576Y1731644I302J1D01*
G37*
G36*
G01X284324D02*
X288024D01*
G02X288326Y1731341I-1J-303D01*
G01Y1721335D01*
G02X288024Y1721032I-302J-1D01*
G01X284324D01*
G02X284022Y1721335I1J303D01*
G01Y1723739D01*
G02X284008Y1723976I2002J237D01*
G02X284022Y1724213I2016J0D01*
G01Y1728463D01*
G02X284008Y1728700I2002J237D01*
G02X284022Y1728937I2016J0D01*
G01Y1731341D01*
G02X284324Y1731644I302J1D01*
G37*
G36*
G01X304009D02*
X307709D01*
G02X308012Y1731341I0J-303D01*
G01Y1721335D01*
G02X307709Y1721032I-303J0D01*
G01X304009D01*
G02X303706Y1721335I0J303D01*
G01Y1723747D01*
G02X303693Y1723976I2003J229D01*
G02X303706Y1724205I2016J0D01*
G01Y1728471D01*
G02X303693Y1728700I2003J229D01*
G02X303706Y1728929I2016J0D01*
G01Y1731341D01*
G02X304009Y1731644I303J0D01*
G37*
G36*
G01X319757D02*
X323457D01*
G02X323760Y1731341I0J-303D01*
G01Y1721335D01*
G02X323457Y1721032I-303J0D01*
G01X319757D01*
G02X319454Y1721335I0J303D01*
G01Y1723747D01*
G02X319441Y1723976I2003J229D01*
G02X319454Y1724205I2016J0D01*
G01Y1728471D01*
G02X319441Y1728700I2003J229D01*
G02X319454Y1728929I2016J0D01*
G01Y1731341D01*
G02X319757Y1731644I303J0D01*
G37*
G36*
G01X335505D02*
X339205D01*
G02X339508Y1731341I0J-303D01*
G01Y1721335D01*
G02X339205Y1721032I-303J0D01*
G01X335505D01*
G02X335202Y1721335I0J303D01*
G01Y1723747D01*
G02X335189Y1723976I2003J229D01*
G02X335202Y1724205I2016J0D01*
G01Y1728471D01*
G02X335189Y1728700I2003J229D01*
G02X335202Y1728929I2016J0D01*
G01Y1731341D01*
G02X335505Y1731644I303J0D01*
G37*
G36*
G01X351253D02*
X354953D01*
G02X355256Y1731341I0J-303D01*
G01Y1721335D01*
G02X354953Y1721032I-303J0D01*
G01X351253D01*
G02X350950Y1721335I0J303D01*
G01Y1723747D01*
G02X350937Y1723976I2003J229D01*
G02X350950Y1724205I2016J0D01*
G01Y1728471D01*
G02X350937Y1728700I2003J229D01*
G02X350950Y1728929I2016J0D01*
G01Y1731341D01*
G02X351253Y1731644I303J0D01*
G37*
G36*
G01X501253D02*
X504953D01*
G02X505256Y1731341I0J-303D01*
G01Y1721335D01*
G02X504953Y1721032I-303J0D01*
G01X501253D01*
G02X500950Y1721335I0J303D01*
G01Y1723747D01*
G02X500937Y1723976I2003J229D01*
G02X500950Y1724205I2016J0D01*
G01Y1728471D01*
G02X500937Y1728700I2003J229D01*
G02X500950Y1728929I2016J0D01*
G01Y1731341D01*
G02X501253Y1731644I303J0D01*
G37*
G36*
G01X517001D02*
X520701D01*
G02X521004Y1731341I0J-303D01*
G01Y1721335D01*
G02X520701Y1721032I-303J0D01*
G01X517001D01*
G02X516698Y1721335I0J303D01*
G01Y1723747D01*
G02X516685Y1723976I2003J229D01*
G02X516698Y1724205I2016J0D01*
G01Y1728471D01*
G02X516685Y1728700I2003J229D01*
G02X516698Y1728929I2016J0D01*
G01Y1731341D01*
G02X517001Y1731644I303J0D01*
G37*
G36*
G01X532749D02*
X536449D01*
G02X536752Y1731341I0J-303D01*
G01Y1721335D01*
G02X536449Y1721032I-303J0D01*
G01X532749D01*
G02X532446Y1721335I0J303D01*
G01Y1723747D01*
G02X532433Y1723976I2003J229D01*
G02X532446Y1724205I2016J0D01*
G01Y1728471D01*
G02X532433Y1728700I2003J229D01*
G02X532446Y1728929I2016J0D01*
G01Y1731341D01*
G02X532749Y1731644I303J0D01*
G37*
G36*
G01X548497D02*
X552197D01*
G02X552500Y1731341I0J-303D01*
G01Y1721335D01*
G02X552197Y1721032I-303J0D01*
G01X548497D01*
G02X548194Y1721335I0J303D01*
G01Y1723747D01*
G02X548181Y1723976I2003J229D01*
G02X548194Y1724205I2016J0D01*
G01Y1728471D01*
G02X548181Y1728700I2003J229D01*
G02X548194Y1728929I2016J0D01*
G01Y1731341D01*
G02X548497Y1731644I303J0D01*
G37*
G36*
G01X568182D02*
X571882D01*
G02X572184Y1731341I-1J-303D01*
G01Y1721335D01*
G02X571882Y1721032I-302J-1D01*
G01X568182D01*
G02X567880Y1721335I1J303D01*
G01Y1723739D01*
G02X567866Y1723976I2002J237D01*
G02X567880Y1724213I2016J0D01*
G01Y1728463D01*
G02X567866Y1728700I2002J237D01*
G02X567880Y1728937I2016J0D01*
G01Y1731341D01*
G02X568182Y1731644I302J1D01*
G37*
G36*
G01X583930D02*
X587630D01*
G02X587932Y1731341I-1J-303D01*
G01Y1721335D01*
G02X587630Y1721032I-302J-1D01*
G01X583930D01*
G02X583628Y1721335I1J303D01*
G01Y1723739D01*
G02X583614Y1723976I2002J237D01*
G02X583628Y1724213I2016J0D01*
G01Y1728463D01*
G02X583614Y1728700I2002J237D01*
G02X583628Y1728937I2016J0D01*
G01Y1731341D01*
G02X583930Y1731644I302J1D01*
G37*
G36*
G01X599678D02*
X603378D01*
G02X603680Y1731341I-1J-303D01*
G01Y1721335D01*
G02X603378Y1721032I-302J-1D01*
G01X599678D01*
G02X599376Y1721335I1J303D01*
G01Y1723739D01*
G02X599362Y1723976I2002J237D01*
G02X599376Y1724213I2016J0D01*
G01Y1728463D01*
G02X599362Y1728700I2002J237D01*
G02X599376Y1728937I2016J0D01*
G01Y1731341D01*
G02X599678Y1731644I302J1D01*
G37*
G36*
G01X615426D02*
X619126D01*
G02X619428Y1731341I-1J-303D01*
G01Y1721335D01*
G02X619126Y1721032I-302J-1D01*
G01X615426D01*
G02X615124Y1721335I1J303D01*
G01Y1723739D01*
G02X615110Y1723976I2002J237D01*
G02X615124Y1724213I2016J0D01*
G01Y1728463D01*
G02X615110Y1728700I2002J237D01*
G02X615124Y1728937I2016J0D01*
G01Y1731341D01*
G02X615426Y1731644I302J1D01*
G37*
G36*
G01X1244954D02*
X1248654D01*
G02X1248956Y1731341I-1J-303D01*
G01Y1721335D01*
G02X1248654Y1721032I-302J-1D01*
G01X1244954D01*
G02X1244652Y1721335I1J303D01*
G01Y1723739D01*
G02X1244638Y1723976I2002J237D01*
G02X1244652Y1724213I2016J0D01*
G01Y1728463D01*
G02X1244638Y1728700I2002J237D01*
G02X1244652Y1728937I2016J0D01*
G01Y1731341D01*
G02X1244954Y1731644I302J1D01*
G37*
G36*
G01X1260702D02*
X1264402D01*
G02X1264704Y1731341I-1J-303D01*
G01Y1721335D01*
G02X1264402Y1721032I-302J-1D01*
G01X1260702D01*
G02X1260400Y1721335I1J303D01*
G01Y1723739D01*
G02X1260386Y1723976I2002J237D01*
G02X1260400Y1724213I2016J0D01*
G01Y1728463D01*
G02X1260386Y1728700I2002J237D01*
G02X1260400Y1728937I2016J0D01*
G01Y1731341D01*
G02X1260702Y1731644I302J1D01*
G37*
G36*
G01X1276450D02*
X1280150D01*
G02X1280452Y1731341I-1J-303D01*
G01Y1721335D01*
G02X1280150Y1721032I-302J-1D01*
G01X1276450D01*
G02X1276148Y1721335I1J303D01*
G01Y1723739D01*
G02X1276134Y1723976I2002J237D01*
G02X1276148Y1724213I2016J0D01*
G01Y1728463D01*
G02X1276134Y1728700I2002J237D01*
G02X1276148Y1728937I2016J0D01*
G01Y1731341D01*
G02X1276450Y1731644I302J1D01*
G37*
G36*
G01X1292198D02*
X1295898D01*
G02X1296200Y1731341I-1J-303D01*
G01Y1721335D01*
G02X1295898Y1721032I-302J-1D01*
G01X1292198D01*
G02X1291896Y1721335I1J303D01*
G01Y1723739D01*
G02X1291882Y1723976I2002J237D01*
G02X1291896Y1724213I2016J0D01*
G01Y1728463D01*
G02X1291882Y1728700I2002J237D01*
G02X1291896Y1728937I2016J0D01*
G01Y1731341D01*
G02X1292198Y1731644I302J1D01*
G37*
G36*
G01X1311883D02*
X1315583D01*
G02X1315886Y1731341I0J-303D01*
G01Y1721335D01*
G02X1315583Y1721032I-303J0D01*
G01X1311883D01*
G02X1311580Y1721335I0J303D01*
G01Y1723747D01*
G02X1311567Y1723976I2003J229D01*
G02X1311580Y1724205I2016J0D01*
G01Y1728471D01*
G02X1311567Y1728700I2003J229D01*
G02X1311580Y1728929I2016J0D01*
G01Y1731341D01*
G02X1311883Y1731644I303J0D01*
G37*
G36*
G01X1327631D02*
X1331331D01*
G02X1331634Y1731341I0J-303D01*
G01Y1721335D01*
G02X1331331Y1721032I-303J0D01*
G01X1327631D01*
G02X1327328Y1721335I0J303D01*
G01Y1723747D01*
G02X1327315Y1723976I2003J229D01*
G02X1327328Y1724205I2016J0D01*
G01Y1728471D01*
G02X1327315Y1728700I2003J229D01*
G02X1327328Y1728929I2016J0D01*
G01Y1731341D01*
G02X1327631Y1731644I303J0D01*
G37*
G36*
G01X1343379D02*
X1347079D01*
G02X1347382Y1731341I0J-303D01*
G01Y1721335D01*
G02X1347079Y1721032I-303J0D01*
G01X1343379D01*
G02X1343076Y1721335I0J303D01*
G01Y1723747D01*
G02X1343063Y1723976I2003J229D01*
G02X1343076Y1724205I2016J0D01*
G01Y1728471D01*
G02X1343063Y1728700I2003J229D01*
G02X1343076Y1728929I2016J0D01*
G01Y1731341D01*
G02X1343379Y1731644I303J0D01*
G37*
G36*
G01X1359127D02*
X1362827D01*
G02X1363130Y1731341I0J-303D01*
G01Y1721335D01*
G02X1362827Y1721032I-303J0D01*
G01X1359127D01*
G02X1358824Y1721335I0J303D01*
G01Y1723747D01*
G02X1358811Y1723976I2003J229D01*
G02X1358824Y1724205I2016J0D01*
G01Y1728471D01*
G02X1358811Y1728700I2003J229D01*
G02X1358824Y1728929I2016J0D01*
G01Y1731341D01*
G02X1359127Y1731644I303J0D01*
G37*
G36*
G01X1509127D02*
X1512827D01*
G02X1513130Y1731341I0J-303D01*
G01Y1721335D01*
G02X1512827Y1721032I-303J0D01*
G01X1509127D01*
G02X1508824Y1721335I0J303D01*
G01Y1723747D01*
G02X1508811Y1723976I2003J229D01*
G02X1508824Y1724205I2016J0D01*
G01Y1728471D01*
G02X1508811Y1728700I2003J229D01*
G02X1508824Y1728929I2016J0D01*
G01Y1731341D01*
G02X1509127Y1731644I303J0D01*
G37*
G36*
G01X1524875D02*
X1528575D01*
G02X1528878Y1731341I0J-303D01*
G01Y1721335D01*
G02X1528575Y1721032I-303J0D01*
G01X1524875D01*
G02X1524572Y1721335I0J303D01*
G01Y1723747D01*
G02X1524559Y1723976I2003J229D01*
G02X1524572Y1724205I2016J0D01*
G01Y1728471D01*
G02X1524559Y1728700I2003J229D01*
G02X1524572Y1728929I2016J0D01*
G01Y1731341D01*
G02X1524875Y1731644I303J0D01*
G37*
G36*
G01X1540623D02*
X1544323D01*
G02X1544626Y1731341I0J-303D01*
G01Y1721335D01*
G02X1544323Y1721032I-303J0D01*
G01X1540623D01*
G02X1540320Y1721335I0J303D01*
G01Y1723747D01*
G02X1540307Y1723976I2003J229D01*
G02X1540320Y1724205I2016J0D01*
G01Y1728471D01*
G02X1540307Y1728700I2003J229D01*
G02X1540320Y1728929I2016J0D01*
G01Y1731341D01*
G02X1540623Y1731644I303J0D01*
G37*
G36*
G01X1556371D02*
X1560071D01*
G02X1560374Y1731341I0J-303D01*
G01Y1721335D01*
G02X1560071Y1721032I-303J0D01*
G01X1556371D01*
G02X1556068Y1721335I0J303D01*
G01Y1723747D01*
G02X1556055Y1723976I2003J229D01*
G02X1556068Y1724205I2016J0D01*
G01Y1728471D01*
G02X1556055Y1728700I2003J229D01*
G02X1556068Y1728929I2016J0D01*
G01Y1731341D01*
G02X1556371Y1731644I303J0D01*
G37*
G36*
G01X1576056D02*
X1579756D01*
G02X1580058Y1731341I-1J-303D01*
G01Y1721335D01*
G02X1579756Y1721032I-302J-1D01*
G01X1576056D01*
G02X1575754Y1721335I1J303D01*
G01Y1723739D01*
G02X1575740Y1723976I2002J237D01*
G02X1575754Y1724213I2016J0D01*
G01Y1728463D01*
G02X1575740Y1728700I2002J237D01*
G02X1575754Y1728937I2016J0D01*
G01Y1731341D01*
G02X1576056Y1731644I302J1D01*
G37*
G36*
G01X1591804D02*
X1595504D01*
G02X1595806Y1731341I-1J-303D01*
G01Y1721335D01*
G02X1595504Y1721032I-302J-1D01*
G01X1591804D01*
G02X1591502Y1721335I1J303D01*
G01Y1723739D01*
G02X1591488Y1723976I2002J237D01*
G02X1591502Y1724213I2016J0D01*
G01Y1728463D01*
G02X1591488Y1728700I2002J237D01*
G02X1591502Y1728937I2016J0D01*
G01Y1731341D01*
G02X1591804Y1731644I302J1D01*
G37*
G36*
G01X1607552D02*
X1611252D01*
G02X1611554Y1731341I-1J-303D01*
G01Y1721335D01*
G02X1611252Y1721032I-302J-1D01*
G01X1607552D01*
G02X1607250Y1721335I1J303D01*
G01Y1723739D01*
G02X1607236Y1723976I2002J237D01*
G02X1607250Y1724213I2016J0D01*
G01Y1728463D01*
G02X1607236Y1728700I2002J237D01*
G02X1607250Y1728937I2016J0D01*
G01Y1731341D01*
G02X1607552Y1731644I302J1D01*
G37*
G36*
G01X1623300D02*
X1627000D01*
G02X1627302Y1731341I-1J-303D01*
G01Y1721335D01*
G02X1627000Y1721032I-302J-1D01*
G01X1623300D01*
G02X1622998Y1721335I1J303D01*
G01Y1723739D01*
G02X1622984Y1723976I2002J237D01*
G02X1622998Y1724213I2016J0D01*
G01Y1728463D01*
G02X1622984Y1728700I2002J237D01*
G02X1622998Y1728937I2016J0D01*
G01Y1731341D01*
G02X1623300Y1731644I302J1D01*
G37*
G36*
G01X105651Y1575002D02*
X102251D01*
G02Y1578006I0J1502D01*
G01X105651D01*
G02Y1575002I0J-1502D01*
G37*
G36*
G01X74218Y1574006D02*
X77618D01*
G02Y1571002I0J-1502D01*
G01X74218D01*
G02Y1574006I0J1502D01*
G37*
G36*
G01X76369Y1508958D02*
X79769D01*
G02Y1505954I0J-1502D01*
G01X76369D01*
G02Y1508958I0J1502D01*
G37*
G36*
G01X391330Y1583652D02*
X387930D01*
G02Y1586658I0J1503D01*
G01X391330D01*
G02Y1583652I0J-1503D01*
G37*
G36*
G01X148938Y1515872D02*
X145538D01*
G02Y1518876I0J1502D01*
G01X148938D01*
G02Y1515872I0J-1502D01*
G37*
G36*
G01X164710Y1519516D02*
X168110D01*
G02Y1516512I0J-1502D01*
G01X164710D01*
G02Y1519516I0J1502D01*
G37*
G36*
G01X89264Y1509114D02*
X92664D01*
G02Y1506108I0J-1503D01*
G01X89264D01*
G02Y1509114I0J1503D01*
G37*
G36*
G01X167266Y1571470D02*
X170666D01*
G02Y1568466I0J-1502D01*
G01X167266D01*
G02Y1571470I0J1502D01*
G37*
G36*
G01X1346792Y1615794D02*
X1350192D01*
G02Y1612790I0J-1502D01*
G01X1346792D01*
G02Y1615794I0J1502D01*
G37*
G36*
G01X1358852D02*
X1362252D01*
G02Y1612790I0J-1502D01*
G01X1358852D01*
G02Y1615794I0J1502D01*
G37*
G36*
G01X1365612Y1591596D02*
X1369012D01*
G02Y1588592I0J-1502D01*
G01X1365612D01*
G02Y1591596I0J1502D01*
G37*
G36*
G01Y1579684D02*
X1369012D01*
G02Y1576680I0J-1502D01*
G01X1365612D01*
G02Y1579684I0J1502D01*
G37*
G36*
G01X1305312D02*
X1308712D01*
G02Y1576680I0J-1502D01*
G01X1305312D01*
G02Y1579684I0J1502D01*
G37*
G36*
G01X1293252Y1591596D02*
X1296652D01*
G02Y1588592I0J-1502D01*
G01X1293252D01*
G02Y1591596I0J1502D01*
G37*
G36*
G01X1310612Y1615794D02*
X1314012D01*
G02Y1612790I0J-1502D01*
G01X1310612D01*
G02Y1615794I0J1502D01*
G37*
G36*
G01X1262372Y1603882D02*
X1265772D01*
G02Y1600878I0J-1502D01*
G01X1262372D01*
G02Y1603882I0J1502D01*
G37*
G36*
G01X1286492Y1615794D02*
X1289892D01*
G02Y1612790I0J-1502D01*
G01X1286492D01*
G02Y1615794I0J1502D01*
G37*
G36*
G01X1262372D02*
X1265772D01*
G02Y1612790I0J-1502D01*
G01X1262372D01*
G02Y1615794I0J1502D01*
G37*
G36*
G01X1334732Y1603882D02*
X1338132D01*
G02Y1600878I0J-1502D01*
G01X1334732D01*
G02Y1603882I0J1502D01*
G37*
G36*
G01X1220892Y1579684D02*
X1224292D01*
G02Y1576680I0J-1502D01*
G01X1220892D01*
G02Y1579684I0J1502D01*
G37*
G36*
G01X1334732Y1615794D02*
X1338132D01*
G02Y1612790I0J-1502D01*
G01X1334732D01*
G02Y1615794I0J1502D01*
G37*
G36*
G01X1370912Y1603882D02*
X1374312D01*
G02Y1600878I0J-1502D01*
G01X1370912D01*
G02Y1603882I0J1502D01*
G37*
G36*
G01X1214132D02*
X1217532D01*
G02Y1600878I0J-1502D01*
G01X1214132D01*
G02Y1603882I0J1502D01*
G37*
G36*
G01X1286492D02*
X1289892D01*
G02Y1600878I0J-1502D01*
G01X1286492D01*
G02Y1603882I0J1502D01*
G37*
G36*
G01X1298552D02*
X1301952D01*
G02Y1600878I0J-1502D01*
G01X1298552D01*
G02Y1603882I0J1502D01*
G37*
G36*
G01X1353552Y1579684D02*
X1356952D01*
G02Y1576680I0J-1502D01*
G01X1353552D01*
G02Y1579684I0J1502D01*
G37*
G36*
G01X1341492Y1591596D02*
X1344892D01*
G02Y1588592I0J-1502D01*
G01X1341492D01*
G02Y1591596I0J1502D01*
G37*
G36*
G01X1370912Y1615794D02*
X1374312D01*
G02Y1612790I0J-1502D01*
G01X1370912D01*
G02Y1615794I0J1502D01*
G37*
G36*
G01X1269132Y1591596D02*
X1272532D01*
G02Y1588592I0J-1502D01*
G01X1269132D01*
G02Y1591596I0J1502D01*
G37*
G36*
G01X1238252Y1603882D02*
X1241652D01*
G02Y1600878I0J-1502D01*
G01X1238252D01*
G02Y1603882I0J1502D01*
G37*
G36*
G01X1353552Y1591596D02*
X1356952D01*
G02Y1588592I0J-1502D01*
G01X1353552D01*
G02Y1591596I0J1502D01*
G37*
G36*
G01X1214132Y1615794D02*
X1217532D01*
G02Y1612790I0J-1502D01*
G01X1214132D01*
G02Y1615794I0J1502D01*
G37*
G36*
G01X1226192Y1603882D02*
X1229592D01*
G02Y1600878I0J-1502D01*
G01X1226192D01*
G02Y1603882I0J1502D01*
G37*
G36*
G01X1208832Y1579684D02*
X1212232D01*
G02Y1576680I0J-1502D01*
G01X1208832D01*
G02Y1579684I0J1502D01*
G37*
G36*
G01Y1591596D02*
X1212232D01*
G02Y1588592I0J-1502D01*
G01X1208832D01*
G02Y1591596I0J1502D01*
G37*
G36*
G01X1341492Y1579684D02*
X1344892D01*
G02Y1576680I0J-1502D01*
G01X1341492D01*
G02Y1579684I0J1502D01*
G37*
G36*
G01X1250312Y1615794D02*
X1253712D01*
G02Y1612790I0J-1502D01*
G01X1250312D01*
G02Y1615794I0J1502D01*
G37*
G36*
G01X1232952Y1579684D02*
X1236352D01*
G02Y1576680I0J-1502D01*
G01X1232952D01*
G02Y1579684I0J1502D01*
G37*
G36*
G01Y1591596D02*
X1236352D01*
G02Y1588592I0J-1502D01*
G01X1232952D01*
G02Y1591596I0J1502D01*
G37*
G36*
G01X1196772Y1579684D02*
X1200172D01*
G02Y1576680I0J-1502D01*
G01X1196772D01*
G02Y1579684I0J1502D01*
G37*
G36*
G01X1257072D02*
X1260472D01*
G02Y1576680I0J-1502D01*
G01X1257072D01*
G02Y1579684I0J1502D01*
G37*
G36*
G01X1220892Y1591596D02*
X1224292D01*
G02Y1588592I0J-1502D01*
G01X1220892D01*
G02Y1591596I0J1502D01*
G37*
G36*
G01X1269132Y1579684D02*
X1272532D01*
G02Y1576680I0J-1502D01*
G01X1269132D01*
G02Y1579684I0J1502D01*
G37*
G36*
G01X1305312Y1591596D02*
X1308712D01*
G02Y1588592I0J-1502D01*
G01X1305312D01*
G02Y1591596I0J1502D01*
G37*
G36*
G01X1245012D02*
X1248412D01*
G02Y1588592I0J-1502D01*
G01X1245012D01*
G02Y1591596I0J1502D01*
G37*
G36*
G01X1250312Y1603882D02*
X1253712D01*
G02Y1600878I0J-1502D01*
G01X1250312D01*
G02Y1603882I0J1502D01*
G37*
G36*
G01X1317372Y1579684D02*
X1320772D01*
G02Y1576680I0J-1502D01*
G01X1317372D01*
G02Y1579684I0J1502D01*
G37*
G36*
G01X1358852Y1603882D02*
X1362252D01*
G02Y1600878I0J-1502D01*
G01X1358852D01*
G02Y1603882I0J1502D01*
G37*
G36*
G01X1202072D02*
X1205472D01*
G02Y1600878I0J-1502D01*
G01X1202072D01*
G02Y1603882I0J1502D01*
G37*
G36*
G01Y1615794D02*
X1205472D01*
G02Y1612790I0J-1502D01*
G01X1202072D01*
G02Y1615794I0J1502D01*
G37*
G36*
G01X1322672Y1603882D02*
X1326072D01*
G02Y1600878I0J-1502D01*
G01X1322672D01*
G02Y1603882I0J1502D01*
G37*
G36*
G01X1310612D02*
X1314012D01*
G02Y1600878I0J-1502D01*
G01X1310612D01*
G02Y1603882I0J1502D01*
G37*
G36*
G01X1274432Y1615794D02*
X1277832D01*
G02Y1612790I0J-1502D01*
G01X1274432D01*
G02Y1615794I0J1502D01*
G37*
G36*
G01X1329432Y1579684D02*
X1332832D01*
G02Y1576680I0J-1502D01*
G01X1329432D01*
G02Y1579684I0J1502D01*
G37*
G36*
G01X1346792Y1603882D02*
X1350192D01*
G02Y1600878I0J-1502D01*
G01X1346792D01*
G02Y1603882I0J1502D01*
G37*
G36*
G01X1317372Y1591596D02*
X1320772D01*
G02Y1588592I0J-1502D01*
G01X1317372D01*
G02Y1591596I0J1502D01*
G37*
G36*
G01X1329432D02*
X1332832D01*
G02Y1588592I0J-1502D01*
G01X1329432D01*
G02Y1591596I0J1502D01*
G37*
G36*
G01X1322672Y1615794D02*
X1326072D01*
G02Y1612790I0J-1502D01*
G01X1322672D01*
G02Y1615794I0J1502D01*
G37*
G36*
G01X1281192Y1591596D02*
X1284592D01*
G02Y1588592I0J-1502D01*
G01X1281192D01*
G02Y1591596I0J1502D01*
G37*
G36*
G01X1196772D02*
X1200172D01*
G02Y1588592I0J-1502D01*
G01X1196772D01*
G02Y1591596I0J1502D01*
G37*
G36*
G01X1226192Y1615794D02*
X1229592D01*
G02Y1612790I0J-1502D01*
G01X1226192D01*
G02Y1615794I0J1502D01*
G37*
G36*
G01X1293252Y1579684D02*
X1296652D01*
G02Y1576680I0J-1502D01*
G01X1293252D01*
G02Y1579684I0J1502D01*
G37*
G36*
G01X1298552Y1615794D02*
X1301952D01*
G02Y1612790I0J-1502D01*
G01X1298552D01*
G02Y1615794I0J1502D01*
G37*
G36*
G01X1281192Y1579684D02*
X1284592D01*
G02Y1576680I0J-1502D01*
G01X1281192D01*
G02Y1579684I0J1502D01*
G37*
G36*
G01X1245012D02*
X1248412D01*
G02Y1576680I0J-1502D01*
G01X1245012D01*
G02Y1579684I0J1502D01*
G37*
G36*
G01X1257072Y1591596D02*
X1260472D01*
G02Y1588592I0J-1502D01*
G01X1257072D01*
G02Y1591596I0J1502D01*
G37*
G36*
G01X1274432Y1603882D02*
X1277832D01*
G02Y1600878I0J-1502D01*
G01X1274432D01*
G02Y1603882I0J1502D01*
G37*
G36*
G01X1238252Y1615794D02*
X1241652D01*
G02Y1612790I0J-1502D01*
G01X1238252D01*
G02Y1615794I0J1502D01*
G37*
G36*
G01X1474516Y730492D02*
G02X1473515Y728758I-2002J0D01*
G01X1469877Y726657D01*
G02X1468878Y726390I-999J1736D01*
G01X1468876D01*
G02X1466874Y728392I0J2002D01*
G02X1467875Y730126I2002J0D01*
G01X1471513Y732227D01*
G02X1472512Y732494I999J-1736D01*
G01X1472514D01*
G02X1474516Y730492I0J-2002D01*
G37*
G36*
G01X1477716Y717492D02*
G02X1476715Y715758I-2002J0D01*
G01X1473077Y713657D01*
G02X1472078Y713390I-999J1736D01*
G01X1472076D01*
G02X1470074Y715392I0J2002D01*
G02X1471075Y717126I2002J0D01*
G01X1474713Y719227D01*
G02X1475712Y719494I999J-1736D01*
G01X1475714D01*
G02X1477716Y717492I0J-2002D01*
G37*
G36*
G01Y702992D02*
G02X1476715Y701258I-2002J0D01*
G01X1473077Y699157D01*
G02X1472078Y698890I-999J1736D01*
G01X1472076D01*
G02X1470074Y700892I0J2002D01*
G02X1471075Y702626I2002J0D01*
G01X1474713Y704727D01*
G02X1475712Y704994I999J-1736D01*
G01X1475714D01*
G02X1477716Y702992I0J-2002D01*
G37*
G36*
G01Y688492D02*
G02X1476715Y686758I-2002J0D01*
G01X1473077Y684657D01*
G02X1472078Y684390I-999J1736D01*
G01X1472076D01*
G02X1470074Y686392I0J2002D01*
G02X1471075Y688126I2002J0D01*
G01X1474713Y690227D01*
G02X1475712Y690494I999J-1736D01*
G01X1475714D01*
G02X1477716Y688492I0J-2002D01*
G37*
G36*
G01Y673992D02*
G02X1476715Y672258I-2002J0D01*
G01X1473077Y670157D01*
G02X1472078Y669890I-999J1736D01*
G01X1472076D01*
G02X1470074Y671892I0J2002D01*
G02X1471075Y673626I2002J0D01*
G01X1474713Y675727D01*
G02X1475712Y675994I999J-1736D01*
G01X1475714D01*
G02X1477716Y673992I0J-2002D01*
G37*
G36*
G01Y659492D02*
G02X1476715Y657758I-2002J0D01*
G01X1473077Y655657D01*
G02X1472078Y655390I-999J1736D01*
G01X1472076D01*
G02X1470074Y657392I0J2002D01*
G02X1471075Y659126I2002J0D01*
G01X1474713Y661227D01*
G02X1475712Y661494I999J-1736D01*
G01X1475714D01*
G02X1477716Y659492I0J-2002D01*
G37*
G36*
G01X1455174Y716992D02*
G02X1457176Y718994I2002J0D01*
G01X1457178D01*
G02X1458177Y718727I0J-2003D01*
G01X1461815Y716626D01*
G02X1462816Y714892I-1001J-1734D01*
G02X1460814Y712890I-2002J0D01*
G01X1460812D01*
G02X1459813Y713157I0J2003D01*
G01X1456175Y715258D01*
G02X1455174Y716992I1001J1734D01*
G37*
G36*
G01Y704992D02*
G02X1457176Y706994I2002J0D01*
G01X1457178D01*
G02X1458177Y706727I0J-2003D01*
G01X1461815Y704626D01*
G02X1462816Y702892I-1001J-1734D01*
G02X1460814Y700890I-2002J0D01*
G01X1460812D01*
G02X1459813Y701157I0J2003D01*
G01X1456175Y703258D01*
G02X1455174Y704992I1001J1734D01*
G37*
G36*
G01Y692992D02*
G02X1457176Y694994I2002J0D01*
G01X1457178D01*
G02X1458177Y694727I0J-2003D01*
G01X1461815Y692626D01*
G02X1462816Y690892I-1001J-1734D01*
G02X1460814Y688890I-2002J0D01*
G01X1460812D01*
G02X1459813Y689157I0J2003D01*
G01X1456175Y691258D01*
G02X1455174Y692992I1001J1734D01*
G37*
G36*
G01Y680992D02*
G02X1457176Y682994I2002J0D01*
G01X1457178D01*
G02X1458177Y682727I0J-2003D01*
G01X1461815Y680626D01*
G02X1462816Y678892I-1001J-1734D01*
G02X1460814Y676890I-2002J0D01*
G01X1460812D01*
G02X1459813Y677157I0J2003D01*
G01X1456175Y679258D01*
G02X1455174Y680992I1001J1734D01*
G37*
G36*
G01Y668992D02*
G02X1457176Y670994I2002J0D01*
G01X1457178D01*
G02X1458177Y670727I0J-2003D01*
G01X1461815Y668626D01*
G02X1462816Y666892I-1001J-1734D01*
G02X1460814Y664890I-2002J0D01*
G01X1460812D01*
G02X1459813Y665157I0J2003D01*
G01X1456175Y667258D01*
G02X1455174Y668992I1001J1734D01*
G37*
G36*
G01Y656992D02*
G02X1457176Y658994I2002J0D01*
G01X1457178D01*
G02X1458177Y658727I0J-2003D01*
G01X1461815Y656626D01*
G02X1462816Y654892I-1001J-1734D01*
G02X1460814Y652890I-2002J0D01*
G01X1460812D01*
G02X1459813Y653157I0J2003D01*
G01X1456175Y655258D01*
G02X1455174Y656992I1001J1734D01*
G37*
G36*
G01X1390978Y737198D02*
G02X1389977Y735464I-2002J0D01*
G01X1386339Y733363D01*
G02X1385340Y733096I-999J1736D01*
G01X1385338D01*
G02X1383336Y735098I0J2002D01*
G02X1384337Y736832I2002J0D01*
G01X1387975Y738933D01*
G02X1388974Y739200I999J-1736D01*
G01X1388976D01*
G02X1390978Y737198I0J-2002D01*
G37*
G36*
G01X1395208Y722735D02*
G02X1394207Y721001I-2002J0D01*
G01X1390569Y718900D01*
G02X1389570Y718632I-1001J1735D01*
G01X1389568D01*
G02X1387566Y720635I1J2003D01*
G02X1388567Y722369I2002J0D01*
G01X1392205Y724470D01*
G02X1393204Y724738I1001J-1735D01*
G01X1393206D01*
G02X1395208Y722735I-1J-2003D01*
G37*
G36*
G01Y693708D02*
G02X1394207Y691974I-2002J0D01*
G01X1390569Y689873D01*
G02X1389570Y689606I-999J1736D01*
G01X1389568D01*
G02X1387566Y691608I0J2002D01*
G02X1388567Y693342I2002J0D01*
G01X1392205Y695443D01*
G02X1393204Y695710I999J-1736D01*
G01X1393206D01*
G02X1395208Y693708I0J-2002D01*
G37*
G36*
G01Y708208D02*
G02X1394207Y706474I-2002J0D01*
G01X1390569Y704373D01*
G02X1389570Y704106I-999J1736D01*
G01X1389568D01*
G02X1387566Y706108I0J2002D01*
G02X1388567Y707842I2002J0D01*
G01X1392205Y709943D01*
G02X1393204Y710210I999J-1736D01*
G01X1393206D01*
G02X1395208Y708208I0J-2002D01*
G37*
G36*
G01Y679208D02*
G02X1394207Y677474I-2002J0D01*
G01X1390569Y675373D01*
G02X1389570Y675106I-999J1736D01*
G01X1389568D01*
G02X1387566Y677108I0J2002D01*
G02X1388567Y678842I2002J0D01*
G01X1392205Y680943D01*
G02X1393204Y681210I999J-1736D01*
G01X1393206D01*
G02X1395208Y679208I0J-2002D01*
G37*
G36*
G01Y664708D02*
G02X1394207Y662974I-2002J0D01*
G01X1390569Y660873D01*
G02X1389570Y660606I-999J1736D01*
G01X1389568D01*
G02X1387566Y662608I0J2002D01*
G02X1388567Y664342I2002J0D01*
G01X1392205Y666443D01*
G02X1393204Y666710I999J-1736D01*
G01X1393206D01*
G02X1395208Y664708I0J-2002D01*
G37*
G36*
G01X1372666Y719708D02*
G02X1374668Y721710I2002J0D01*
G01X1374670D01*
G02X1375669Y721443I0J-2003D01*
G01X1379307Y719342D01*
G02X1380308Y717608I-1001J-1734D01*
G02X1378306Y715606I-2002J0D01*
G01X1378304D01*
G02X1377305Y715873I0J2003D01*
G01X1373667Y717974D01*
G02X1372666Y719708I1001J1734D01*
G37*
G36*
G01Y695708D02*
G02X1374668Y697710I2002J0D01*
G01X1374670D01*
G02X1375669Y697443I0J-2003D01*
G01X1379307Y695342D01*
G02X1380308Y693608I-1001J-1734D01*
G02X1378306Y691606I-2002J0D01*
G01X1378304D01*
G02X1377305Y691873I0J2003D01*
G01X1373667Y693974D01*
G02X1372666Y695708I1001J1734D01*
G37*
G36*
G01Y707708D02*
G02X1374668Y709710I2002J0D01*
G01X1374670D01*
G02X1375669Y709443I0J-2003D01*
G01X1379307Y707342D01*
G02X1380308Y705608I-1001J-1734D01*
G02X1378306Y703606I-2002J0D01*
G01X1378304D01*
G02X1377305Y703873I0J2003D01*
G01X1373667Y705974D01*
G02X1372666Y707708I1001J1734D01*
G37*
G36*
G01Y683708D02*
G02X1374668Y685710I2002J0D01*
G01X1374670D01*
G02X1375669Y685443I0J-2003D01*
G01X1379307Y683342D01*
G02X1380308Y681608I-1001J-1734D01*
G02X1378306Y679606I-2002J0D01*
G01X1378304D01*
G02X1377305Y679873I0J2003D01*
G01X1373667Y681974D01*
G02X1372666Y683708I1001J1734D01*
G37*
G36*
G01Y671708D02*
G02X1374668Y673710I2002J0D01*
G01X1374670D01*
G02X1375669Y673443I0J-2003D01*
G01X1379307Y671342D01*
G02X1380308Y669608I-1001J-1734D01*
G02X1378306Y667606I-2002J0D01*
G01X1378304D01*
G02X1377305Y667873I0J2003D01*
G01X1373667Y669974D01*
G02X1372666Y671708I1001J1734D01*
G37*
G36*
G01Y659708D02*
G02X1374668Y661710I2002J0D01*
G01X1374670D01*
G02X1375669Y661443I0J-2003D01*
G01X1379307Y659342D01*
G02X1380308Y657608I-1001J-1734D01*
G02X1378306Y655606I-2002J0D01*
G01X1378304D01*
G02X1377305Y655873I0J2003D01*
G01X1373667Y657974D01*
G02X1372666Y659708I1001J1734D01*
G37*
G36*
G01X146312Y1571028D02*
X149712D01*
G02Y1568022I0J-1503D01*
G01X146312D01*
G02Y1571028I0J1503D01*
G37*
G36*
G01X1701934Y76800D02*
X1705334D01*
G02Y73794I0J-1503D01*
G01X1701934D01*
G02Y76800I0J1503D01*
G37*
G36*
G01X1690934Y70800D02*
X1694334D01*
G02Y67794I0J-1503D01*
G01X1690934D01*
G02Y70800I0J1503D01*
G37*
G36*
G01X1679934Y76800D02*
X1683334D01*
G02Y73794I0J-1503D01*
G01X1679934D01*
G02Y76800I0J1503D01*
G37*
G36*
G01X1657800D02*
X1661200D01*
G02Y73794I0J-1503D01*
G01X1657800D01*
G02Y76800I0J1503D01*
G37*
G36*
G01X1668800Y70800D02*
X1672200D01*
G02Y67794I0J-1503D01*
G01X1668800D01*
G02Y70800I0J1503D01*
G37*
G36*
G01X1646800D02*
X1650200D01*
G02Y67794I0J-1503D01*
G01X1646800D01*
G02Y70800I0J1503D01*
G37*
G36*
G01X1635800Y76800D02*
X1639200D01*
G02Y73794I0J-1503D01*
G01X1635800D01*
G02Y76800I0J1503D01*
G37*
G36*
G01X1612596D02*
X1615996D01*
G02Y73794I0J-1503D01*
G01X1612596D01*
G02Y76800I0J1503D01*
G37*
G36*
G01X1623596Y70800D02*
X1626996D01*
G02Y67794I0J-1503D01*
G01X1623596D01*
G02Y70800I0J1503D01*
G37*
G36*
G01X1601596D02*
X1604996D01*
G02Y67794I0J-1503D01*
G01X1601596D01*
G02Y70800I0J1503D01*
G37*
G36*
G01X1590596Y76800D02*
X1593996D01*
G02Y73794I0J-1503D01*
G01X1590596D01*
G02Y76800I0J1503D01*
G37*
G36*
G01X1579596Y70800D02*
X1582996D01*
G02Y67794I0J-1503D01*
G01X1579596D01*
G02Y70800I0J1503D01*
G37*
G36*
G01X1568596Y76800D02*
X1571996D01*
G02Y73794I0J-1503D01*
G01X1568596D01*
G02Y76800I0J1503D01*
G37*
G36*
G01X1546596D02*
X1549996D01*
G02Y73794I0J-1503D01*
G01X1546596D01*
G02Y76800I0J1503D01*
G37*
G36*
G01X1557596Y70800D02*
X1560996D01*
G02Y67794I0J-1503D01*
G01X1557596D01*
G02Y70800I0J1503D01*
G37*
G36*
G01X1535596D02*
X1538996D01*
G02Y67794I0J-1503D01*
G01X1535596D01*
G02Y70800I0J1503D01*
G37*
G36*
G01X230895Y73838D02*
X227495D01*
G02Y76842I0J1502D01*
G01X230895D01*
G02Y73838I0J-1502D01*
G37*
G36*
G01X219895Y67838D02*
X216495D01*
G02Y70842I0J1502D01*
G01X219895D01*
G02Y67838I0J-1502D01*
G37*
G36*
G01X208895Y73838D02*
X205495D01*
G02Y76842I0J1502D01*
G01X208895D01*
G02Y73838I0J-1502D01*
G37*
G36*
G01X194361Y70842D02*
X197761D01*
G02Y67838I0J-1502D01*
G01X194361D01*
G02Y70842I0J1502D01*
G37*
G36*
G01X183361Y76842D02*
X186761D01*
G02Y73838I0J-1502D01*
G01X183361D01*
G02Y76842I0J1502D01*
G37*
G36*
G01X161361D02*
X164761D01*
G02Y73838I0J-1502D01*
G01X161361D01*
G02Y76842I0J1502D01*
G37*
G36*
G01X172361Y70842D02*
X175761D01*
G02Y67838I0J-1502D01*
G01X172361D01*
G02Y70842I0J1502D01*
G37*
G36*
G01X149157D02*
X152557D01*
G02Y67838I0J-1502D01*
G01X149157D01*
G02Y70842I0J1502D01*
G37*
G36*
G01X138157Y76842D02*
X141557D01*
G02Y73838I0J-1502D01*
G01X138157D01*
G02Y76842I0J1502D01*
G37*
G36*
G01X116157D02*
X119557D01*
G02Y73838I0J-1502D01*
G01X116157D01*
G02Y76842I0J1502D01*
G37*
G36*
G01X127157Y70842D02*
X130557D01*
G02Y67838I0J-1502D01*
G01X127157D01*
G02Y70842I0J1502D01*
G37*
G36*
G01X105157D02*
X108557D01*
G02Y67838I0J-1502D01*
G01X105157D01*
G02Y70842I0J1502D01*
G37*
G36*
G01X94157Y76842D02*
X97557D01*
G02Y73838I0J-1502D01*
G01X94157D01*
G02Y76842I0J1502D01*
G37*
G36*
G01X83157Y70842D02*
X86557D01*
G02Y67838I0J-1502D01*
G01X83157D01*
G02Y70842I0J1502D01*
G37*
G36*
G01X72157Y76842D02*
X75557D01*
G02Y73838I0J-1502D01*
G01X72157D01*
G02Y76842I0J1502D01*
G37*
G36*
G01X61157Y70842D02*
X64557D01*
G02Y67838I0J-1502D01*
G01X61157D01*
G02Y70842I0J1502D01*
G37*
G36*
G01X1619075Y1579684D02*
X1622475D01*
G02Y1576680I0J-1502D01*
G01X1619075D01*
G02Y1579684I0J1502D01*
G37*
G36*
G01X326857Y1603882D02*
X330257D01*
G02Y1600878I0J-1502D01*
G01X326857D01*
G02Y1603882I0J1502D01*
G37*
G36*
G01X363037Y1615794D02*
X366437D01*
G02Y1612790I0J-1502D01*
G01X363037D01*
G02Y1615794I0J1502D01*
G37*
G36*
G01X545411Y1579684D02*
X548811D01*
G02Y1576680I0J-1502D01*
G01X545411D01*
G02Y1579684I0J1502D01*
G37*
G36*
G01Y1591596D02*
X548811D01*
G02Y1588592I0J-1502D01*
G01X545411D01*
G02Y1591596I0J1502D01*
G37*
G36*
G01X1377672D02*
X1381072D01*
G02Y1588592I0J-1502D01*
G01X1377672D01*
G02Y1591596I0J1502D01*
G37*
G36*
G01X533351D02*
X536751D01*
G02Y1588592I0J-1502D01*
G01X533351D01*
G02Y1591596I0J1502D01*
G37*
G36*
G01Y1579684D02*
X536751D01*
G02Y1576680I0J-1502D01*
G01X533351D01*
G02Y1579684I0J1502D01*
G37*
G36*
G01X1594955Y1591596D02*
X1598355D01*
G02Y1588592I0J-1502D01*
G01X1594955D01*
G02Y1591596I0J1502D01*
G37*
G36*
G01X581591D02*
X584991D01*
G02Y1588592I0J-1502D01*
G01X581591D01*
G02Y1591596I0J1502D01*
G37*
G36*
G01Y1579684D02*
X584991D01*
G02Y1576680I0J-1502D01*
G01X581591D01*
G02Y1579684I0J1502D01*
G37*
G36*
G01X1594955D02*
X1598355D01*
G02Y1576680I0J-1502D01*
G01X1594955D01*
G02Y1579684I0J1502D01*
G37*
G36*
G01X605711Y1591596D02*
X609111D01*
G02Y1588592I0J-1502D01*
G01X605711D01*
G02Y1591596I0J1502D01*
G37*
G36*
G01X333617Y1579684D02*
X337017D01*
G02Y1576680I0J-1502D01*
G01X333617D01*
G02Y1579684I0J1502D01*
G37*
G36*
G01X345677D02*
X349077D01*
G02Y1576680I0J-1502D01*
G01X345677D01*
G02Y1579684I0J1502D01*
G37*
G36*
G01X617771D02*
X621171D01*
G02Y1576680I0J-1502D01*
G01X617771D01*
G02Y1579684I0J1502D01*
G37*
G36*
G01Y1591596D02*
X621171D01*
G02Y1588592I0J-1502D01*
G01X617771D01*
G02Y1591596I0J1502D01*
G37*
G36*
G01X629831Y1579684D02*
X633231D01*
G02Y1576680I0J-1502D01*
G01X629831D01*
G02Y1579684I0J1502D01*
G37*
G36*
G01X1582895D02*
X1586295D01*
G02Y1576680I0J-1502D01*
G01X1582895D01*
G02Y1579684I0J1502D01*
G37*
G36*
G01X1570835D02*
X1574235D01*
G02Y1576680I0J-1502D01*
G01X1570835D01*
G02Y1579684I0J1502D01*
G37*
G36*
G01X1558775D02*
X1562175D01*
G02Y1576680I0J-1502D01*
G01X1558775D01*
G02Y1579684I0J1502D01*
G37*
G36*
G01X321557D02*
X324957D01*
G02Y1576680I0J-1502D01*
G01X321557D01*
G02Y1579684I0J1502D01*
G37*
G36*
G01X278617Y1603882D02*
X282017D01*
G02Y1600878I0J-1502D01*
G01X278617D01*
G02Y1603882I0J1502D01*
G37*
G36*
G01X1534655Y1591596D02*
X1538055D01*
G02Y1588592I0J-1502D01*
G01X1534655D01*
G02Y1591596I0J1502D01*
G37*
G36*
G01Y1579684D02*
X1538055D01*
G02Y1576680I0J-1502D01*
G01X1534655D01*
G02Y1579684I0J1502D01*
G37*
G36*
G01X1510535Y1591596D02*
X1513935D01*
G02Y1588592I0J-1502D01*
G01X1510535D01*
G02Y1591596I0J1502D01*
G37*
G36*
G01X1522595D02*
X1525995D01*
G02Y1588592I0J-1502D01*
G01X1522595D01*
G02Y1591596I0J1502D01*
G37*
G36*
G01X309497Y1579684D02*
X312897D01*
G02Y1576680I0J-1502D01*
G01X309497D01*
G02Y1579684I0J1502D01*
G37*
G36*
G01X302737Y1603882D02*
X306137D01*
G02Y1600878I0J-1502D01*
G01X302737D01*
G02Y1603882I0J1502D01*
G37*
G36*
G01X1498475Y1579684D02*
X1501875D01*
G02Y1576680I0J-1502D01*
G01X1498475D01*
G02Y1579684I0J1502D01*
G37*
G36*
G01X314797Y1615794D02*
X318197D01*
G02Y1612790I0J-1502D01*
G01X314797D01*
G02Y1615794I0J1502D01*
G37*
G36*
G01X278617D02*
X282017D01*
G02Y1612790I0J-1502D01*
G01X278617D01*
G02Y1615794I0J1502D01*
G37*
G36*
G01X497171Y1591596D02*
X500571D01*
G02Y1588592I0J-1502D01*
G01X497171D01*
G02Y1591596I0J1502D01*
G37*
G36*
G01X509231D02*
X512631D01*
G02Y1588592I0J-1502D01*
G01X509231D01*
G02Y1591596I0J1502D01*
G37*
G36*
G01Y1579684D02*
X512631D01*
G02Y1576680I0J-1502D01*
G01X509231D01*
G02Y1579684I0J1502D01*
G37*
G36*
G01X1486415Y1591596D02*
X1489815D01*
G02Y1588592I0J-1502D01*
G01X1486415D01*
G02Y1591596I0J1502D01*
G37*
G36*
G01Y1579684D02*
X1489815D01*
G02Y1576680I0J-1502D01*
G01X1486415D01*
G02Y1579684I0J1502D01*
G37*
G36*
G01X321557Y1591596D02*
X324957D01*
G02Y1588592I0J-1502D01*
G01X321557D01*
G02Y1591596I0J1502D01*
G37*
G36*
G01X1462295D02*
X1465695D01*
G02Y1588592I0J-1502D01*
G01X1462295D01*
G02Y1591596I0J1502D01*
G37*
G36*
G01X1474355D02*
X1477755D01*
G02Y1588592I0J-1502D01*
G01X1474355D01*
G02Y1591596I0J1502D01*
G37*
G36*
G01X641891Y1579684D02*
X645291D01*
G02Y1576680I0J-1502D01*
G01X641891D01*
G02Y1579684I0J1502D01*
G37*
G36*
G01Y1591596D02*
X645291D01*
G02Y1588592I0J-1502D01*
G01X641891D01*
G02Y1591596I0J1502D01*
G37*
G36*
G01X285377Y1579684D02*
X288777D01*
G02Y1576680I0J-1502D01*
G01X285377D01*
G02Y1579684I0J1502D01*
G37*
G36*
G01X1462295D02*
X1465695D01*
G02Y1576680I0J-1502D01*
G01X1462295D01*
G02Y1579684I0J1502D01*
G37*
G36*
G01X206257Y1615794D02*
X209657D01*
G02Y1612790I0J-1502D01*
G01X206257D01*
G02Y1615794I0J1502D01*
G37*
G36*
G01X338917D02*
X342317D01*
G02Y1612790I0J-1502D01*
G01X338917D01*
G02Y1615794I0J1502D01*
G37*
G36*
G01X1474355Y1579684D02*
X1477755D01*
G02Y1576680I0J-1502D01*
G01X1474355D01*
G02Y1579684I0J1502D01*
G37*
G36*
G01X261257D02*
X264657D01*
G02Y1576680I0J-1502D01*
G01X261257D01*
G02Y1579684I0J1502D01*
G37*
G36*
G01X485111D02*
X488511D01*
G02Y1576680I0J-1502D01*
G01X485111D01*
G02Y1579684I0J1502D01*
G37*
G36*
G01Y1591596D02*
X488511D01*
G02Y1588592I0J-1502D01*
G01X485111D01*
G02Y1591596I0J1502D01*
G37*
G36*
G01X338917Y1603882D02*
X342317D01*
G02Y1600878I0J-1502D01*
G01X338917D01*
G02Y1603882I0J1502D01*
G37*
G36*
G01X1648495Y1615794D02*
X1651895D01*
G02Y1612790I0J-1502D01*
G01X1648495D01*
G02Y1615794I0J1502D01*
G37*
G36*
G01Y1603882D02*
X1651895D01*
G02Y1600878I0J-1502D01*
G01X1648495D01*
G02Y1603882I0J1502D01*
G37*
G36*
G01X1624375Y1615794D02*
X1627775D01*
G02Y1612790I0J-1502D01*
G01X1624375D01*
G02Y1615794I0J1502D01*
G37*
G36*
G01X266557D02*
X269957D01*
G02Y1612790I0J-1502D01*
G01X266557D01*
G02Y1615794I0J1502D01*
G37*
G36*
G01X254497Y1603882D02*
X257897D01*
G02Y1600878I0J-1502D01*
G01X254497D01*
G02Y1603882I0J1502D01*
G37*
G36*
G01X653951Y1591596D02*
X657351D01*
G02Y1588592I0J-1502D01*
G01X653951D01*
G02Y1591596I0J1502D01*
G37*
G36*
G01Y1579684D02*
X657351D01*
G02Y1576680I0J-1502D01*
G01X653951D01*
G02Y1579684I0J1502D01*
G37*
G36*
G01X369797Y1591596D02*
X373197D01*
G02Y1588592I0J-1502D01*
G01X369797D01*
G02Y1591596I0J1502D01*
G37*
G36*
G01X1636435Y1603882D02*
X1639835D01*
G02Y1600878I0J-1502D01*
G01X1636435D01*
G02Y1603882I0J1502D01*
G37*
G36*
G01X266557D02*
X269957D01*
G02Y1600878I0J-1502D01*
G01X266557D01*
G02Y1603882I0J1502D01*
G37*
G36*
G01X1624375D02*
X1627775D01*
G02Y1600878I0J-1502D01*
G01X1624375D01*
G02Y1603882I0J1502D01*
G37*
G36*
G01X254497Y1615794D02*
X257897D01*
G02Y1612790I0J-1502D01*
G01X254497D01*
G02Y1615794I0J1502D01*
G37*
G36*
G01X194197Y1603882D02*
X197597D01*
G02Y1600878I0J-1502D01*
G01X194197D01*
G02Y1603882I0J1502D01*
G37*
G36*
G01X242437D02*
X245837D01*
G02Y1600878I0J-1502D01*
G01X242437D01*
G02Y1603882I0J1502D01*
G37*
G36*
G01X1612315D02*
X1615715D01*
G02Y1600878I0J-1502D01*
G01X1612315D01*
G02Y1603882I0J1502D01*
G37*
G36*
G01Y1615794D02*
X1615715D01*
G02Y1612790I0J-1502D01*
G01X1612315D01*
G02Y1615794I0J1502D01*
G37*
G36*
G01X230377D02*
X233777D01*
G02Y1612790I0J-1502D01*
G01X230377D01*
G02Y1615794I0J1502D01*
G37*
G36*
G01X521291Y1579684D02*
X524691D01*
G02Y1576680I0J-1502D01*
G01X521291D01*
G02Y1579684I0J1502D01*
G37*
G36*
G01Y1591596D02*
X524691D01*
G02Y1588592I0J-1502D01*
G01X521291D01*
G02Y1591596I0J1502D01*
G37*
G36*
G01X497171Y1579684D02*
X500571D01*
G02Y1576680I0J-1502D01*
G01X497171D01*
G02Y1579684I0J1502D01*
G37*
G36*
G01X593651D02*
X597051D01*
G02Y1576680I0J-1502D01*
G01X593651D01*
G02Y1579684I0J1502D01*
G37*
G36*
G01Y1591596D02*
X597051D01*
G02Y1588592I0J-1502D01*
G01X593651D01*
G02Y1591596I0J1502D01*
G37*
G36*
G01X1600255Y1603882D02*
X1603655D01*
G02Y1600878I0J-1502D01*
G01X1600255D01*
G02Y1603882I0J1502D01*
G37*
G36*
G01Y1615794D02*
X1603655D01*
G02Y1612790I0J-1502D01*
G01X1600255D01*
G02Y1615794I0J1502D01*
G37*
G36*
G01X557471Y1579684D02*
X560871D01*
G02Y1576680I0J-1502D01*
G01X557471D01*
G02Y1579684I0J1502D01*
G37*
G36*
G01X569531D02*
X572931D01*
G02Y1576680I0J-1502D01*
G01X569531D01*
G02Y1579684I0J1502D01*
G37*
G36*
G01Y1591596D02*
X572931D01*
G02Y1588592I0J-1502D01*
G01X569531D01*
G02Y1591596I0J1502D01*
G37*
G36*
G01X557471D02*
X560871D01*
G02Y1588592I0J-1502D01*
G01X557471D01*
G02Y1591596I0J1502D01*
G37*
G36*
G01X333617D02*
X337017D01*
G02Y1588592I0J-1502D01*
G01X333617D01*
G02Y1591596I0J1502D01*
G37*
G36*
G01X345677D02*
X349077D01*
G02Y1588592I0J-1502D01*
G01X345677D01*
G02Y1591596I0J1502D01*
G37*
G36*
G01X1607015Y1579684D02*
X1610415D01*
G02Y1576680I0J-1502D01*
G01X1607015D01*
G02Y1579684I0J1502D01*
G37*
G36*
G01X1576135Y1615794D02*
X1579535D01*
G02Y1612790I0J-1502D01*
G01X1576135D01*
G02Y1615794I0J1502D01*
G37*
G36*
G01X314797Y1603882D02*
X318197D01*
G02Y1600878I0J-1502D01*
G01X314797D01*
G02Y1603882I0J1502D01*
G37*
G36*
G01X1576135D02*
X1579535D01*
G02Y1600878I0J-1502D01*
G01X1576135D01*
G02Y1603882I0J1502D01*
G37*
G36*
G01X261257Y1591596D02*
X264657D01*
G02Y1588592I0J-1502D01*
G01X261257D01*
G02Y1591596I0J1502D01*
G37*
G36*
G01X357737Y1579684D02*
X361137D01*
G02Y1576680I0J-1502D01*
G01X357737D01*
G02Y1579684I0J1502D01*
G37*
G36*
G01X1546715Y1591596D02*
X1550115D01*
G02Y1588592I0J-1502D01*
G01X1546715D01*
G02Y1591596I0J1502D01*
G37*
G36*
G01Y1579684D02*
X1550115D01*
G02Y1576680I0J-1502D01*
G01X1546715D01*
G02Y1579684I0J1502D01*
G37*
G36*
G01X326857Y1615794D02*
X330257D01*
G02Y1612790I0J-1502D01*
G01X326857D01*
G02Y1615794I0J1502D01*
G37*
G36*
G01X249197Y1591596D02*
X252597D01*
G02Y1588592I0J-1502D01*
G01X249197D01*
G02Y1591596I0J1502D01*
G37*
G36*
G01X309497D02*
X312897D01*
G02Y1588592I0J-1502D01*
G01X309497D01*
G02Y1591596I0J1502D01*
G37*
G36*
G01X1564075Y1603882D02*
X1567475D01*
G02Y1600878I0J-1502D01*
G01X1564075D01*
G02Y1603882I0J1502D01*
G37*
G36*
G01Y1615794D02*
X1567475D01*
G02Y1612790I0J-1502D01*
G01X1564075D01*
G02Y1615794I0J1502D01*
G37*
G36*
G01X1552015D02*
X1555415D01*
G02Y1612790I0J-1502D01*
G01X1552015D01*
G02Y1615794I0J1502D01*
G37*
G36*
G01X1503775D02*
X1507175D01*
G02Y1612790I0J-1502D01*
G01X1503775D01*
G02Y1615794I0J1502D01*
G37*
G36*
G01X1552015Y1603882D02*
X1555415D01*
G02Y1600878I0J-1502D01*
G01X1552015D01*
G02Y1603882I0J1502D01*
G37*
G36*
G01X629831Y1591596D02*
X633231D01*
G02Y1588592I0J-1502D01*
G01X629831D01*
G02Y1591596I0J1502D01*
G37*
G36*
G01X1377672Y1579684D02*
X1381072D01*
G02Y1576680I0J-1502D01*
G01X1377672D01*
G02Y1579684I0J1502D01*
G37*
G36*
G01X218317Y1603882D02*
X221717D01*
G02Y1600878I0J-1502D01*
G01X218317D01*
G02Y1603882I0J1502D01*
G37*
G36*
G01X206257D02*
X209657D01*
G02Y1600878I0J-1502D01*
G01X206257D01*
G02Y1603882I0J1502D01*
G37*
G36*
G01X1527895Y1615794D02*
X1531295D01*
G02Y1612790I0J-1502D01*
G01X1527895D01*
G02Y1615794I0J1502D01*
G37*
G36*
G01X200957Y1591596D02*
X204357D01*
G02Y1588592I0J-1502D01*
G01X200957D01*
G02Y1591596I0J1502D01*
G37*
G36*
G01X1631135D02*
X1634535D01*
G02Y1588592I0J-1502D01*
G01X1631135D01*
G02Y1591596I0J1502D01*
G37*
G36*
G01X1539955Y1615794D02*
X1543355D01*
G02Y1612790I0J-1502D01*
G01X1539955D01*
G02Y1615794I0J1502D01*
G37*
G36*
G01Y1603882D02*
X1543355D01*
G02Y1600878I0J-1502D01*
G01X1539955D01*
G02Y1603882I0J1502D01*
G37*
G36*
G01X1527895D02*
X1531295D01*
G02Y1600878I0J-1502D01*
G01X1527895D01*
G02Y1603882I0J1502D01*
G37*
G36*
G01X302737Y1615794D02*
X306137D01*
G02Y1612790I0J-1502D01*
G01X302737D01*
G02Y1615794I0J1502D01*
G37*
G36*
G01X1522595Y1579684D02*
X1525995D01*
G02Y1576680I0J-1502D01*
G01X1522595D01*
G02Y1579684I0J1502D01*
G37*
G36*
G01X1515835Y1615794D02*
X1519235D01*
G02Y1612790I0J-1502D01*
G01X1515835D01*
G02Y1615794I0J1502D01*
G37*
G36*
G01X1636435D02*
X1639835D01*
G02Y1612790I0J-1502D01*
G01X1636435D01*
G02Y1615794I0J1502D01*
G37*
G36*
G01X1498475Y1591596D02*
X1501875D01*
G02Y1588592I0J-1502D01*
G01X1498475D01*
G02Y1591596I0J1502D01*
G37*
G36*
G01X1643195D02*
X1646595D01*
G02Y1588592I0J-1502D01*
G01X1643195D01*
G02Y1591596I0J1502D01*
G37*
G36*
G01X1515835Y1603882D02*
X1519235D01*
G02Y1600878I0J-1502D01*
G01X1515835D01*
G02Y1603882I0J1502D01*
G37*
G36*
G01X357737Y1591596D02*
X361137D01*
G02Y1588592I0J-1502D01*
G01X357737D01*
G02Y1591596I0J1502D01*
G37*
G36*
G01X194197Y1615794D02*
X197597D01*
G02Y1612790I0J-1502D01*
G01X194197D01*
G02Y1615794I0J1502D01*
G37*
G36*
G01X1510535Y1579684D02*
X1513935D01*
G02Y1576680I0J-1502D01*
G01X1510535D01*
G02Y1579684I0J1502D01*
G37*
G36*
G01X1570835Y1591596D02*
X1574235D01*
G02Y1588592I0J-1502D01*
G01X1570835D01*
G02Y1591596I0J1502D01*
G37*
G36*
G01X273317D02*
X276717D01*
G02Y1588592I0J-1502D01*
G01X273317D01*
G02Y1591596I0J1502D01*
G37*
G36*
G01Y1579684D02*
X276717D01*
G02Y1576680I0J-1502D01*
G01X273317D01*
G02Y1579684I0J1502D01*
G37*
G36*
G01X1491715Y1603882D02*
X1495115D01*
G02Y1600878I0J-1502D01*
G01X1491715D01*
G02Y1603882I0J1502D01*
G37*
G36*
G01Y1615794D02*
X1495115D01*
G02Y1612790I0J-1502D01*
G01X1491715D01*
G02Y1615794I0J1502D01*
G37*
G36*
G01X1631135Y1579684D02*
X1634535D01*
G02Y1576680I0J-1502D01*
G01X1631135D01*
G02Y1579684I0J1502D01*
G37*
G36*
G01X213017Y1591596D02*
X216417D01*
G02Y1588592I0J-1502D01*
G01X213017D01*
G02Y1591596I0J1502D01*
G37*
G36*
G01X188897Y1579684D02*
X192297D01*
G02Y1576680I0J-1502D01*
G01X188897D01*
G02Y1579684I0J1502D01*
G37*
G36*
G01X1503775Y1603882D02*
X1507175D01*
G02Y1600878I0J-1502D01*
G01X1503775D01*
G02Y1603882I0J1502D01*
G37*
G36*
G01X200957Y1579684D02*
X204357D01*
G02Y1576680I0J-1502D01*
G01X200957D01*
G02Y1579684I0J1502D01*
G37*
G36*
G01X605711D02*
X609111D01*
G02Y1576680I0J-1502D01*
G01X605711D01*
G02Y1579684I0J1502D01*
G37*
G36*
G01X1479655Y1603882D02*
X1483055D01*
G02Y1600878I0J-1502D01*
G01X1479655D01*
G02Y1603882I0J1502D01*
G37*
G36*
G01Y1615794D02*
X1483055D01*
G02Y1612790I0J-1502D01*
G01X1479655D01*
G02Y1615794I0J1502D01*
G37*
G36*
G01X249197Y1579684D02*
X252597D01*
G02Y1576680I0J-1502D01*
G01X249197D01*
G02Y1579684I0J1502D01*
G37*
G36*
G01X1467595Y1615794D02*
X1470995D01*
G02Y1612790I0J-1502D01*
G01X1467595D01*
G02Y1615794I0J1502D01*
G37*
G36*
G01Y1603882D02*
X1470995D01*
G02Y1600878I0J-1502D01*
G01X1467595D01*
G02Y1603882I0J1502D01*
G37*
G36*
G01X1558775Y1591596D02*
X1562175D01*
G02Y1588592I0J-1502D01*
G01X1558775D01*
G02Y1591596I0J1502D01*
G37*
G36*
G01X1643195Y1579684D02*
X1646595D01*
G02Y1576680I0J-1502D01*
G01X1643195D01*
G02Y1579684I0J1502D01*
G37*
G36*
G01X188897Y1591596D02*
X192297D01*
G02Y1588592I0J-1502D01*
G01X188897D01*
G02Y1591596I0J1502D01*
G37*
G36*
G01X1607015D02*
X1610415D01*
G02Y1588592I0J-1502D01*
G01X1607015D01*
G02Y1591596I0J1502D01*
G37*
G36*
G01X1582895D02*
X1586295D01*
G02Y1588592I0J-1502D01*
G01X1582895D01*
G02Y1591596I0J1502D01*
G37*
G36*
G01X225077Y1579684D02*
X228477D01*
G02Y1576680I0J-1502D01*
G01X225077D01*
G02Y1579684I0J1502D01*
G37*
G36*
G01Y1591596D02*
X228477D01*
G02Y1588592I0J-1502D01*
G01X225077D01*
G02Y1591596I0J1502D01*
G37*
G36*
G01X218317Y1615794D02*
X221717D01*
G02Y1612790I0J-1502D01*
G01X218317D01*
G02Y1615794I0J1502D01*
G37*
G36*
G01X290677Y1603882D02*
X294077D01*
G02Y1600878I0J-1502D01*
G01X290677D01*
G02Y1603882I0J1502D01*
G37*
G36*
G01Y1615794D02*
X294077D01*
G02Y1612790I0J-1502D01*
G01X290677D01*
G02Y1615794I0J1502D01*
G37*
G36*
G01X237137Y1579684D02*
X240537D01*
G02Y1576680I0J-1502D01*
G01X237137D01*
G02Y1579684I0J1502D01*
G37*
G36*
G01X213017D02*
X216417D01*
G02Y1576680I0J-1502D01*
G01X213017D01*
G02Y1579684I0J1502D01*
G37*
G36*
G01X230377Y1603882D02*
X233777D01*
G02Y1600878I0J-1502D01*
G01X230377D01*
G02Y1603882I0J1502D01*
G37*
G36*
G01X1619075Y1591596D02*
X1622475D01*
G02Y1588592I0J-1502D01*
G01X1619075D01*
G02Y1591596I0J1502D01*
G37*
G36*
G01X242437Y1615794D02*
X245837D01*
G02Y1612790I0J-1502D01*
G01X242437D01*
G02Y1615794I0J1502D01*
G37*
G36*
G01X369797Y1579684D02*
X373197D01*
G02Y1576680I0J-1502D01*
G01X369797D01*
G02Y1579684I0J1502D01*
G37*
G36*
G01X473051Y1591596D02*
X476451D01*
G02Y1588592I0J-1502D01*
G01X473051D01*
G02Y1591596I0J1502D01*
G37*
G36*
G01Y1579684D02*
X476451D01*
G02Y1576680I0J-1502D01*
G01X473051D01*
G02Y1579684I0J1502D01*
G37*
G36*
G01X1588195Y1603882D02*
X1591595D01*
G02Y1600878I0J-1502D01*
G01X1588195D01*
G02Y1603882I0J1502D01*
G37*
G36*
G01Y1615794D02*
X1591595D01*
G02Y1612790I0J-1502D01*
G01X1588195D01*
G02Y1615794I0J1502D01*
G37*
G36*
G01X61470Y86124D02*
X64870D01*
G02Y83120I0J-1502D01*
G01X61470D01*
G02Y86124I0J1502D01*
G37*
G36*
G01X297437Y1579684D02*
X300837D01*
G02Y1576680I0J-1502D01*
G01X297437D01*
G02Y1579684I0J1502D01*
G37*
G36*
G01X350977Y1615794D02*
X354377D01*
G02Y1612790I0J-1502D01*
G01X350977D01*
G02Y1615794I0J1502D01*
G37*
G36*
G01X375097Y1603882D02*
X378497D01*
G02Y1600878I0J-1502D01*
G01X375097D01*
G02Y1603882I0J1502D01*
G37*
G36*
G01Y1615794D02*
X378497D01*
G02Y1612790I0J-1502D01*
G01X375097D01*
G02Y1615794I0J1502D01*
G37*
G36*
G01X363037Y1603882D02*
X366437D01*
G02Y1600878I0J-1502D01*
G01X363037D01*
G02Y1603882I0J1502D01*
G37*
G36*
G01X528880Y873810D02*
G02X531476I1298J0D01*
G01Y873808D01*
G02X531403Y873381I-1298J2D01*
G01X531373Y873295D01*
X532179Y871898D01*
X532269Y871881D01*
G02X533326Y870606I-240J-1275D01*
G02X530732I-1297J0D01*
G01Y870607D01*
G02X530803Y871032I1297J2D01*
G01X530833Y871118D01*
X530026Y872518D01*
X529936Y872535D01*
G02X528880Y873810I242J1275D01*
G37*
G36*
G01X521480D02*
G02X524076I1298J0D01*
G01Y873808D01*
G02X524003Y873381I-1298J2D01*
G01X523973Y873295D01*
X524779Y871898D01*
X524869Y871881D01*
G02X525926Y870606I-240J-1275D01*
G02X523332I-1297J0D01*
G01Y870607D01*
G02X523403Y871032I1297J2D01*
G01X523433Y871118D01*
X522626Y872518D01*
X522536Y872535D01*
G02X521480Y873810I242J1275D01*
G37*
G36*
G01X515932Y883423D02*
G02X518526I1297J0D01*
G01Y883421D01*
G02X518454Y882994I-1298J-1D01*
G01X518424Y882908D01*
X519230Y881511D01*
X519320Y881494D01*
G02X520376Y880219I-242J-1275D01*
G02X517780I-1298J0D01*
G02X517853Y880647I1299J-1D01*
G01X517883Y880733D01*
X517077Y882131D01*
X516987Y882148D01*
G02X515932Y883423I243J1275D01*
G37*
G36*
G01X353132D02*
G02X355726I1297J0D01*
G01Y883421D01*
G02X355654Y882994I-1298J-1D01*
G01X355624Y882908D01*
X356430Y881511D01*
X356520Y881494D01*
G02X357576Y880219I-242J-1275D01*
G02X354980I-1298J0D01*
G02X355053Y880647I1299J-1D01*
G01X355083Y880733D01*
X354277Y882131D01*
X354187Y882148D01*
G02X353132Y883423I243J1275D01*
G37*
G36*
G01X1505024Y886625D02*
Y886627D01*
G02X1507618I1297J0D01*
G02X1506563Y885352I-1298J0D01*
G01X1506473Y885335D01*
X1505666Y883937D01*
X1505696Y883851D01*
G02X1505768Y883423I-1226J-426D01*
G02X1503174I-1297J0D01*
G02X1504230Y884698I1298J0D01*
G01X1504320Y884715D01*
X1505126Y886112D01*
X1505096Y886198D01*
G02X1505024Y886625I1226J426D01*
G37*
G36*
G01X1497622Y873810D02*
G02X1500218I1298J0D01*
G01Y873808D01*
G02X1500145Y873381I-1298J2D01*
G01X1500115Y873295D01*
X1500921Y871898D01*
X1501011Y871881D01*
G02X1502068Y870606I-240J-1275D01*
G02X1499474I-1297J0D01*
G01Y870607D01*
G02X1499545Y871032I1297J2D01*
G01X1499575Y871118D01*
X1498768Y872518D01*
X1498678Y872535D01*
G02X1497622Y873810I242J1275D01*
G37*
G36*
G01X528882Y886625D02*
Y886627D01*
G02X531476I1297J0D01*
G02X530421Y885352I-1298J0D01*
G01X530331Y885335D01*
X529524Y883937D01*
X529554Y883851D01*
G02X529626Y883423I-1226J-426D01*
G02X527032I-1297J0D01*
G02X528088Y884698I1298J0D01*
G01X528178Y884715D01*
X528984Y886112D01*
X528954Y886198D01*
G02X528882Y886625I1226J426D01*
G37*
G36*
G01X358680D02*
Y886627D01*
G02X361276I1298J0D01*
G02X360220Y885352I-1298J0D01*
G01X360130Y885335D01*
X359324Y883938D01*
X359354Y883852D01*
G02X359426Y883425I-1226J-426D01*
G01Y883423D01*
G02X356832I-1297J0D01*
G02X357887Y884698I1298J0D01*
G01X357977Y884715D01*
X358783Y886112D01*
X358753Y886198D01*
G02X358680Y886625I1225J429D01*
G37*
G36*
G01X1499474Y883423D02*
G02X1502068I1297J0D01*
G01Y883421D01*
G02X1501996Y882994I-1298J-1D01*
G01X1501966Y882908D01*
X1502772Y881511D01*
X1502862Y881494D01*
G02X1503918Y880219I-242J-1275D01*
G02X1501324I-1297J0D01*
G01Y880221D01*
G02X1501396Y880646I1297J-1D01*
G01X1501426Y880732D01*
X1500619Y882131D01*
X1500529Y882148D01*
G02X1499474Y883423I243J1275D01*
G37*
G36*
G01X1505022Y873810D02*
G02X1507618I1298J0D01*
G01Y873808D01*
G02X1507545Y873381I-1298J2D01*
G01X1507515Y873295D01*
X1508321Y871898D01*
X1508411Y871881D01*
G02X1509468Y870606I-240J-1275D01*
G02X1506874I-1297J0D01*
G01Y870607D01*
G02X1506945Y871032I1297J2D01*
G01X1506975Y871118D01*
X1506168Y872518D01*
X1506078Y872535D01*
G02X1505022Y873810I242J1275D01*
G37*
G36*
G01X1492074Y883423D02*
G02X1494668I1297J0D01*
G01Y883421D01*
G02X1494596Y882994I-1298J-1D01*
G01X1494566Y882908D01*
X1495372Y881511D01*
X1495462Y881494D01*
G02X1496518Y880219I-242J-1275D01*
G02X1493922I-1298J0D01*
G02X1493995Y880647I1299J-1D01*
G01X1494025Y880733D01*
X1493219Y882131D01*
X1493129Y882148D01*
G02X1492074Y883423I243J1275D01*
G37*
G36*
G01X523332D02*
G02X525926I1297J0D01*
G01Y883421D01*
G02X525854Y882994I-1298J-1D01*
G01X525824Y882908D01*
X526630Y881511D01*
X526720Y881494D01*
G02X527776Y880219I-242J-1275D01*
G02X525182I-1297J0D01*
G01Y880221D01*
G02X525254Y880646I1297J-1D01*
G01X525284Y880732D01*
X524477Y882131D01*
X524387Y882148D01*
G02X523332Y883423I243J1275D01*
G37*
G36*
G01X366080Y886625D02*
Y886627D01*
G02X368676I1298J0D01*
G02X367620Y885352I-1298J0D01*
G01X367530Y885335D01*
X366724Y883938D01*
X366754Y883852D01*
G02X366826Y883425I-1226J-426D01*
G01Y883423D01*
G02X364232I-1297J0D01*
G02X365287Y884698I1298J0D01*
G01X365377Y884715D01*
X366183Y886112D01*
X366153Y886198D01*
G02X366080Y886625I1225J429D01*
G37*
G36*
G01X1330101Y541552D02*
X1333143D01*
G02Y538546I0J-1503D01*
G01X1330101D01*
G02Y541552I0J1503D01*
G37*
G36*
G01X1334822Y886625D02*
Y886627D01*
G02X1337418I1298J0D01*
G02X1336362Y885352I-1298J0D01*
G01X1336272Y885335D01*
X1335466Y883938D01*
X1335496Y883852D01*
G02X1335568Y883425I-1226J-426D01*
G01Y883423D01*
G02X1332974I-1297J0D01*
G02X1334029Y884698I1298J0D01*
G01X1334119Y884715D01*
X1334925Y886112D01*
X1334895Y886198D01*
G02X1334822Y886625I1225J429D01*
G37*
G36*
G01X360532Y883423D02*
G02X363126I1297J0D01*
G01Y883421D01*
G02X363054Y882994I-1298J-1D01*
G01X363024Y882908D01*
X363830Y881511D01*
X363920Y881494D01*
G02X364976Y880219I-242J-1275D01*
G02X362380I-1298J0D01*
G02X362453Y880647I1299J-1D01*
G01X362483Y880733D01*
X361677Y882131D01*
X361587Y882148D01*
G02X360532Y883423I243J1275D01*
G37*
G36*
G01X1329274D02*
G02X1331868I1297J0D01*
G01Y883421D01*
G02X1331796Y882994I-1298J-1D01*
G01X1331766Y882908D01*
X1332572Y881511D01*
X1332662Y881494D01*
G02X1333718Y880219I-242J-1275D01*
G02X1331122I-1298J0D01*
G02X1331195Y880647I1299J-1D01*
G01X1331225Y880733D01*
X1330419Y882131D01*
X1330329Y882148D01*
G02X1329274Y883423I243J1275D01*
G37*
G36*
G01X1342222Y886625D02*
Y886627D01*
G02X1344818I1298J0D01*
G02X1343762Y885352I-1298J0D01*
G01X1343672Y885335D01*
X1342866Y883938D01*
X1342896Y883852D01*
G02X1342968Y883425I-1226J-426D01*
G01Y883423D01*
G02X1340374I-1297J0D01*
G02X1341429Y884698I1298J0D01*
G01X1341519Y884715D01*
X1342325Y886112D01*
X1342295Y886198D01*
G02X1342222Y886625I1225J429D01*
G37*
G36*
G01X1336674Y883423D02*
G02X1339268I1297J0D01*
G01Y883421D01*
G02X1339196Y882994I-1298J-1D01*
G01X1339166Y882908D01*
X1339972Y881511D01*
X1340062Y881494D01*
G02X1341118Y880219I-242J-1275D01*
G02X1338522I-1298J0D01*
G02X1338595Y880647I1299J-1D01*
G01X1338625Y880733D01*
X1337819Y882131D01*
X1337729Y882148D01*
G02X1336674Y883423I243J1275D01*
G37*
G36*
G01X1358624Y283142D02*
X1355224D01*
G02Y286146I0J1502D01*
G01X1358624D01*
G02Y283142I0J-1502D01*
G37*
G36*
G01X1348084Y278756D02*
X1344684D01*
G02Y281762I0J1503D01*
G01X1348084D01*
G02Y278756I0J-1503D01*
G37*
G36*
G01X1368524Y281242D02*
X1365124D01*
G02Y284246I0J1502D01*
G01X1368524D01*
G02Y281242I0J-1502D01*
G37*
G36*
G01X1328480Y322400D02*
X1325080D01*
G02Y325404I0J1502D01*
G01X1328480D01*
G02Y322400I0J-1502D01*
G37*
G36*
G01X613970Y190254D02*
X617370D01*
G02Y187250I0J-1502D01*
G01X613970D01*
G02Y190254I0J1502D01*
G37*
G36*
G01X64571Y427304D02*
X61171D01*
G02Y430308I0J1502D01*
G01X64571D01*
G02Y427304I0J-1502D01*
G37*
G36*
G01X626640Y190254D02*
X630040D01*
G02Y187250I0J-1502D01*
G01X626640D01*
G02Y190254I0J1502D01*
G37*
G36*
G01X423180Y1601300D02*
X419780D01*
G02Y1604304I0J1502D01*
G01X423180D01*
G02Y1601300I0J-1502D01*
G37*
G36*
G01X49360Y427304D02*
X45960D01*
G02Y430308I0J1502D01*
G01X49360D01*
G02Y427304I0J-1502D01*
G37*
G36*
G01X1400985Y242432D02*
X1404385D01*
G02Y239426I0J-1503D01*
G01X1400985D01*
G02Y242432I0J1503D01*
G37*
G36*
G01X930731Y531982D02*
X933773D01*
G02Y528976I0J-1503D01*
G01X930731D01*
G02Y531982I0J1503D01*
G37*
G36*
G01X285377Y1591596D02*
X288777D01*
G02Y1588592I0J-1502D01*
G01X285377D01*
G02Y1591596I0J1502D01*
G37*
G36*
G01X229131Y49144D02*
X225731D01*
G02Y52148I0J1502D01*
G01X229131D01*
G02Y49144I0J-1502D01*
G37*
G36*
G01X284230D02*
X280830D01*
G02Y52148I0J1502D01*
G01X284230D01*
G02Y49144I0J-1502D01*
G37*
G36*
G01X1755272Y27934D02*
X1758672D01*
G02Y24928I0J-1503D01*
G01X1755272D01*
G02Y27934I0J1503D01*
G37*
G36*
G01X1530660Y101664D02*
X1534060D01*
G02Y98660I0J-1502D01*
G01X1530660D01*
G02Y101664I0J1502D01*
G37*
G36*
G01X1549308Y27934D02*
X1552708D01*
G02Y24928I0J-1503D01*
G01X1549308D01*
G02Y27934I0J1503D01*
G37*
G36*
G01X1556413Y20998D02*
X1559813D01*
G02Y17992I0J-1503D01*
G01X1556413D01*
G02Y20998I0J1503D01*
G37*
G36*
G01X1563481Y27934D02*
X1566881D01*
G02Y24928I0J-1503D01*
G01X1563481D01*
G02Y27934I0J1503D01*
G37*
G36*
G01X1570586Y20998D02*
X1573986D01*
G02Y17992I0J-1503D01*
G01X1570586D01*
G02Y20998I0J1503D01*
G37*
G36*
G01X1577654Y27934D02*
X1581054D01*
G02Y24928I0J-1503D01*
G01X1577654D01*
G02Y27934I0J1503D01*
G37*
G36*
G01X1584759Y20998D02*
X1588159D01*
G02Y17992I0J-1503D01*
G01X1584759D01*
G02Y20998I0J1503D01*
G37*
G36*
G01X1591828Y27934D02*
X1595228D01*
G02Y24928I0J-1503D01*
G01X1591828D01*
G02Y27934I0J1503D01*
G37*
G36*
G01X1598933Y20998D02*
X1602333D01*
G02Y17992I0J-1503D01*
G01X1598933D01*
G02Y20998I0J1503D01*
G37*
G36*
G01X1627694Y27934D02*
X1631094D01*
G02Y24928I0J-1503D01*
G01X1627694D01*
G02Y27934I0J1503D01*
G37*
G36*
G01X1634799Y20998D02*
X1638199D01*
G02Y17992I0J-1503D01*
G01X1634799D01*
G02Y20998I0J1503D01*
G37*
G36*
G01X218667Y21040D02*
X222067D01*
G02Y18036I0J-1502D01*
G01X218667D01*
G02Y21040I0J1502D01*
G37*
G36*
G01X211562Y27976D02*
X214962D01*
G02Y24972I0J-1502D01*
G01X211562D01*
G02Y27976I0J1502D01*
G37*
G36*
G01X204494Y21040D02*
X207894D01*
G02Y18036I0J-1502D01*
G01X204494D01*
G02Y21040I0J1502D01*
G37*
G36*
G01X197389Y27976D02*
X200789D01*
G02Y24972I0J-1502D01*
G01X197389D01*
G02Y27976I0J1502D01*
G37*
G36*
G01X167428D02*
X170828D01*
G02Y24972I0J-1502D01*
G01X167428D01*
G02Y27976I0J1502D01*
G37*
G36*
G01X174533Y21040D02*
X177933D01*
G02Y18036I0J-1502D01*
G01X174533D01*
G02Y21040I0J1502D01*
G37*
G36*
G01X153255Y27976D02*
X156655D01*
G02Y24972I0J-1502D01*
G01X153255D01*
G02Y27976I0J1502D01*
G37*
G36*
G01X160360Y21040D02*
X163760D01*
G02Y18036I0J-1502D01*
G01X160360D01*
G02Y21040I0J1502D01*
G37*
G36*
G01X124494D02*
X127894D01*
G02Y18036I0J-1502D01*
G01X124494D01*
G02Y21040I0J1502D01*
G37*
G36*
G01X117389Y27976D02*
X120789D01*
G02Y24972I0J-1502D01*
G01X117389D01*
G02Y27976I0J1502D01*
G37*
G36*
G01X103215D02*
X106615D01*
G02Y24972I0J-1502D01*
G01X103215D01*
G02Y27976I0J1502D01*
G37*
G36*
G01X110320Y21040D02*
X113720D01*
G02Y18036I0J-1502D01*
G01X110320D01*
G02Y21040I0J1502D01*
G37*
G36*
G01X89042Y27976D02*
X92442D01*
G02Y24972I0J-1502D01*
G01X89042D01*
G02Y27976I0J1502D01*
G37*
G36*
G01X96147Y21040D02*
X99547D01*
G02Y18036I0J-1502D01*
G01X96147D01*
G02Y21040I0J1502D01*
G37*
G36*
G01X74869Y27976D02*
X78269D01*
G02Y24972I0J-1502D01*
G01X74869D01*
G02Y27976I0J1502D01*
G37*
G36*
G01X81974Y21040D02*
X85374D01*
G02Y18036I0J-1502D01*
G01X81974D01*
G02Y21040I0J1502D01*
G37*
G36*
G01X1641867Y27934D02*
X1645267D01*
G02Y24928I0J-1503D01*
G01X1641867D01*
G02Y27934I0J1503D01*
G37*
G36*
G01X1648972Y20998D02*
X1652372D01*
G02Y17992I0J-1503D01*
G01X1648972D01*
G02Y20998I0J1503D01*
G37*
G36*
G01X1671828Y27934D02*
X1675228D01*
G02Y24928I0J-1503D01*
G01X1671828D01*
G02Y27934I0J1503D01*
G37*
G36*
G01X1678933Y20998D02*
X1682333D01*
G02Y17992I0J-1503D01*
G01X1678933D01*
G02Y20998I0J1503D01*
G37*
G36*
G01X1686001Y27934D02*
X1689401D01*
G02Y24928I0J-1503D01*
G01X1686001D01*
G02Y27934I0J1503D01*
G37*
G36*
G01X1693106Y20998D02*
X1696506D01*
G02Y17992I0J-1503D01*
G01X1693106D01*
G02Y20998I0J1503D01*
G37*
G36*
G01X1700217Y27962D02*
X1703617D01*
G02Y24956I0J-1503D01*
G01X1700217D01*
G02Y27962I0J1503D01*
G37*
G36*
G01X1700170Y52152D02*
X1703570D01*
G02Y49146I0J-1503D01*
G01X1700170D01*
G02Y52152I0J1503D01*
G37*
G36*
G01X670612Y48766D02*
X674012D01*
G02Y45762I0J-1502D01*
G01X670612D01*
G02Y48766I0J1502D01*
G37*
G36*
G01X284233Y24972D02*
X280833D01*
G02Y27976I0J1502D01*
G01X284233D01*
G02Y24972I0J-1502D01*
G37*
G36*
G01X1307442Y305496D02*
X1304042D01*
G02Y308500I0J1502D01*
G01X1307442D01*
G02Y305496I0J-1502D01*
G37*
G36*
G01X1382972Y1603882D02*
X1386372D01*
G02Y1600878I0J-1502D01*
G01X1382972D01*
G02Y1603882I0J1502D01*
G37*
G36*
G01Y1615794D02*
X1386372D01*
G02Y1612790I0J-1502D01*
G01X1382972D01*
G02Y1615794I0J1502D01*
G37*
G36*
G01X229135Y24972D02*
X225735D01*
G02Y27976I0J1502D01*
G01X229135D01*
G02Y24972I0J-1502D01*
G37*
G36*
G01X350977Y1603882D02*
X354377D01*
G02Y1600878I0J-1502D01*
G01X350977D01*
G02Y1603882I0J1502D01*
G37*
G36*
G01X1307042Y291134D02*
X1303642D01*
G02Y294138I0J1502D01*
G01X1307042D01*
G02Y291134I0J-1502D01*
G37*
G36*
G01X405990Y1617450D02*
X402590D01*
G02Y1620454I0J1502D01*
G01X405990D01*
G02Y1617450I0J-1502D01*
G37*
G36*
G01X441740Y1650764D02*
X438340D01*
G02Y1653768I0J1502D01*
G01X441740D01*
G02Y1650764I0J-1502D01*
G37*
G36*
G01X49212Y450100D02*
X45812D01*
G02Y453104I0J1502D01*
G01X49212D01*
G02Y450100I0J-1502D01*
G37*
G36*
G01X1418630Y221520D02*
X1422030D01*
G02Y218516I0J-1502D01*
G01X1418630D01*
G02Y221520I0J1502D01*
G37*
G36*
G01X1407420D02*
X1410820D01*
G02Y218516I0J-1502D01*
G01X1407420D01*
G02Y221520I0J1502D01*
G37*
G36*
G01X1432660D02*
X1436060D01*
G02Y218516I0J-1502D01*
G01X1432660D01*
G02Y221520I0J1502D01*
G37*
G36*
G01X862930Y71574D02*
X866330D01*
G02Y68570I0J-1502D01*
G01X862930D01*
G02Y71574I0J1502D01*
G37*
G36*
G01X1348824Y327478D02*
X1345424D01*
G02Y330484I0J1503D01*
G01X1348824D01*
G02Y327478I0J-1503D01*
G37*
G36*
G01X1341431Y321190D02*
X1338031D01*
G02Y324196I0J1503D01*
G01X1341431D01*
G02Y321190I0J-1503D01*
G37*
G36*
G01X1335145Y331114D02*
X1331745D01*
G02Y334118I0J1502D01*
G01X1335145D01*
G02Y331114I0J-1502D01*
G37*
G36*
G01X1319618Y316570D02*
X1316218D01*
G02Y319576I0J1503D01*
G01X1319618D01*
G02Y316570I0J-1503D01*
G37*
G36*
G01X1311077Y321494D02*
X1307677D01*
G02Y324498I0J1502D01*
G01X1311077D01*
G02Y321494I0J-1502D01*
G37*
G36*
G01X1380602Y199170D02*
X1384002D01*
G02Y196166I0J-1502D01*
G01X1380602D01*
G02Y199170I0J1502D01*
G37*
G36*
G01X1398006D02*
X1401406D01*
G02Y196166I0J-1502D01*
G01X1398006D01*
G02Y199170I0J1502D01*
G37*
G36*
G01X1373591Y177932D02*
X1376991D01*
G02Y174928I0J-1502D01*
G01X1373591D01*
G02Y177932I0J1502D01*
G37*
G36*
G01X1169820Y637554D02*
X1173220D01*
G02Y634550I0J-1502D01*
G01X1169820D01*
G02Y637554I0J1502D01*
G37*
G36*
G01X519764Y41830D02*
X523164D01*
G02Y38826I0J-1502D01*
G01X519764D01*
G02Y41830I0J1502D01*
G37*
G36*
G01X732793Y72938D02*
X736193D01*
G02Y69934I0J-1502D01*
G01X732793D01*
G02Y72938I0J1502D01*
G37*
G36*
G01X1161860Y643614D02*
X1165260D01*
G02Y640610I0J-1502D01*
G01X1161860D01*
G02Y643614I0J1502D01*
G37*
G36*
G01X663543Y44830D02*
X666943D01*
G02Y41826I0J-1502D01*
G01X663543D01*
G02Y44830I0J1502D01*
G37*
G36*
G01X656439Y48766D02*
X659839D01*
G02Y45762I0J-1502D01*
G01X656439D01*
G02Y48766I0J1502D01*
G37*
G36*
G01X562771Y1603882D02*
X566171D01*
G02Y1600878I0J-1502D01*
G01X562771D01*
G02Y1603882I0J1502D01*
G37*
G36*
G01X538651D02*
X542051D01*
G02Y1600878I0J-1502D01*
G01X538651D01*
G02Y1603882I0J1502D01*
G37*
G36*
G01X1406970Y140244D02*
X1410370D01*
G02Y137240I0J-1502D01*
G01X1406970D01*
G02Y140244I0J1502D01*
G37*
G36*
G01X1323303Y297674D02*
X1319903D01*
G02Y300678I0J1502D01*
G01X1323303D01*
G02Y297674I0J-1502D01*
G37*
G36*
G01X1361771Y330772D02*
X1358371D01*
G02Y333778I0J1503D01*
G01X1361771D01*
G02Y330772I0J-1503D01*
G37*
G36*
G01X555175Y72938D02*
X558575D01*
G02Y69934I0J-1502D01*
G01X555175D01*
G02Y72938I0J1502D01*
G37*
G36*
G01X541002D02*
X544402D01*
G02Y69934I0J-1502D01*
G01X541002D01*
G02Y72938I0J1502D01*
G37*
G36*
G01X519742D02*
X523142D01*
G02Y69934I0J-1502D01*
G01X519742D01*
G02Y72938I0J1502D01*
G37*
G36*
G01X533915Y61324D02*
X537315D01*
G02Y58320I0J-1502D01*
G01X533915D01*
G02Y61324I0J1502D01*
G37*
G36*
G01X1294500Y298190D02*
X1291100D01*
G02Y301194I0J1502D01*
G01X1294500D01*
G02Y298190I0J-1502D01*
G37*
G36*
G01X1404829Y185766D02*
X1408229D01*
G02Y182760I0J-1503D01*
G01X1404829D01*
G02Y185766I0J1503D01*
G37*
G36*
G01X538651Y1615794D02*
X542051D01*
G02Y1612790I0J-1502D01*
G01X538651D01*
G02Y1615794I0J1502D01*
G37*
G36*
G01X526591Y1603882D02*
X529991D01*
G02Y1600878I0J-1502D01*
G01X526591D01*
G02Y1603882I0J1502D01*
G37*
G36*
G01X514531D02*
X517931D01*
G02Y1600878I0J-1502D01*
G01X514531D01*
G02Y1603882I0J1502D01*
G37*
G36*
G01X526591Y1615794D02*
X529991D01*
G02Y1612790I0J-1502D01*
G01X526591D01*
G02Y1615794I0J1502D01*
G37*
G36*
G01X514531D02*
X517931D01*
G02Y1612790I0J-1502D01*
G01X514531D01*
G02Y1615794I0J1502D01*
G37*
G36*
G01X490411Y1603882D02*
X493811D01*
G02Y1600878I0J-1502D01*
G01X490411D01*
G02Y1603882I0J1502D01*
G37*
G36*
G01X478351Y1615794D02*
X481751D01*
G02Y1612790I0J-1502D01*
G01X478351D01*
G02Y1615794I0J1502D01*
G37*
G36*
G01X502471D02*
X505871D01*
G02Y1612790I0J-1502D01*
G01X502471D01*
G02Y1615794I0J1502D01*
G37*
G36*
G01X478351Y1603882D02*
X481751D01*
G02Y1600878I0J-1502D01*
G01X478351D01*
G02Y1603882I0J1502D01*
G37*
G36*
G01X1412284Y173198D02*
X1415684D01*
G02Y170194I0J-1502D01*
G01X1412284D01*
G02Y173198I0J1502D01*
G37*
G36*
G01X598951Y1603882D02*
X602351D01*
G02Y1600878I0J-1502D01*
G01X598951D01*
G02Y1603882I0J1502D01*
G37*
G36*
G01Y1615794D02*
X602351D01*
G02Y1612790I0J-1502D01*
G01X598951D01*
G02Y1615794I0J1502D01*
G37*
G36*
G01X586891Y1603882D02*
X590291D01*
G02Y1600878I0J-1502D01*
G01X586891D01*
G02Y1603882I0J1502D01*
G37*
G36*
G01X647191D02*
X650591D01*
G02Y1600878I0J-1502D01*
G01X647191D01*
G02Y1603882I0J1502D01*
G37*
G36*
G01X635131Y1615794D02*
X638531D01*
G02Y1612790I0J-1502D01*
G01X635131D01*
G02Y1615794I0J1502D01*
G37*
G36*
G01X647191D02*
X650591D01*
G02Y1612790I0J-1502D01*
G01X647191D01*
G02Y1615794I0J1502D01*
G37*
G36*
G01X623071D02*
X626471D01*
G02Y1612790I0J-1502D01*
G01X623071D01*
G02Y1615794I0J1502D01*
G37*
G36*
G01X1355200Y336340D02*
X1351800D01*
G02Y339346I0J1503D01*
G01X1355200D01*
G02Y336340I0J-1503D01*
G37*
G36*
G01X1328814Y292054D02*
X1325414D01*
G02Y295058I0J1502D01*
G01X1328814D01*
G02Y292054I0J-1502D01*
G37*
G36*
G01X1340161Y291902D02*
X1336761D01*
G02Y294906I0J1502D01*
G01X1340161D01*
G02Y291902I0J-1502D01*
G37*
G36*
G01X1413950Y185766D02*
X1417350D01*
G02Y182760I0J-1503D01*
G01X1413950D01*
G02Y185766I0J1503D01*
G37*
G36*
G01X1423110D02*
X1426510D01*
G02Y182760I0J-1503D01*
G01X1423110D01*
G02Y185766I0J1503D01*
G37*
G36*
G01X1401341Y178662D02*
X1404741D01*
G02Y175656I0J-1503D01*
G01X1401341D01*
G02Y178662I0J1503D01*
G37*
G36*
G01X1403778Y173186D02*
X1407178D01*
G02Y170182I0J-1502D01*
G01X1403778D01*
G02Y173186I0J1502D01*
G37*
G36*
G01X1389256Y199170D02*
X1392656D01*
G02Y196166I0J-1502D01*
G01X1389256D01*
G02Y199170I0J1502D01*
G37*
G36*
G01X550711Y1603882D02*
X554111D01*
G02Y1600878I0J-1502D01*
G01X550711D01*
G02Y1603882I0J1502D01*
G37*
G36*
G01X502471D02*
X505871D01*
G02Y1600878I0J-1502D01*
G01X502471D01*
G02Y1603882I0J1502D01*
G37*
G36*
G01X490411Y1615794D02*
X493811D01*
G02Y1612790I0J-1502D01*
G01X490411D01*
G02Y1615794I0J1502D01*
G37*
G36*
G01X987440Y432696D02*
X990840D01*
G02Y429690I0J-1503D01*
G01X987440D01*
G02Y432696I0J1503D01*
G37*
G36*
G01X1471460Y631900D02*
X1468060D01*
G02Y634904I0J1502D01*
G01X1471460D01*
G02Y631900I0J-1502D01*
G37*
G36*
G01X934047Y459364D02*
X937447D01*
G02Y456360I0J-1502D01*
G01X934047D01*
G02Y459364I0J1502D01*
G37*
G36*
G01X942047Y464514D02*
X945447D01*
G02Y461510I0J-1502D01*
G01X942047D01*
G02Y464514I0J1502D01*
G37*
G36*
G01X550711Y1615794D02*
X554111D01*
G02Y1612790I0J-1502D01*
G01X550711D01*
G02Y1615794I0J1502D01*
G37*
G36*
G01X635131Y1603882D02*
X638531D01*
G02Y1600878I0J-1502D01*
G01X635131D01*
G02Y1603882I0J1502D01*
G37*
G36*
G01X909584Y459638D02*
X912984D01*
G02Y456632I0J-1503D01*
G01X909584D01*
G02Y459638I0J1503D01*
G37*
G36*
G01X913394Y523164D02*
X916794D01*
G02Y520160I0J-1502D01*
G01X913394D01*
G02Y523164I0J1502D01*
G37*
G36*
G01X574831Y1603882D02*
X578231D01*
G02Y1600878I0J-1502D01*
G01X574831D01*
G02Y1603882I0J1502D01*
G37*
G36*
G01X659251D02*
X662651D01*
G02Y1600878I0J-1502D01*
G01X659251D01*
G02Y1603882I0J1502D01*
G37*
G36*
G01X1153370Y639694D02*
X1156770D01*
G02Y636690I0J-1502D01*
G01X1153370D01*
G02Y639694I0J1502D01*
G37*
G36*
G01X1406786Y199170D02*
X1410186D01*
G02Y196166I0J-1502D01*
G01X1406786D01*
G02Y199170I0J1502D01*
G37*
G36*
G01X611011Y1615794D02*
X614411D01*
G02Y1612790I0J-1502D01*
G01X611011D01*
G02Y1615794I0J1502D01*
G37*
G36*
G01X1312136Y283446D02*
X1308736D01*
G02Y286450I0J1502D01*
G01X1312136D01*
G02Y283446I0J-1502D01*
G37*
G36*
G01X611011Y1603882D02*
X614411D01*
G02Y1600878I0J-1502D01*
G01X611011D01*
G02Y1603882I0J1502D01*
G37*
G36*
G01X586891Y1615794D02*
X590291D01*
G02Y1612790I0J-1502D01*
G01X586891D01*
G02Y1615794I0J1502D01*
G37*
G36*
G01X659251D02*
X662651D01*
G02Y1612790I0J-1502D01*
G01X659251D01*
G02Y1615794I0J1502D01*
G37*
G36*
G01X574831D02*
X578231D01*
G02Y1612790I0J-1502D01*
G01X574831D01*
G02Y1615794I0J1502D01*
G37*
G36*
G01X1183360Y643564D02*
X1186760D01*
G02Y640560I0J-1502D01*
G01X1183360D01*
G02Y643564I0J1502D01*
G37*
G36*
G01X562771Y1615794D02*
X566171D01*
G02Y1612790I0J-1502D01*
G01X562771D01*
G02Y1615794I0J1502D01*
G37*
G36*
G01X901230Y533114D02*
X904630D01*
G02Y530110I0J-1502D01*
G01X901230D01*
G02Y533114I0J1502D01*
G37*
G36*
G01X954390Y529098D02*
X957790D01*
G02Y526094I0J-1502D01*
G01X954390D01*
G02Y529098I0J1502D01*
G37*
G36*
G01X963930Y534864D02*
X967330D01*
G02Y531860I0J-1502D01*
G01X963930D01*
G02Y534864I0J1502D01*
G37*
G36*
G01X548070Y80874D02*
X551470D01*
G02Y77870I0J-1502D01*
G01X548070D01*
G02Y80874I0J1502D01*
G37*
G36*
G01X623071Y1603882D02*
X626471D01*
G02Y1600878I0J-1502D01*
G01X623071D01*
G02Y1603882I0J1502D01*
G37*
G36*
G01X888130Y534114D02*
X891530D01*
G02Y531110I0J-1502D01*
G01X888130D01*
G02Y534114I0J1502D01*
G37*
G36*
G01X297437Y1591596D02*
X300837D01*
G02Y1588592I0J-1502D01*
G01X297437D01*
G02Y1591596I0J1502D01*
G37*
G36*
G01X237137D02*
X240537D01*
G02Y1588592I0J-1502D01*
G01X237137D01*
G02Y1591596I0J1502D01*
G37*
G36*
G01X937340Y309612D02*
X920138D01*
G02X937340I8601J12041D01*
G37*
G36*
G01X921047Y464514D02*
X924447D01*
G02Y461510I0J-1502D01*
G01X921047D01*
G02Y464514I0J1502D01*
G37*
G36*
G01X371587Y173422D02*
X365287D01*
G02Y197050I0J11814D01*
G01X371587D01*
G02Y173422I0J-11814D01*
G37*
G36*
G01X253477D02*
X247176D01*
G02X247175Y197050I0J11814D01*
G01X253476D01*
G02X253477Y173422I0J-11814D01*
G37*
G36*
G01X1012861Y434390D02*
X1016261D01*
G02Y431386I0J-1502D01*
G01X1012861D01*
G02Y434390I0J1502D01*
G37*
G36*
G01X50772Y120610D02*
X55372Y124913D01*
G02X66448Y113076I5538J-5919D01*
G01X61848Y108773D01*
G02X50772Y120610I-5538J5918D01*
G37*
G36*
G01X62587Y23395D02*
G02X58024Y17311I-2280J-3043D01*
G02X62587Y23395I2279J3044D01*
G37*
G36*
G01X353132Y870606D02*
G02X355726I1297J0D01*
G02X355654Y870177I-1297J-3D01*
G01X355623Y870091D01*
X356430Y868693D01*
X356520Y868676D01*
G02X357576Y867401I-242J-1275D01*
G02X354980I-1298J0D01*
G02X355053Y867830I1297J0D01*
G01X355084Y867916D01*
X354277Y869314D01*
X354187Y869331D01*
G02X353132Y870606I243J1275D01*
G37*
G36*
G01X360532D02*
G02X363126I1297J0D01*
G02X363054Y870177I-1297J-3D01*
G01X363023Y870091D01*
X363830Y868693D01*
X363920Y868676D01*
G02X364976Y867401I-242J-1275D01*
G02X362380I-1298J0D01*
G02X362453Y867830I1297J0D01*
G01X362484Y867916D01*
X361677Y869314D01*
X361587Y869331D01*
G02X360532Y870606I243J1275D01*
G37*
G36*
G01X367932D02*
G02X370526I1297J0D01*
G02X370454Y870177I-1297J-3D01*
G01X370423Y870091D01*
X371230Y868693D01*
X371320Y868676D01*
G02X372376Y867401I-242J-1275D01*
G02X369780I-1298J0D01*
G02X369853Y867830I1297J0D01*
G01X369884Y867916D01*
X369077Y869314D01*
X368987Y869331D01*
G02X367932Y870606I243J1275D01*
G37*
G36*
G01X375332D02*
G02X377926I1297J0D01*
G02X377854Y870177I-1297J-3D01*
G01X377823Y870091D01*
X378630Y868693D01*
X378720Y868676D01*
G02X379776Y867401I-242J-1275D01*
G02X377180I-1298J0D01*
G02X377253Y867830I1297J0D01*
G01X377284Y867916D01*
X376477Y869314D01*
X376387Y869331D01*
G02X375332Y870606I243J1275D01*
G37*
G36*
G01X382732D02*
G02X385326I1297J0D01*
G02X385254Y870177I-1297J-3D01*
G01X385223Y870091D01*
X386030Y868693D01*
X386120Y868676D01*
G02X387176Y867401I-242J-1275D01*
G02X384580I-1298J0D01*
G02X384653Y867830I1297J0D01*
G01X384684Y867916D01*
X383877Y869314D01*
X383787Y869331D01*
G02X382732Y870606I243J1275D01*
G37*
G36*
G01X390132D02*
G02X392726I1297J0D01*
G02X392654Y870177I-1297J-3D01*
G01X392623Y870091D01*
X393430Y868693D01*
X393520Y868676D01*
G02X394576Y867401I-242J-1275D01*
G02X391980I-1298J0D01*
G02X392053Y867830I1297J0D01*
G01X392084Y867916D01*
X391277Y869314D01*
X391187Y869331D01*
G02X390132Y870606I243J1275D01*
G37*
G36*
G01X397532D02*
G02X400126I1297J0D01*
G02X400054Y870177I-1297J-3D01*
G01X400023Y870091D01*
X400830Y868693D01*
X400920Y868676D01*
G02X401976Y867401I-242J-1275D01*
G02X399380I-1298J0D01*
G02X399453Y867830I1297J0D01*
G01X399484Y867916D01*
X398677Y869314D01*
X398587Y869331D01*
G02X397532Y870606I243J1275D01*
G37*
G36*
G01X404932D02*
G02X407526I1297J0D01*
G02X407454Y870177I-1297J-3D01*
G01X407423Y870091D01*
X408230Y868693D01*
X408320Y868676D01*
G02X409376Y867401I-242J-1275D01*
G02X406780I-1298J0D01*
G02X406853Y867830I1297J0D01*
G01X406884Y867916D01*
X406077Y869314D01*
X405987Y869331D01*
G02X404932Y870606I243J1275D01*
G37*
G36*
G01X416032D02*
G02X418626I1297J0D01*
G02X417571Y869331I-1298J0D01*
G01X417481Y869314D01*
X416673Y867915D01*
X416703Y867828D01*
G02X416776Y867401I-1225J-429D01*
G02X414180I-1298J0D01*
G02X415238Y868676I1297J0D01*
G01X415328Y868693D01*
X416135Y870091D01*
X416104Y870178D01*
G02X416032Y870606I1225J426D01*
G37*
G36*
G01X423432D02*
G02X426026I1297J0D01*
G02X424971Y869331I-1298J0D01*
G01X424881Y869314D01*
X424073Y867915D01*
X424103Y867828D01*
G02X424176Y867401I-1225J-429D01*
G02X421580I-1298J0D01*
G02X422638Y868676I1297J0D01*
G01X422728Y868693D01*
X423535Y870091D01*
X423504Y870178D01*
G02X423432Y870606I1225J426D01*
G37*
G36*
G01X430832D02*
G02X433426I1297J0D01*
G02X432371Y869331I-1298J0D01*
G01X432281Y869314D01*
X431473Y867915D01*
X431503Y867828D01*
G02X431576Y867401I-1225J-429D01*
G02X428980I-1298J0D01*
G02X430038Y868676I1297J0D01*
G01X430128Y868693D01*
X430935Y870091D01*
X430904Y870178D01*
G02X430832Y870606I1225J426D01*
G37*
G36*
G01X438232D02*
G02X440826I1297J0D01*
G02X439771Y869331I-1298J0D01*
G01X439681Y869314D01*
X438873Y867915D01*
X438903Y867828D01*
G02X438976Y867401I-1225J-429D01*
G02X436380I-1298J0D01*
G02X437438Y868676I1297J0D01*
G01X437528Y868693D01*
X438335Y870091D01*
X438304Y870178D01*
G02X438232Y870606I1225J426D01*
G37*
G36*
G01X445632D02*
G02X448226I1297J0D01*
G02X447171Y869331I-1298J0D01*
G01X447081Y869314D01*
X446273Y867915D01*
X446303Y867828D01*
G02X446376Y867401I-1225J-429D01*
G02X443780I-1298J0D01*
G02X444838Y868676I1297J0D01*
G01X444928Y868693D01*
X445735Y870091D01*
X445704Y870178D01*
G02X445632Y870606I1225J426D01*
G37*
G36*
G01X453032D02*
G02X455626I1297J0D01*
G02X454571Y869331I-1298J0D01*
G01X454481Y869314D01*
X453673Y867915D01*
X453703Y867828D01*
G02X453776Y867401I-1225J-429D01*
G02X451180I-1298J0D01*
G02X452238Y868676I1297J0D01*
G01X452328Y868693D01*
X453135Y870091D01*
X453104Y870178D01*
G02X453032Y870606I1225J426D01*
G37*
G36*
G01X460432D02*
G02X463026I1297J0D01*
G02X461971Y869331I-1298J0D01*
G01X461881Y869314D01*
X461073Y867915D01*
X461103Y867828D01*
G02X461176Y867401I-1225J-429D01*
G02X458580I-1298J0D01*
G02X459638Y868676I1297J0D01*
G01X459728Y868693D01*
X460535Y870091D01*
X460504Y870178D01*
G02X460432Y870606I1225J426D01*
G37*
G36*
G01X467832D02*
G02X470426I1297J0D01*
G02X469371Y869331I-1298J0D01*
G01X469281Y869314D01*
X468473Y867915D01*
X468503Y867828D01*
G02X468576Y867401I-1225J-429D01*
G02X465980I-1298J0D01*
G02X467038Y868676I1297J0D01*
G01X467128Y868693D01*
X467935Y870091D01*
X467904Y870178D01*
G02X467832Y870606I1225J426D01*
G37*
G36*
G01X475232D02*
G02X477826I1297J0D01*
G02X476771Y869331I-1298J0D01*
G01X476681Y869314D01*
X475873Y867915D01*
X475903Y867828D01*
G02X475976Y867401I-1225J-429D01*
G02X473380I-1298J0D01*
G02X474438Y868676I1297J0D01*
G01X474528Y868693D01*
X475335Y870091D01*
X475304Y870178D01*
G02X475232Y870606I1225J426D01*
G37*
G36*
G01X482632D02*
G02X485226I1297J0D01*
G02X484171Y869331I-1298J0D01*
G01X484081Y869314D01*
X483273Y867915D01*
X483303Y867828D01*
G02X483376Y867401I-1225J-429D01*
G02X480780I-1298J0D01*
G02X481838Y868676I1297J0D01*
G01X481928Y868693D01*
X482735Y870091D01*
X482704Y870178D01*
G02X482632Y870606I1225J426D01*
G37*
G36*
G01X490032D02*
G02X492626I1297J0D01*
G02X491571Y869331I-1298J0D01*
G01X491481Y869314D01*
X490673Y867915D01*
X490703Y867828D01*
G02X490776Y867401I-1225J-429D01*
G02X488180I-1298J0D01*
G02X489238Y868676I1297J0D01*
G01X489328Y868693D01*
X490135Y870091D01*
X490104Y870178D01*
G02X490032Y870606I1225J426D01*
G37*
G36*
G01X497432D02*
G02X500026I1297J0D01*
G02X498971Y869331I-1298J0D01*
G01X498881Y869314D01*
X498073Y867915D01*
X498103Y867828D01*
G02X498176Y867401I-1225J-429D01*
G02X495580I-1298J0D01*
G02X496638Y868676I1297J0D01*
G01X496728Y868693D01*
X497535Y870091D01*
X497504Y870178D01*
G02X497432Y870606I1225J426D01*
G37*
G36*
G01X504832D02*
G02X507426I1297J0D01*
G02X506371Y869331I-1298J0D01*
G01X506281Y869314D01*
X505473Y867915D01*
X505503Y867828D01*
G02X505576Y867401I-1225J-429D01*
G02X502980I-1298J0D01*
G02X504038Y868676I1297J0D01*
G01X504128Y868693D01*
X504935Y870091D01*
X504904Y870178D01*
G02X504832Y870606I1225J426D01*
G37*
G36*
G01X512232D02*
G02X514826I1297J0D01*
G02X513771Y869331I-1298J0D01*
G01X513681Y869314D01*
X512873Y867915D01*
X512903Y867828D01*
G02X512976Y867401I-1225J-429D01*
G02X510380I-1298J0D01*
G02X511438Y868676I1297J0D01*
G01X511528Y868693D01*
X512335Y870091D01*
X512304Y870178D01*
G02X512232Y870606I1225J426D01*
G37*
G36*
G01X519632D02*
G02X522226I1297J0D01*
G02X521171Y869331I-1298J0D01*
G01X521081Y869314D01*
X520273Y867915D01*
X520303Y867828D01*
G02X520376Y867401I-1225J-429D01*
G02X517780I-1298J0D01*
G02X518838Y868676I1297J0D01*
G01X518928Y868693D01*
X519735Y870091D01*
X519704Y870178D01*
G02X519632Y870606I1225J426D01*
G37*
G36*
G01X527032D02*
G02X529626I1297J0D01*
G02X528571Y869331I-1298J0D01*
G01X528481Y869314D01*
X527674Y867916D01*
X527704Y867829D01*
G02X527776Y867401I-1225J-426D01*
G02X525182I-1297J0D01*
G02X526238Y868676I1298J0D01*
G01X526328Y868693D01*
X527135Y870091D01*
X527104Y870178D01*
G02X527032Y870606I1225J426D01*
G37*
G36*
G01X1329274D02*
G02X1331868I1297J0D01*
G02X1331796Y870177I-1297J-3D01*
G01X1331765Y870091D01*
X1332572Y868693D01*
X1332662Y868676D01*
G02X1333718Y867401I-242J-1275D01*
G02X1331122I-1298J0D01*
G02X1331195Y867830I1297J0D01*
G01X1331226Y867916D01*
X1330419Y869314D01*
X1330329Y869331D01*
G02X1329274Y870606I243J1275D01*
G37*
G36*
G01X1336674D02*
G02X1339268I1297J0D01*
G02X1339196Y870177I-1297J-3D01*
G01X1339165Y870091D01*
X1339972Y868693D01*
X1340062Y868676D01*
G02X1341118Y867401I-242J-1275D01*
G02X1338522I-1298J0D01*
G02X1338595Y867830I1297J0D01*
G01X1338626Y867916D01*
X1337819Y869314D01*
X1337729Y869331D01*
G02X1336674Y870606I243J1275D01*
G37*
G36*
G01X1344074D02*
G02X1346668I1297J0D01*
G02X1346596Y870177I-1297J-3D01*
G01X1346565Y870091D01*
X1347372Y868693D01*
X1347462Y868676D01*
G02X1348518Y867401I-242J-1275D01*
G02X1345922I-1298J0D01*
G02X1345995Y867830I1297J0D01*
G01X1346026Y867916D01*
X1345219Y869314D01*
X1345129Y869331D01*
G02X1344074Y870606I243J1275D01*
G37*
G36*
G01X1351474D02*
G02X1354068I1297J0D01*
G02X1353996Y870177I-1297J-3D01*
G01X1353965Y870091D01*
X1354772Y868693D01*
X1354862Y868676D01*
G02X1355918Y867401I-242J-1275D01*
G02X1353322I-1298J0D01*
G02X1353395Y867830I1297J0D01*
G01X1353426Y867916D01*
X1352619Y869314D01*
X1352529Y869331D01*
G02X1351474Y870606I243J1275D01*
G37*
G36*
G01X1358874D02*
G02X1361468I1297J0D01*
G02X1361396Y870177I-1297J-3D01*
G01X1361365Y870091D01*
X1362172Y868693D01*
X1362262Y868676D01*
G02X1363318Y867401I-242J-1275D01*
G02X1360722I-1298J0D01*
G02X1360795Y867830I1297J0D01*
G01X1360826Y867916D01*
X1360019Y869314D01*
X1359929Y869331D01*
G02X1358874Y870606I243J1275D01*
G37*
G36*
G01X1366274D02*
G02X1368868I1297J0D01*
G02X1368796Y870177I-1297J-3D01*
G01X1368765Y870091D01*
X1369572Y868693D01*
X1369662Y868676D01*
G02X1370718Y867401I-242J-1275D01*
G02X1368122I-1298J0D01*
G02X1368195Y867830I1297J0D01*
G01X1368226Y867916D01*
X1367419Y869314D01*
X1367329Y869331D01*
G02X1366274Y870606I243J1275D01*
G37*
G36*
G01X1373674D02*
G02X1376268I1297J0D01*
G02X1376196Y870177I-1297J-3D01*
G01X1376165Y870091D01*
X1376972Y868693D01*
X1377062Y868676D01*
G02X1378118Y867401I-242J-1275D01*
G02X1375522I-1298J0D01*
G02X1375595Y867830I1297J0D01*
G01X1375626Y867916D01*
X1374819Y869314D01*
X1374729Y869331D01*
G02X1373674Y870606I243J1275D01*
G37*
G36*
G01X1381074D02*
G02X1383668I1297J0D01*
G02X1383596Y870177I-1297J-3D01*
G01X1383565Y870091D01*
X1384372Y868693D01*
X1384462Y868676D01*
G02X1385518Y867401I-242J-1275D01*
G02X1382922I-1298J0D01*
G02X1382995Y867830I1297J0D01*
G01X1383026Y867916D01*
X1382219Y869314D01*
X1382129Y869331D01*
G02X1381074Y870606I243J1275D01*
G37*
G36*
G01X1392174D02*
G02X1394768I1297J0D01*
G02X1393713Y869331I-1298J0D01*
G01X1393623Y869314D01*
X1392815Y867915D01*
X1392845Y867828D01*
G02X1392918Y867401I-1225J-429D01*
G02X1390322I-1298J0D01*
G02X1391380Y868676I1297J0D01*
G01X1391470Y868693D01*
X1392277Y870091D01*
X1392246Y870178D01*
G02X1392174Y870606I1225J426D01*
G37*
G36*
G01X1399574D02*
G02X1402168I1297J0D01*
G02X1401113Y869331I-1298J0D01*
G01X1401023Y869314D01*
X1400215Y867915D01*
X1400245Y867828D01*
G02X1400318Y867401I-1225J-429D01*
G02X1397722I-1298J0D01*
G02X1398780Y868676I1297J0D01*
G01X1398870Y868693D01*
X1399677Y870091D01*
X1399646Y870178D01*
G02X1399574Y870606I1225J426D01*
G37*
G36*
G01X1406974D02*
G02X1409568I1297J0D01*
G02X1408513Y869331I-1298J0D01*
G01X1408423Y869314D01*
X1407615Y867915D01*
X1407645Y867828D01*
G02X1407718Y867401I-1225J-429D01*
G02X1405122I-1298J0D01*
G02X1406180Y868676I1297J0D01*
G01X1406270Y868693D01*
X1407077Y870091D01*
X1407046Y870178D01*
G02X1406974Y870606I1225J426D01*
G37*
G36*
G01X1414374D02*
G02X1416968I1297J0D01*
G02X1415913Y869331I-1298J0D01*
G01X1415823Y869314D01*
X1415015Y867915D01*
X1415045Y867828D01*
G02X1415118Y867401I-1225J-429D01*
G02X1412522I-1298J0D01*
G02X1413580Y868676I1297J0D01*
G01X1413670Y868693D01*
X1414477Y870091D01*
X1414446Y870178D01*
G02X1414374Y870606I1225J426D01*
G37*
G36*
G01X1421774D02*
G02X1424368I1297J0D01*
G02X1423313Y869331I-1298J0D01*
G01X1423223Y869314D01*
X1422415Y867915D01*
X1422445Y867828D01*
G02X1422518Y867401I-1225J-429D01*
G02X1419922I-1298J0D01*
G02X1420980Y868676I1297J0D01*
G01X1421070Y868693D01*
X1421877Y870091D01*
X1421846Y870178D01*
G02X1421774Y870606I1225J426D01*
G37*
G36*
G01X1429174D02*
G02X1431768I1297J0D01*
G02X1430713Y869331I-1298J0D01*
G01X1430623Y869314D01*
X1429815Y867915D01*
X1429845Y867828D01*
G02X1429918Y867401I-1225J-429D01*
G02X1427322I-1298J0D01*
G02X1428380Y868676I1297J0D01*
G01X1428470Y868693D01*
X1429277Y870091D01*
X1429246Y870178D01*
G02X1429174Y870606I1225J426D01*
G37*
G36*
G01X1436574D02*
G02X1439168I1297J0D01*
G02X1438113Y869331I-1298J0D01*
G01X1438023Y869314D01*
X1437215Y867915D01*
X1437245Y867828D01*
G02X1437318Y867401I-1225J-429D01*
G02X1434722I-1298J0D01*
G02X1435780Y868676I1297J0D01*
G01X1435870Y868693D01*
X1436677Y870091D01*
X1436646Y870178D01*
G02X1436574Y870606I1225J426D01*
G37*
G36*
G01X1443974D02*
G02X1446568I1297J0D01*
G02X1445513Y869331I-1298J0D01*
G01X1445423Y869314D01*
X1444615Y867915D01*
X1444645Y867828D01*
G02X1444718Y867401I-1225J-429D01*
G02X1442122I-1298J0D01*
G02X1443180Y868676I1297J0D01*
G01X1443270Y868693D01*
X1444077Y870091D01*
X1444046Y870178D01*
G02X1443974Y870606I1225J426D01*
G37*
G36*
G01X1451374D02*
G02X1453968I1297J0D01*
G02X1452913Y869331I-1298J0D01*
G01X1452823Y869314D01*
X1452015Y867915D01*
X1452045Y867828D01*
G02X1452118Y867401I-1225J-429D01*
G02X1449522I-1298J0D01*
G02X1450580Y868676I1297J0D01*
G01X1450670Y868693D01*
X1451477Y870091D01*
X1451446Y870178D01*
G02X1451374Y870606I1225J426D01*
G37*
G36*
G01X1458774D02*
G02X1461368I1297J0D01*
G02X1460313Y869331I-1298J0D01*
G01X1460223Y869314D01*
X1459415Y867915D01*
X1459445Y867828D01*
G02X1459518Y867401I-1225J-429D01*
G02X1456922I-1298J0D01*
G02X1457980Y868676I1297J0D01*
G01X1458070Y868693D01*
X1458877Y870091D01*
X1458846Y870178D01*
G02X1458774Y870606I1225J426D01*
G37*
G36*
G01X1466174D02*
G02X1468768I1297J0D01*
G02X1467713Y869331I-1298J0D01*
G01X1467623Y869314D01*
X1466815Y867915D01*
X1466845Y867828D01*
G02X1466918Y867401I-1225J-429D01*
G02X1464322I-1298J0D01*
G02X1465380Y868676I1297J0D01*
G01X1465470Y868693D01*
X1466277Y870091D01*
X1466246Y870178D01*
G02X1466174Y870606I1225J426D01*
G37*
G36*
G01X1473574D02*
G02X1476168I1297J0D01*
G02X1475113Y869331I-1298J0D01*
G01X1475023Y869314D01*
X1474215Y867915D01*
X1474245Y867828D01*
G02X1474318Y867401I-1225J-429D01*
G02X1471722I-1298J0D01*
G02X1472780Y868676I1297J0D01*
G01X1472870Y868693D01*
X1473677Y870091D01*
X1473646Y870178D01*
G02X1473574Y870606I1225J426D01*
G37*
G36*
G01X1480974D02*
G02X1483568I1297J0D01*
G02X1482513Y869331I-1298J0D01*
G01X1482423Y869314D01*
X1481615Y867915D01*
X1481645Y867828D01*
G02X1481718Y867401I-1225J-429D01*
G02X1479122I-1298J0D01*
G02X1480180Y868676I1297J0D01*
G01X1480270Y868693D01*
X1481077Y870091D01*
X1481046Y870178D01*
G02X1480974Y870606I1225J426D01*
G37*
G36*
G01X1488374D02*
G02X1490968I1297J0D01*
G02X1489913Y869331I-1298J0D01*
G01X1489823Y869314D01*
X1489015Y867915D01*
X1489045Y867828D01*
G02X1489118Y867401I-1225J-429D01*
G02X1486522I-1298J0D01*
G02X1487580Y868676I1297J0D01*
G01X1487670Y868693D01*
X1488477Y870091D01*
X1488446Y870178D01*
G02X1488374Y870606I1225J426D01*
G37*
G36*
G01X1495774D02*
G02X1498368I1297J0D01*
G02X1497313Y869331I-1298J0D01*
G01X1497223Y869314D01*
X1496415Y867915D01*
X1496445Y867828D01*
G02X1496518Y867401I-1225J-429D01*
G02X1493922I-1298J0D01*
G02X1494980Y868676I1297J0D01*
G01X1495070Y868693D01*
X1495877Y870091D01*
X1495846Y870178D01*
G02X1495774Y870606I1225J426D01*
G37*
G36*
G01X1503174D02*
G02X1505768I1297J0D01*
G02X1504713Y869331I-1298J0D01*
G01X1504623Y869314D01*
X1503816Y867916D01*
X1503846Y867829D01*
G02X1503918Y867401I-1225J-426D01*
G02X1501324I-1297J0D01*
G02X1502380Y868676I1298J0D01*
G01X1502470Y868693D01*
X1503277Y870091D01*
X1503246Y870178D01*
G02X1503174Y870606I1225J426D01*
G37*
G36*
G01X351280Y873810D02*
G02X353876I1298J0D01*
G02X352820Y872535I-1298J0D01*
G01X352730Y872518D01*
X351923Y871121D01*
X351954Y871034D01*
G02X352026Y870606I-1225J-426D01*
G02X349432I-1297J0D01*
G02X350487Y871881I1298J0D01*
G01X350577Y871898D01*
X351384Y873295D01*
X351353Y873382D01*
G02X351280Y873810I1225J429D01*
G37*
G36*
G01X358680D02*
G02X361276I1298J0D01*
G02X360220Y872535I-1298J0D01*
G01X360130Y872518D01*
X359323Y871121D01*
X359354Y871034D01*
G02X359426Y870606I-1225J-426D01*
G02X356832I-1297J0D01*
G02X357887Y871881I1298J0D01*
G01X357977Y871898D01*
X358784Y873295D01*
X358753Y873382D01*
G02X358680Y873810I1225J429D01*
G37*
G36*
G01X366080D02*
G02X368676I1298J0D01*
G02X367620Y872535I-1298J0D01*
G01X367530Y872518D01*
X366723Y871121D01*
X366754Y871034D01*
G02X366826Y870606I-1225J-426D01*
G02X364232I-1297J0D01*
G02X365287Y871881I1298J0D01*
G01X365377Y871898D01*
X366184Y873295D01*
X366153Y873382D01*
G02X366080Y873810I1225J429D01*
G37*
G36*
G01X373480D02*
G02X376076I1298J0D01*
G02X375020Y872535I-1298J0D01*
G01X374930Y872518D01*
X374123Y871121D01*
X374154Y871034D01*
G02X374226Y870606I-1225J-426D01*
G02X371632I-1297J0D01*
G02X372687Y871881I1298J0D01*
G01X372777Y871898D01*
X373584Y873295D01*
X373553Y873382D01*
G02X373480Y873810I1225J429D01*
G37*
G36*
G01X380880D02*
G02X383476I1298J0D01*
G02X382420Y872535I-1298J0D01*
G01X382330Y872518D01*
X381523Y871121D01*
X381554Y871034D01*
G02X381626Y870606I-1225J-426D01*
G02X379032I-1297J0D01*
G02X380087Y871881I1298J0D01*
G01X380177Y871898D01*
X380984Y873295D01*
X380953Y873382D01*
G02X380880Y873810I1225J429D01*
G37*
G36*
G01X388280D02*
G02X390876I1298J0D01*
G02X389820Y872535I-1298J0D01*
G01X389730Y872518D01*
X388923Y871121D01*
X388954Y871034D01*
G02X389026Y870606I-1225J-426D01*
G02X386432I-1297J0D01*
G02X387487Y871881I1298J0D01*
G01X387577Y871898D01*
X388384Y873295D01*
X388353Y873382D01*
G02X388280Y873810I1225J429D01*
G37*
G36*
G01X395680D02*
G02X398276I1298J0D01*
G02X397220Y872535I-1298J0D01*
G01X397130Y872518D01*
X396323Y871121D01*
X396354Y871034D01*
G02X396426Y870606I-1225J-426D01*
G02X393832I-1297J0D01*
G02X394887Y871881I1298J0D01*
G01X394977Y871898D01*
X395784Y873295D01*
X395753Y873382D01*
G02X395680Y873810I1225J429D01*
G37*
G36*
G01X403080D02*
G02X405676I1298J0D01*
G02X404620Y872535I-1298J0D01*
G01X404530Y872518D01*
X403723Y871121D01*
X403754Y871034D01*
G02X403826Y870606I-1225J-426D01*
G02X401232I-1297J0D01*
G02X402287Y871881I1298J0D01*
G01X402377Y871898D01*
X403184Y873295D01*
X403153Y873382D01*
G02X403080Y873810I1225J429D01*
G37*
G36*
G01X410480D02*
G02X413076I1298J0D01*
G02X413003Y873381I-1297J0D01*
G01X412972Y873295D01*
X413778Y871898D01*
X413868Y871881D01*
G02X414926Y870606I-239J-1275D01*
G02X412332I-1297J0D01*
G02X412403Y871032I1297J3D01*
G01X412434Y871119D01*
X411626Y872518D01*
X411536Y872535D01*
G02X410480Y873810I242J1275D01*
G37*
G36*
G01X417880D02*
G02X420476I1298J0D01*
G02X420403Y873381I-1297J0D01*
G01X420372Y873295D01*
X421178Y871898D01*
X421268Y871881D01*
G02X422326Y870606I-239J-1275D01*
G02X419732I-1297J0D01*
G02X419803Y871032I1297J3D01*
G01X419834Y871119D01*
X419026Y872518D01*
X418936Y872535D01*
G02X417880Y873810I242J1275D01*
G37*
G36*
G01X425280D02*
G02X427876I1298J0D01*
G02X427803Y873381I-1297J0D01*
G01X427772Y873295D01*
X428578Y871898D01*
X428668Y871881D01*
G02X429726Y870606I-239J-1275D01*
G02X427132I-1297J0D01*
G02X427203Y871032I1297J3D01*
G01X427234Y871119D01*
X426426Y872518D01*
X426336Y872535D01*
G02X425280Y873810I242J1275D01*
G37*
G36*
G01X432682D02*
G02X435276I1297J0D01*
G02X435204Y873381I-1297J-3D01*
G01X435173Y873295D01*
X435979Y871898D01*
X436069Y871881D01*
G02X437126Y870606I-240J-1275D01*
G02X434532I-1297J0D01*
G01Y870608D01*
G02X434604Y871033I1297J-1D01*
G01X434634Y871120D01*
X433827Y872518D01*
X433737Y872535D01*
G02X432682Y873810I243J1275D01*
G37*
G36*
G01X440080D02*
G02X442676I1298J0D01*
G02X442603Y873381I-1297J0D01*
G01X442572Y873295D01*
X443378Y871898D01*
X443468Y871881D01*
G02X444526Y870606I-239J-1275D01*
G02X441932I-1297J0D01*
G02X442003Y871032I1297J3D01*
G01X442034Y871119D01*
X441226Y872518D01*
X441136Y872535D01*
G02X440080Y873810I242J1275D01*
G37*
G36*
G01X447482D02*
G02X450076I1297J0D01*
G02X450004Y873381I-1297J-3D01*
G01X449973Y873295D01*
X450779Y871898D01*
X450869Y871881D01*
G02X451926Y870606I-240J-1275D01*
G02X449332I-1297J0D01*
G01Y870608D01*
G02X449404Y871033I1297J-1D01*
G01X449434Y871120D01*
X448627Y872518D01*
X448537Y872535D01*
G02X447482Y873810I243J1275D01*
G37*
G36*
G01X454880D02*
G02X457476I1298J0D01*
G02X457403Y873381I-1297J0D01*
G01X457372Y873295D01*
X458178Y871898D01*
X458268Y871881D01*
G02X459326Y870606I-239J-1275D01*
G02X456732I-1297J0D01*
G02X456803Y871032I1297J3D01*
G01X456834Y871119D01*
X456026Y872518D01*
X455936Y872535D01*
G02X454880Y873810I242J1275D01*
G37*
G36*
G01X462280D02*
G02X464876I1298J0D01*
G02X464803Y873381I-1297J0D01*
G01X464772Y873295D01*
X465578Y871898D01*
X465668Y871881D01*
G02X466726Y870606I-239J-1275D01*
G02X464132I-1297J0D01*
G02X464203Y871032I1297J3D01*
G01X464234Y871119D01*
X463426Y872518D01*
X463336Y872535D01*
G02X462280Y873810I242J1275D01*
G37*
G36*
G01X477080D02*
G02X479676I1298J0D01*
G02X479603Y873381I-1297J0D01*
G01X479572Y873295D01*
X480378Y871898D01*
X480468Y871881D01*
G02X481526Y870606I-239J-1275D01*
G02X478932I-1297J0D01*
G02X479003Y871032I1297J3D01*
G01X479034Y871119D01*
X478226Y872518D01*
X478136Y872535D01*
G02X477080Y873810I242J1275D01*
G37*
G36*
G01X484480D02*
G02X487076I1298J0D01*
G02X487003Y873381I-1297J0D01*
G01X486972Y873295D01*
X487778Y871898D01*
X487868Y871881D01*
G02X488926Y870606I-239J-1275D01*
G02X486332I-1297J0D01*
G02X486403Y871032I1297J3D01*
G01X486434Y871119D01*
X485626Y872518D01*
X485536Y872535D01*
G02X484480Y873810I242J1275D01*
G37*
G36*
G01X491880D02*
G02X494476I1298J0D01*
G02X494403Y873381I-1297J0D01*
G01X494372Y873295D01*
X495178Y871898D01*
X495268Y871881D01*
G02X496326Y870606I-239J-1275D01*
G02X493732I-1297J0D01*
G02X493803Y871032I1297J3D01*
G01X493834Y871119D01*
X493026Y872518D01*
X492936Y872535D01*
G02X491880Y873810I242J1275D01*
G37*
G36*
G01X499280D02*
G02X501876I1298J0D01*
G02X501803Y873381I-1297J0D01*
G01X501772Y873295D01*
X502578Y871898D01*
X502668Y871881D01*
G02X503726Y870606I-239J-1275D01*
G02X501132I-1297J0D01*
G02X501203Y871032I1297J3D01*
G01X501234Y871119D01*
X500426Y872518D01*
X500336Y872535D01*
G02X499280Y873810I242J1275D01*
G37*
G36*
G01X506680D02*
G02X509276I1298J0D01*
G02X509203Y873381I-1297J0D01*
G01X509172Y873295D01*
X509978Y871898D01*
X510068Y871881D01*
G02X511126Y870606I-239J-1275D01*
G02X508532I-1297J0D01*
G02X508603Y871032I1297J3D01*
G01X508634Y871119D01*
X507826Y872518D01*
X507736Y872535D01*
G02X506680Y873810I242J1275D01*
G37*
G36*
G01X514080D02*
G02X516676I1298J0D01*
G02X516603Y873381I-1297J0D01*
G01X516572Y873295D01*
X517378Y871898D01*
X517468Y871881D01*
G02X518526Y870606I-239J-1275D01*
G02X515932I-1297J0D01*
G02X516003Y871032I1297J3D01*
G01X516034Y871119D01*
X515226Y872518D01*
X515136Y872535D01*
G02X514080Y873810I242J1275D01*
G37*
G36*
G01X1327422D02*
G02X1330018I1298J0D01*
G02X1328962Y872535I-1298J0D01*
G01X1328872Y872518D01*
X1328065Y871121D01*
X1328096Y871034D01*
G02X1328168Y870606I-1225J-426D01*
G02X1325574I-1297J0D01*
G02X1326629Y871881I1298J0D01*
G01X1326719Y871898D01*
X1327526Y873295D01*
X1327495Y873382D01*
G02X1327422Y873810I1225J429D01*
G37*
G36*
G01X1334822D02*
G02X1337418I1298J0D01*
G02X1336362Y872535I-1298J0D01*
G01X1336272Y872518D01*
X1335465Y871121D01*
X1335496Y871034D01*
G02X1335568Y870606I-1225J-426D01*
G02X1332974I-1297J0D01*
G02X1334029Y871881I1298J0D01*
G01X1334119Y871898D01*
X1334926Y873295D01*
X1334895Y873382D01*
G02X1334822Y873810I1225J429D01*
G37*
G36*
G01X1342222D02*
G02X1344818I1298J0D01*
G02X1343762Y872535I-1298J0D01*
G01X1343672Y872518D01*
X1342865Y871121D01*
X1342896Y871034D01*
G02X1342968Y870606I-1225J-426D01*
G02X1340374I-1297J0D01*
G02X1341429Y871881I1298J0D01*
G01X1341519Y871898D01*
X1342326Y873295D01*
X1342295Y873382D01*
G02X1342222Y873810I1225J429D01*
G37*
G36*
G01X1349622D02*
G02X1352218I1298J0D01*
G02X1351162Y872535I-1298J0D01*
G01X1351072Y872518D01*
X1350265Y871121D01*
X1350296Y871034D01*
G02X1350368Y870606I-1225J-426D01*
G02X1347774I-1297J0D01*
G02X1348829Y871881I1298J0D01*
G01X1348919Y871898D01*
X1349726Y873295D01*
X1349695Y873382D01*
G02X1349622Y873810I1225J429D01*
G37*
G36*
G01X1357022D02*
G02X1359618I1298J0D01*
G02X1358562Y872535I-1298J0D01*
G01X1358472Y872518D01*
X1357665Y871121D01*
X1357696Y871034D01*
G02X1357768Y870606I-1225J-426D01*
G02X1355174I-1297J0D01*
G02X1356229Y871881I1298J0D01*
G01X1356319Y871898D01*
X1357126Y873295D01*
X1357095Y873382D01*
G02X1357022Y873810I1225J429D01*
G37*
G36*
G01X1364422D02*
G02X1367018I1298J0D01*
G02X1365962Y872535I-1298J0D01*
G01X1365872Y872518D01*
X1365065Y871121D01*
X1365096Y871034D01*
G02X1365168Y870606I-1225J-426D01*
G02X1362574I-1297J0D01*
G02X1363629Y871881I1298J0D01*
G01X1363719Y871898D01*
X1364526Y873295D01*
X1364495Y873382D01*
G02X1364422Y873810I1225J429D01*
G37*
G36*
G01X1371822D02*
G02X1374418I1298J0D01*
G02X1373362Y872535I-1298J0D01*
G01X1373272Y872518D01*
X1372465Y871121D01*
X1372496Y871034D01*
G02X1372568Y870606I-1225J-426D01*
G02X1369974I-1297J0D01*
G02X1371029Y871881I1298J0D01*
G01X1371119Y871898D01*
X1371926Y873295D01*
X1371895Y873382D01*
G02X1371822Y873810I1225J429D01*
G37*
G36*
G01X1379222D02*
G02X1381818I1298J0D01*
G02X1380762Y872535I-1298J0D01*
G01X1380672Y872518D01*
X1379865Y871121D01*
X1379896Y871034D01*
G02X1379968Y870606I-1225J-426D01*
G02X1377374I-1297J0D01*
G02X1378429Y871881I1298J0D01*
G01X1378519Y871898D01*
X1379326Y873295D01*
X1379295Y873382D01*
G02X1379222Y873810I1225J429D01*
G37*
G36*
G01X1386622D02*
G02X1389218I1298J0D01*
G02X1389145Y873381I-1297J0D01*
G01X1389114Y873295D01*
X1389920Y871898D01*
X1390010Y871881D01*
G02X1391068Y870606I-239J-1275D01*
G02X1388474I-1297J0D01*
G02X1388545Y871032I1297J3D01*
G01X1388576Y871119D01*
X1387768Y872518D01*
X1387678Y872535D01*
G02X1386622Y873810I242J1275D01*
G37*
G36*
G01X1394022D02*
G02X1396618I1298J0D01*
G02X1396545Y873381I-1297J0D01*
G01X1396514Y873295D01*
X1397320Y871898D01*
X1397410Y871881D01*
G02X1398468Y870606I-239J-1275D01*
G02X1395874I-1297J0D01*
G02X1395945Y871032I1297J3D01*
G01X1395976Y871119D01*
X1395168Y872518D01*
X1395078Y872535D01*
G02X1394022Y873810I242J1275D01*
G37*
G36*
G01X1401422D02*
G02X1404018I1298J0D01*
G02X1403945Y873381I-1297J0D01*
G01X1403914Y873295D01*
X1404720Y871898D01*
X1404810Y871881D01*
G02X1405868Y870606I-239J-1275D01*
G02X1403274I-1297J0D01*
G02X1403345Y871032I1297J3D01*
G01X1403376Y871119D01*
X1402568Y872518D01*
X1402478Y872535D01*
G02X1401422Y873810I242J1275D01*
G37*
G36*
G01X1408824D02*
G02X1411418I1297J0D01*
G02X1411346Y873381I-1297J-3D01*
G01X1411315Y873295D01*
X1412121Y871898D01*
X1412211Y871881D01*
G02X1413268Y870606I-240J-1275D01*
G02X1410674I-1297J0D01*
G01Y870608D01*
G02X1410746Y871033I1297J-1D01*
G01X1410776Y871120D01*
X1409969Y872518D01*
X1409879Y872535D01*
G02X1408824Y873810I243J1275D01*
G37*
G36*
G01X1416222D02*
G02X1418818I1298J0D01*
G02X1418745Y873381I-1297J0D01*
G01X1418714Y873295D01*
X1419520Y871898D01*
X1419610Y871881D01*
G02X1420668Y870606I-239J-1275D01*
G02X1418074I-1297J0D01*
G02X1418145Y871032I1297J3D01*
G01X1418176Y871119D01*
X1417368Y872518D01*
X1417278Y872535D01*
G02X1416222Y873810I242J1275D01*
G37*
G36*
G01X1423624D02*
G02X1426218I1297J0D01*
G02X1426146Y873381I-1297J-3D01*
G01X1426115Y873295D01*
X1426921Y871898D01*
X1427011Y871881D01*
G02X1428068Y870606I-240J-1275D01*
G02X1425474I-1297J0D01*
G01Y870608D01*
G02X1425546Y871033I1297J-1D01*
G01X1425576Y871120D01*
X1424769Y872518D01*
X1424679Y872535D01*
G02X1423624Y873810I243J1275D01*
G37*
G36*
G01X1431022D02*
G02X1433618I1298J0D01*
G02X1433545Y873381I-1297J0D01*
G01X1433514Y873295D01*
X1434320Y871898D01*
X1434410Y871881D01*
G02X1435468Y870606I-239J-1275D01*
G02X1432874I-1297J0D01*
G02X1432945Y871032I1297J3D01*
G01X1432976Y871119D01*
X1432168Y872518D01*
X1432078Y872535D01*
G02X1431022Y873810I242J1275D01*
G37*
G36*
G01X1438422D02*
G02X1441018I1298J0D01*
G02X1440945Y873381I-1297J0D01*
G01X1440914Y873295D01*
X1441720Y871898D01*
X1441810Y871881D01*
G02X1442868Y870606I-239J-1275D01*
G02X1440274I-1297J0D01*
G02X1440345Y871032I1297J3D01*
G01X1440376Y871119D01*
X1439568Y872518D01*
X1439478Y872535D01*
G02X1438422Y873810I242J1275D01*
G37*
G36*
G01X1453222D02*
G02X1455818I1298J0D01*
G02X1455745Y873381I-1297J0D01*
G01X1455714Y873295D01*
X1456520Y871898D01*
X1456610Y871881D01*
G02X1457668Y870606I-239J-1275D01*
G02X1455074I-1297J0D01*
G02X1455145Y871032I1297J3D01*
G01X1455176Y871119D01*
X1454368Y872518D01*
X1454278Y872535D01*
G02X1453222Y873810I242J1275D01*
G37*
G36*
G01X1460622D02*
G02X1463218I1298J0D01*
G02X1463145Y873381I-1297J0D01*
G01X1463114Y873295D01*
X1463920Y871898D01*
X1464010Y871881D01*
G02X1465068Y870606I-239J-1275D01*
G02X1462474I-1297J0D01*
G02X1462545Y871032I1297J3D01*
G01X1462576Y871119D01*
X1461768Y872518D01*
X1461678Y872535D01*
G02X1460622Y873810I242J1275D01*
G37*
G36*
G01X1468022D02*
G02X1470618I1298J0D01*
G02X1470545Y873381I-1297J0D01*
G01X1470514Y873295D01*
X1471320Y871898D01*
X1471410Y871881D01*
G02X1472468Y870606I-239J-1275D01*
G02X1469874I-1297J0D01*
G02X1469945Y871032I1297J3D01*
G01X1469976Y871119D01*
X1469168Y872518D01*
X1469078Y872535D01*
G02X1468022Y873810I242J1275D01*
G37*
G36*
G01X1475422D02*
G02X1478018I1298J0D01*
G02X1477945Y873381I-1297J0D01*
G01X1477914Y873295D01*
X1478720Y871898D01*
X1478810Y871881D01*
G02X1479868Y870606I-239J-1275D01*
G02X1477274I-1297J0D01*
G02X1477345Y871032I1297J3D01*
G01X1477376Y871119D01*
X1476568Y872518D01*
X1476478Y872535D01*
G02X1475422Y873810I242J1275D01*
G37*
G36*
G01X1482822D02*
G02X1485418I1298J0D01*
G02X1485345Y873381I-1297J0D01*
G01X1485314Y873295D01*
X1486120Y871898D01*
X1486210Y871881D01*
G02X1487268Y870606I-239J-1275D01*
G02X1484674I-1297J0D01*
G02X1484745Y871032I1297J3D01*
G01X1484776Y871119D01*
X1483968Y872518D01*
X1483878Y872535D01*
G02X1482822Y873810I242J1275D01*
G37*
G36*
G01X1490222D02*
G02X1492818I1298J0D01*
G02X1492745Y873381I-1297J0D01*
G01X1492714Y873295D01*
X1493520Y871898D01*
X1493610Y871881D01*
G02X1494668Y870606I-239J-1275D01*
G02X1492074I-1297J0D01*
G02X1492145Y871032I1297J3D01*
G01X1492176Y871119D01*
X1491368Y872518D01*
X1491278Y872535D01*
G02X1490222Y873810I242J1275D01*
G37*
G36*
G01X367932Y883423D02*
G02X370526I1297J0D01*
G02X370454Y882994I-1297J-3D01*
G01X370423Y882908D01*
X371229Y881511D01*
X371319Y881494D01*
G02X372376Y880219I-240J-1275D01*
G02X369780I-1298J0D01*
G02X369853Y880647I1298J-1D01*
G01X369883Y880734D01*
X369077Y882131D01*
X368987Y882148D01*
G02X367932Y883423I243J1275D01*
G37*
G36*
G01X375332D02*
G02X377926I1297J0D01*
G02X377854Y882994I-1297J-3D01*
G01X377823Y882908D01*
X378629Y881511D01*
X378719Y881494D01*
G02X379776Y880219I-240J-1275D01*
G02X377180I-1298J0D01*
G02X377253Y880647I1298J-1D01*
G01X377283Y880734D01*
X376477Y882131D01*
X376387Y882148D01*
G02X375332Y883423I243J1275D01*
G37*
G36*
G01X382732D02*
G02X385326I1297J0D01*
G02X385254Y882994I-1297J-3D01*
G01X385223Y882908D01*
X386029Y881511D01*
X386119Y881494D01*
G02X387176Y880219I-240J-1275D01*
G02X384580I-1298J0D01*
G02X384653Y880647I1298J-1D01*
G01X384683Y880734D01*
X383877Y882131D01*
X383787Y882148D01*
G02X382732Y883423I243J1275D01*
G37*
G36*
G01X390132D02*
G02X392726I1297J0D01*
G02X392654Y882994I-1297J-3D01*
G01X392623Y882908D01*
X393429Y881511D01*
X393519Y881494D01*
G02X394576Y880219I-240J-1275D01*
G02X391980I-1298J0D01*
G02X392053Y880647I1298J-1D01*
G01X392083Y880734D01*
X391277Y882131D01*
X391187Y882148D01*
G02X390132Y883423I243J1275D01*
G37*
G36*
G01X397532D02*
G02X400126I1297J0D01*
G02X400054Y882994I-1297J-3D01*
G01X400023Y882908D01*
X400829Y881511D01*
X400919Y881494D01*
G02X401976Y880219I-240J-1275D01*
G02X399380I-1298J0D01*
G02X399453Y880647I1298J-1D01*
G01X399483Y880734D01*
X398677Y882131D01*
X398587Y882148D01*
G02X397532Y883423I243J1275D01*
G37*
G36*
G01X404932D02*
G02X407526I1297J0D01*
G02X407454Y882994I-1297J-3D01*
G01X407423Y882908D01*
X408229Y881511D01*
X408319Y881494D01*
G02X409376Y880219I-240J-1275D01*
G02X406780I-1298J0D01*
G02X406853Y880647I1298J-1D01*
G01X406883Y880734D01*
X406077Y882131D01*
X405987Y882148D01*
G02X404932Y883423I243J1275D01*
G37*
G36*
G01X412332D02*
G02X414926I1297J0D01*
G02X414854Y882994I-1297J-3D01*
G01X414823Y882908D01*
X415629Y881511D01*
X415719Y881494D01*
G02X416776Y880219I-240J-1275D01*
G02X414180I-1298J0D01*
G02X414253Y880647I1298J-1D01*
G01X414283Y880734D01*
X413477Y882131D01*
X413387Y882148D01*
G02X412332Y883423I243J1275D01*
G37*
G36*
G01X419732D02*
G02X422326I1297J0D01*
G02X422254Y882994I-1297J-3D01*
G01X422223Y882908D01*
X423029Y881511D01*
X423119Y881494D01*
G02X424176Y880219I-240J-1275D01*
G02X421580I-1298J0D01*
G02X421653Y880647I1298J-1D01*
G01X421683Y880734D01*
X420877Y882131D01*
X420787Y882148D01*
G02X419732Y883423I243J1275D01*
G37*
G36*
G01X427132D02*
G02X429726I1297J0D01*
G02X429654Y882994I-1297J-3D01*
G01X429623Y882908D01*
X430429Y881511D01*
X430519Y881494D01*
G02X431576Y880219I-240J-1275D01*
G02X428980I-1298J0D01*
G02X429053Y880647I1298J-1D01*
G01X429083Y880734D01*
X428277Y882131D01*
X428187Y882148D01*
G02X427132Y883423I243J1275D01*
G37*
G36*
G01X434532D02*
G02X437126I1297J0D01*
G02X437054Y882994I-1297J-3D01*
G01X437023Y882908D01*
X437829Y881511D01*
X437919Y881494D01*
G02X438976Y880219I-240J-1275D01*
G02X436380I-1298J0D01*
G02X436453Y880647I1298J-1D01*
G01X436483Y880734D01*
X435677Y882131D01*
X435587Y882148D01*
G02X434532Y883423I243J1275D01*
G37*
G36*
G01X441932D02*
G02X444526I1297J0D01*
G02X444454Y882994I-1297J-3D01*
G01X444423Y882908D01*
X445229Y881511D01*
X445319Y881494D01*
G02X446376Y880219I-240J-1275D01*
G02X443780I-1298J0D01*
G02X443853Y880647I1298J-1D01*
G01X443883Y880734D01*
X443077Y882131D01*
X442987Y882148D01*
G02X441932Y883423I243J1275D01*
G37*
G36*
G01X449332D02*
G02X451926I1297J0D01*
G02X451854Y882994I-1297J-3D01*
G01X451823Y882908D01*
X452629Y881511D01*
X452719Y881494D01*
G02X453776Y880219I-240J-1275D01*
G02X451182I-1297J0D01*
G01Y880221D01*
G02X451254Y880646I1297J-1D01*
G01X451284Y880733D01*
X450477Y882131D01*
X450387Y882148D01*
G02X449332Y883423I243J1275D01*
G37*
G36*
G01X456732D02*
G02X459326I1297J0D01*
G02X459254Y882994I-1297J-3D01*
G01X459223Y882908D01*
X460029Y881511D01*
X460119Y881494D01*
G02X461176Y880219I-240J-1275D01*
G02X458580I-1298J0D01*
G02X458653Y880647I1298J-1D01*
G01X458683Y880734D01*
X457877Y882131D01*
X457787Y882148D01*
G02X456732Y883423I243J1275D01*
G37*
G36*
G01X464132D02*
G02X466726I1297J0D01*
G02X466654Y882994I-1297J-3D01*
G01X466623Y882908D01*
X467429Y881511D01*
X467519Y881494D01*
G02X468576Y880219I-240J-1275D01*
G02X465980I-1298J0D01*
G02X466053Y880647I1298J-1D01*
G01X466083Y880734D01*
X465277Y882131D01*
X465187Y882148D01*
G02X464132Y883423I243J1275D01*
G37*
G36*
G01X471532D02*
G02X474126I1297J0D01*
G02X474054Y882994I-1297J-3D01*
G01X474023Y882908D01*
X474829Y881511D01*
X474919Y881494D01*
G02X475976Y880219I-240J-1275D01*
G02X473380I-1298J0D01*
G02X473453Y880647I1298J-1D01*
G01X473483Y880734D01*
X472677Y882131D01*
X472587Y882148D01*
G02X471532Y883423I243J1275D01*
G37*
G36*
G01X478932D02*
G02X481526I1297J0D01*
G02X481454Y882994I-1297J-3D01*
G01X481423Y882908D01*
X482229Y881511D01*
X482319Y881494D01*
G02X483376Y880219I-240J-1275D01*
G02X480780I-1298J0D01*
G02X480853Y880647I1298J-1D01*
G01X480883Y880734D01*
X480077Y882131D01*
X479987Y882148D01*
G02X478932Y883423I243J1275D01*
G37*
G36*
G01X486332D02*
G02X488926I1297J0D01*
G02X488854Y882994I-1297J-3D01*
G01X488823Y882908D01*
X489629Y881511D01*
X489719Y881494D01*
G02X490776Y880219I-240J-1275D01*
G02X488180I-1298J0D01*
G02X488253Y880647I1298J-1D01*
G01X488283Y880734D01*
X487477Y882131D01*
X487387Y882148D01*
G02X486332Y883423I243J1275D01*
G37*
G36*
G01X493732D02*
G02X496326I1297J0D01*
G02X496254Y882994I-1297J-3D01*
G01X496223Y882908D01*
X497029Y881511D01*
X497119Y881494D01*
G02X498176Y880219I-240J-1275D01*
G02X495580I-1298J0D01*
G02X495653Y880647I1298J-1D01*
G01X495683Y880734D01*
X494877Y882131D01*
X494787Y882148D01*
G02X493732Y883423I243J1275D01*
G37*
G36*
G01X501132D02*
G02X503726I1297J0D01*
G02X503654Y882994I-1297J-3D01*
G01X503623Y882908D01*
X504429Y881511D01*
X504519Y881494D01*
G02X505576Y880219I-240J-1275D01*
G02X502980I-1298J0D01*
G02X503053Y880647I1298J-1D01*
G01X503083Y880734D01*
X502277Y882131D01*
X502187Y882148D01*
G02X501132Y883423I243J1275D01*
G37*
G36*
G01X508532D02*
G02X511126I1297J0D01*
G02X511054Y882994I-1297J-3D01*
G01X511023Y882908D01*
X511829Y881511D01*
X511919Y881494D01*
G02X512976Y880219I-240J-1275D01*
G02X510380I-1298J0D01*
G02X510453Y880647I1298J-1D01*
G01X510483Y880734D01*
X509677Y882131D01*
X509587Y882148D01*
G02X508532Y883423I243J1275D01*
G37*
G36*
G01X1344074D02*
G02X1346668I1297J0D01*
G02X1346596Y882994I-1297J-3D01*
G01X1346565Y882908D01*
X1347371Y881511D01*
X1347461Y881494D01*
G02X1348518Y880219I-240J-1275D01*
G02X1345922I-1298J0D01*
G02X1345995Y880647I1298J-1D01*
G01X1346025Y880734D01*
X1345219Y882131D01*
X1345129Y882148D01*
G02X1344074Y883423I243J1275D01*
G37*
G36*
G01X1351474D02*
G02X1354068I1297J0D01*
G02X1353996Y882994I-1297J-3D01*
G01X1353965Y882908D01*
X1354771Y881511D01*
X1354861Y881494D01*
G02X1355918Y880219I-240J-1275D01*
G02X1353322I-1298J0D01*
G02X1353395Y880647I1298J-1D01*
G01X1353425Y880734D01*
X1352619Y882131D01*
X1352529Y882148D01*
G02X1351474Y883423I243J1275D01*
G37*
G36*
G01X1358874D02*
G02X1361468I1297J0D01*
G02X1361396Y882994I-1297J-3D01*
G01X1361365Y882908D01*
X1362171Y881511D01*
X1362261Y881494D01*
G02X1363318Y880219I-240J-1275D01*
G02X1360722I-1298J0D01*
G02X1360795Y880647I1298J-1D01*
G01X1360825Y880734D01*
X1360019Y882131D01*
X1359929Y882148D01*
G02X1358874Y883423I243J1275D01*
G37*
G36*
G01X1366274D02*
G02X1368868I1297J0D01*
G02X1368796Y882994I-1297J-3D01*
G01X1368765Y882908D01*
X1369571Y881511D01*
X1369661Y881494D01*
G02X1370718Y880219I-240J-1275D01*
G02X1368122I-1298J0D01*
G02X1368195Y880647I1298J-1D01*
G01X1368225Y880734D01*
X1367419Y882131D01*
X1367329Y882148D01*
G02X1366274Y883423I243J1275D01*
G37*
G36*
G01X1373674D02*
G02X1376268I1297J0D01*
G02X1376196Y882994I-1297J-3D01*
G01X1376165Y882908D01*
X1376971Y881511D01*
X1377061Y881494D01*
G02X1378118Y880219I-240J-1275D01*
G02X1375522I-1298J0D01*
G02X1375595Y880647I1298J-1D01*
G01X1375625Y880734D01*
X1374819Y882131D01*
X1374729Y882148D01*
G02X1373674Y883423I243J1275D01*
G37*
G36*
G01X1381074D02*
G02X1383668I1297J0D01*
G02X1383596Y882994I-1297J-3D01*
G01X1383565Y882908D01*
X1384371Y881511D01*
X1384461Y881494D01*
G02X1385518Y880219I-240J-1275D01*
G02X1382922I-1298J0D01*
G02X1382995Y880647I1298J-1D01*
G01X1383025Y880734D01*
X1382219Y882131D01*
X1382129Y882148D01*
G02X1381074Y883423I243J1275D01*
G37*
G36*
G01X1388474D02*
G02X1391068I1297J0D01*
G02X1390996Y882994I-1297J-3D01*
G01X1390965Y882908D01*
X1391771Y881511D01*
X1391861Y881494D01*
G02X1392918Y880219I-240J-1275D01*
G02X1390322I-1298J0D01*
G02X1390395Y880647I1298J-1D01*
G01X1390425Y880734D01*
X1389619Y882131D01*
X1389529Y882148D01*
G02X1388474Y883423I243J1275D01*
G37*
G36*
G01X1395874D02*
G02X1398468I1297J0D01*
G02X1398396Y882994I-1297J-3D01*
G01X1398365Y882908D01*
X1399171Y881511D01*
X1399261Y881494D01*
G02X1400318Y880219I-240J-1275D01*
G02X1397722I-1298J0D01*
G02X1397795Y880647I1298J-1D01*
G01X1397825Y880734D01*
X1397019Y882131D01*
X1396929Y882148D01*
G02X1395874Y883423I243J1275D01*
G37*
G36*
G01X1403274D02*
G02X1405868I1297J0D01*
G02X1405796Y882994I-1297J-3D01*
G01X1405765Y882908D01*
X1406571Y881511D01*
X1406661Y881494D01*
G02X1407718Y880219I-240J-1275D01*
G02X1405122I-1298J0D01*
G02X1405195Y880647I1298J-1D01*
G01X1405225Y880734D01*
X1404419Y882131D01*
X1404329Y882148D01*
G02X1403274Y883423I243J1275D01*
G37*
G36*
G01X1410674D02*
G02X1413268I1297J0D01*
G02X1413196Y882994I-1297J-3D01*
G01X1413165Y882908D01*
X1413971Y881511D01*
X1414061Y881494D01*
G02X1415118Y880219I-240J-1275D01*
G02X1412522I-1298J0D01*
G02X1412595Y880647I1298J-1D01*
G01X1412625Y880734D01*
X1411819Y882131D01*
X1411729Y882148D01*
G02X1410674Y883423I243J1275D01*
G37*
G36*
G01X1418074D02*
G02X1420668I1297J0D01*
G02X1420596Y882994I-1297J-3D01*
G01X1420565Y882908D01*
X1421371Y881511D01*
X1421461Y881494D01*
G02X1422518Y880219I-240J-1275D01*
G02X1419922I-1298J0D01*
G02X1419995Y880647I1298J-1D01*
G01X1420025Y880734D01*
X1419219Y882131D01*
X1419129Y882148D01*
G02X1418074Y883423I243J1275D01*
G37*
G36*
G01X1425474D02*
G02X1428068I1297J0D01*
G02X1427996Y882994I-1297J-3D01*
G01X1427965Y882908D01*
X1428771Y881511D01*
X1428861Y881494D01*
G02X1429918Y880219I-240J-1275D01*
G02X1427324I-1297J0D01*
G01Y880221D01*
G02X1427396Y880646I1297J-1D01*
G01X1427426Y880733D01*
X1426619Y882131D01*
X1426529Y882148D01*
G02X1425474Y883423I243J1275D01*
G37*
G36*
G01X1432874D02*
G02X1435468I1297J0D01*
G02X1435396Y882994I-1297J-3D01*
G01X1435365Y882908D01*
X1436171Y881511D01*
X1436261Y881494D01*
G02X1437318Y880219I-240J-1275D01*
G02X1434722I-1298J0D01*
G02X1434795Y880647I1298J-1D01*
G01X1434825Y880734D01*
X1434019Y882131D01*
X1433929Y882148D01*
G02X1432874Y883423I243J1275D01*
G37*
G36*
G01X1440274D02*
G02X1442868I1297J0D01*
G02X1442796Y882994I-1297J-3D01*
G01X1442765Y882908D01*
X1443571Y881511D01*
X1443661Y881494D01*
G02X1444718Y880219I-240J-1275D01*
G02X1442122I-1298J0D01*
G02X1442195Y880647I1298J-1D01*
G01X1442225Y880734D01*
X1441419Y882131D01*
X1441329Y882148D01*
G02X1440274Y883423I243J1275D01*
G37*
G36*
G01X1447674D02*
G02X1450268I1297J0D01*
G02X1450196Y882994I-1297J-3D01*
G01X1450165Y882908D01*
X1450971Y881511D01*
X1451061Y881494D01*
G02X1452118Y880219I-240J-1275D01*
G02X1449522I-1298J0D01*
G02X1449595Y880647I1298J-1D01*
G01X1449625Y880734D01*
X1448819Y882131D01*
X1448729Y882148D01*
G02X1447674Y883423I243J1275D01*
G37*
G36*
G01X1455074D02*
G02X1457668I1297J0D01*
G02X1457596Y882994I-1297J-3D01*
G01X1457565Y882908D01*
X1458371Y881511D01*
X1458461Y881494D01*
G02X1459518Y880219I-240J-1275D01*
G02X1456922I-1298J0D01*
G02X1456995Y880647I1298J-1D01*
G01X1457025Y880734D01*
X1456219Y882131D01*
X1456129Y882148D01*
G02X1455074Y883423I243J1275D01*
G37*
G36*
G01X1462474D02*
G02X1465068I1297J0D01*
G02X1464996Y882994I-1297J-3D01*
G01X1464965Y882908D01*
X1465771Y881511D01*
X1465861Y881494D01*
G02X1466918Y880219I-240J-1275D01*
G02X1464322I-1298J0D01*
G02X1464395Y880647I1298J-1D01*
G01X1464425Y880734D01*
X1463619Y882131D01*
X1463529Y882148D01*
G02X1462474Y883423I243J1275D01*
G37*
G36*
G01X1469874D02*
G02X1472468I1297J0D01*
G02X1472396Y882994I-1297J-3D01*
G01X1472365Y882908D01*
X1473171Y881511D01*
X1473261Y881494D01*
G02X1474318Y880219I-240J-1275D01*
G02X1471722I-1298J0D01*
G02X1471795Y880647I1298J-1D01*
G01X1471825Y880734D01*
X1471019Y882131D01*
X1470929Y882148D01*
G02X1469874Y883423I243J1275D01*
G37*
G36*
G01X1477274D02*
G02X1479868I1297J0D01*
G02X1479796Y882994I-1297J-3D01*
G01X1479765Y882908D01*
X1480571Y881511D01*
X1480661Y881494D01*
G02X1481718Y880219I-240J-1275D01*
G02X1479122I-1298J0D01*
G02X1479195Y880647I1298J-1D01*
G01X1479225Y880734D01*
X1478419Y882131D01*
X1478329Y882148D01*
G02X1477274Y883423I243J1275D01*
G37*
G36*
G01X1484674D02*
G02X1487268I1297J0D01*
G02X1487196Y882994I-1297J-3D01*
G01X1487165Y882908D01*
X1487971Y881511D01*
X1488061Y881494D01*
G02X1489118Y880219I-240J-1275D01*
G02X1486522I-1298J0D01*
G02X1486595Y880647I1298J-1D01*
G01X1486625Y880734D01*
X1485819Y882131D01*
X1485729Y882148D01*
G02X1484674Y883423I243J1275D01*
G37*
G36*
G01X373480Y886627D02*
G02X376076I1298J0D01*
G02X375020Y885352I-1298J0D01*
G01X374930Y885335D01*
X374123Y883938D01*
X374154Y883851D01*
G02X374226Y883423I-1225J-426D01*
G02X371632I-1297J0D01*
G02X372687Y884698I1298J0D01*
G01X372777Y884715D01*
X373584Y886112D01*
X373553Y886199D01*
G02X373480Y886627I1225J429D01*
G37*
G36*
G01X380880D02*
G02X383476I1298J0D01*
G02X382420Y885352I-1298J0D01*
G01X382330Y885335D01*
X381523Y883938D01*
X381554Y883851D01*
G02X381626Y883423I-1225J-426D01*
G02X379032I-1297J0D01*
G02X380087Y884698I1298J0D01*
G01X380177Y884715D01*
X380984Y886112D01*
X380953Y886199D01*
G02X380880Y886627I1225J429D01*
G37*
G36*
G01X388280D02*
G02X390876I1298J0D01*
G02X389820Y885352I-1298J0D01*
G01X389730Y885335D01*
X388923Y883938D01*
X388954Y883851D01*
G02X389026Y883423I-1225J-426D01*
G02X386432I-1297J0D01*
G02X387487Y884698I1298J0D01*
G01X387577Y884715D01*
X388384Y886112D01*
X388353Y886199D01*
G02X388280Y886627I1225J429D01*
G37*
G36*
G01X395680D02*
G02X398276I1298J0D01*
G02X397220Y885352I-1298J0D01*
G01X397130Y885335D01*
X396323Y883938D01*
X396354Y883851D01*
G02X396426Y883423I-1225J-426D01*
G02X393832I-1297J0D01*
G02X394887Y884698I1298J0D01*
G01X394977Y884715D01*
X395784Y886112D01*
X395753Y886199D01*
G02X395680Y886627I1225J429D01*
G37*
G36*
G01X403080D02*
G02X405676I1298J0D01*
G02X404620Y885352I-1298J0D01*
G01X404530Y885335D01*
X403723Y883938D01*
X403754Y883851D01*
G02X403826Y883423I-1225J-426D01*
G02X401232I-1297J0D01*
G02X402287Y884698I1298J0D01*
G01X402377Y884715D01*
X403184Y886112D01*
X403153Y886199D01*
G02X403080Y886627I1225J429D01*
G37*
G36*
G01X410480D02*
G02X413076I1298J0D01*
G02X412020Y885352I-1298J0D01*
G01X411930Y885335D01*
X411123Y883938D01*
X411154Y883851D01*
G02X411226Y883423I-1225J-426D01*
G02X408632I-1297J0D01*
G02X409687Y884698I1298J0D01*
G01X409777Y884715D01*
X410584Y886112D01*
X410553Y886199D01*
G02X410480Y886627I1225J429D01*
G37*
G36*
G01X417880D02*
G02X420476I1298J0D01*
G02X419420Y885352I-1298J0D01*
G01X419330Y885335D01*
X418523Y883938D01*
X418554Y883851D01*
G02X418626Y883423I-1225J-426D01*
G02X416032I-1297J0D01*
G02X417087Y884698I1298J0D01*
G01X417177Y884715D01*
X417984Y886112D01*
X417953Y886199D01*
G02X417880Y886627I1225J429D01*
G37*
G36*
G01X425280D02*
G02X427876I1298J0D01*
G02X426820Y885352I-1298J0D01*
G01X426730Y885335D01*
X425923Y883938D01*
X425954Y883851D01*
G02X426026Y883423I-1225J-426D01*
G02X423432I-1297J0D01*
G02X424487Y884698I1298J0D01*
G01X424577Y884715D01*
X425384Y886112D01*
X425353Y886199D01*
G02X425280Y886627I1225J429D01*
G37*
G36*
G01X432680D02*
G02X435276I1298J0D01*
G02X434220Y885352I-1298J0D01*
G01X434130Y885335D01*
X433323Y883938D01*
X433354Y883851D01*
G02X433426Y883423I-1225J-426D01*
G02X430832I-1297J0D01*
G02X431887Y884698I1298J0D01*
G01X431977Y884715D01*
X432784Y886112D01*
X432753Y886199D01*
G02X432680Y886627I1225J429D01*
G37*
G36*
G01X440080D02*
G02X442676I1298J0D01*
G02X441620Y885352I-1298J0D01*
G01X441530Y885335D01*
X440723Y883938D01*
X440754Y883851D01*
G02X440826Y883423I-1225J-426D01*
G02X438232I-1297J0D01*
G02X439287Y884698I1298J0D01*
G01X439377Y884715D01*
X440184Y886112D01*
X440153Y886199D01*
G02X440080Y886627I1225J429D01*
G37*
G36*
G01X447480D02*
G02X450076I1298J0D01*
G02X449020Y885352I-1298J0D01*
G01X448930Y885335D01*
X448123Y883938D01*
X448154Y883851D01*
G02X448226Y883423I-1225J-426D01*
G02X445632I-1297J0D01*
G02X446687Y884698I1298J0D01*
G01X446777Y884715D01*
X447584Y886112D01*
X447553Y886199D01*
G02X447480Y886627I1225J429D01*
G37*
G36*
G01X454880D02*
G02X457476I1298J0D01*
G02X456420Y885352I-1298J0D01*
G01X456330Y885335D01*
X455523Y883938D01*
X455554Y883851D01*
G02X455626Y883423I-1225J-426D01*
G02X453032I-1297J0D01*
G02X454087Y884698I1298J0D01*
G01X454177Y884715D01*
X454984Y886112D01*
X454953Y886199D01*
G02X454880Y886627I1225J429D01*
G37*
G36*
G01X462280D02*
G02X464876I1298J0D01*
G02X463820Y885352I-1298J0D01*
G01X463730Y885335D01*
X462923Y883938D01*
X462954Y883851D01*
G02X463026Y883423I-1225J-426D01*
G02X460432I-1297J0D01*
G02X461487Y884698I1298J0D01*
G01X461577Y884715D01*
X462384Y886112D01*
X462353Y886199D01*
G02X462280Y886627I1225J429D01*
G37*
G36*
G01X469680D02*
G02X472276I1298J0D01*
G02X471220Y885352I-1298J0D01*
G01X471130Y885335D01*
X470323Y883938D01*
X470354Y883851D01*
G02X470426Y883423I-1225J-426D01*
G02X467832I-1297J0D01*
G02X468887Y884698I1298J0D01*
G01X468977Y884715D01*
X469784Y886112D01*
X469753Y886199D01*
G02X469680Y886627I1225J429D01*
G37*
G36*
G01X477080D02*
G02X479676I1298J0D01*
G02X478620Y885352I-1298J0D01*
G01X478530Y885335D01*
X477723Y883938D01*
X477754Y883851D01*
G02X477826Y883423I-1225J-426D01*
G02X475232I-1297J0D01*
G02X476287Y884698I1298J0D01*
G01X476377Y884715D01*
X477184Y886112D01*
X477153Y886199D01*
G02X477080Y886627I1225J429D01*
G37*
G36*
G01X484480D02*
G02X487076I1298J0D01*
G02X486020Y885352I-1298J0D01*
G01X485930Y885335D01*
X485123Y883938D01*
X485154Y883851D01*
G02X485226Y883423I-1225J-426D01*
G02X482632I-1297J0D01*
G02X483687Y884698I1298J0D01*
G01X483777Y884715D01*
X484584Y886112D01*
X484553Y886199D01*
G02X484480Y886627I1225J429D01*
G37*
G36*
G01X491880D02*
G02X494476I1298J0D01*
G02X493420Y885352I-1298J0D01*
G01X493330Y885335D01*
X492523Y883938D01*
X492554Y883851D01*
G02X492626Y883423I-1225J-426D01*
G02X490032I-1297J0D01*
G02X491087Y884698I1298J0D01*
G01X491177Y884715D01*
X491984Y886112D01*
X491953Y886199D01*
G02X491880Y886627I1225J429D01*
G37*
G36*
G01X499280D02*
G02X501876I1298J0D01*
G02X500820Y885352I-1298J0D01*
G01X500730Y885335D01*
X499923Y883938D01*
X499954Y883851D01*
G02X500026Y883423I-1225J-426D01*
G02X497432I-1297J0D01*
G02X498487Y884698I1298J0D01*
G01X498577Y884715D01*
X499384Y886112D01*
X499353Y886199D01*
G02X499280Y886627I1225J429D01*
G37*
G36*
G01X506680D02*
G02X509276I1298J0D01*
G02X508220Y885352I-1298J0D01*
G01X508130Y885335D01*
X507323Y883938D01*
X507354Y883851D01*
G02X507426Y883423I-1225J-426D01*
G02X504832I-1297J0D01*
G02X505887Y884698I1298J0D01*
G01X505977Y884715D01*
X506784Y886112D01*
X506753Y886199D01*
G02X506680Y886627I1225J429D01*
G37*
G36*
G01X514080D02*
G02X516676I1298J0D01*
G02X515620Y885352I-1298J0D01*
G01X515530Y885335D01*
X514723Y883938D01*
X514754Y883851D01*
G02X514826Y883423I-1225J-426D01*
G02X512232I-1297J0D01*
G02X513287Y884698I1298J0D01*
G01X513377Y884715D01*
X514184Y886112D01*
X514153Y886199D01*
G02X514080Y886627I1225J429D01*
G37*
G36*
G01X521480D02*
G02X524076I1298J0D01*
G02X523020Y885352I-1298J0D01*
G01X522930Y885335D01*
X522123Y883938D01*
X522154Y883851D01*
G02X522226Y883423I-1225J-426D01*
G02X519632I-1297J0D01*
G02X520687Y884698I1298J0D01*
G01X520777Y884715D01*
X521584Y886112D01*
X521553Y886199D01*
G02X521480Y886627I1225J429D01*
G37*
G36*
G01X1349622D02*
G02X1352218I1298J0D01*
G02X1351162Y885352I-1298J0D01*
G01X1351072Y885335D01*
X1350265Y883938D01*
X1350296Y883851D01*
G02X1350368Y883423I-1225J-426D01*
G02X1347774I-1297J0D01*
G02X1348829Y884698I1298J0D01*
G01X1348919Y884715D01*
X1349726Y886112D01*
X1349695Y886199D01*
G02X1349622Y886627I1225J429D01*
G37*
G36*
G01X1357022D02*
G02X1359618I1298J0D01*
G02X1358562Y885352I-1298J0D01*
G01X1358472Y885335D01*
X1357665Y883938D01*
X1357696Y883851D01*
G02X1357768Y883423I-1225J-426D01*
G02X1355174I-1297J0D01*
G02X1356229Y884698I1298J0D01*
G01X1356319Y884715D01*
X1357126Y886112D01*
X1357095Y886199D01*
G02X1357022Y886627I1225J429D01*
G37*
G36*
G01X1364422D02*
G02X1367018I1298J0D01*
G02X1365962Y885352I-1298J0D01*
G01X1365872Y885335D01*
X1365065Y883938D01*
X1365096Y883851D01*
G02X1365168Y883423I-1225J-426D01*
G02X1362574I-1297J0D01*
G02X1363629Y884698I1298J0D01*
G01X1363719Y884715D01*
X1364526Y886112D01*
X1364495Y886199D01*
G02X1364422Y886627I1225J429D01*
G37*
G36*
G01X1371822D02*
G02X1374418I1298J0D01*
G02X1373362Y885352I-1298J0D01*
G01X1373272Y885335D01*
X1372465Y883938D01*
X1372496Y883851D01*
G02X1372568Y883423I-1225J-426D01*
G02X1369974I-1297J0D01*
G02X1371029Y884698I1298J0D01*
G01X1371119Y884715D01*
X1371926Y886112D01*
X1371895Y886199D01*
G02X1371822Y886627I1225J429D01*
G37*
G36*
G01X1379222D02*
G02X1381818I1298J0D01*
G02X1380762Y885352I-1298J0D01*
G01X1380672Y885335D01*
X1379865Y883938D01*
X1379896Y883851D01*
G02X1379968Y883423I-1225J-426D01*
G02X1377374I-1297J0D01*
G02X1378429Y884698I1298J0D01*
G01X1378519Y884715D01*
X1379326Y886112D01*
X1379295Y886199D01*
G02X1379222Y886627I1225J429D01*
G37*
G36*
G01X1386622D02*
G02X1389218I1298J0D01*
G02X1388162Y885352I-1298J0D01*
G01X1388072Y885335D01*
X1387265Y883938D01*
X1387296Y883851D01*
G02X1387368Y883423I-1225J-426D01*
G02X1384774I-1297J0D01*
G02X1385829Y884698I1298J0D01*
G01X1385919Y884715D01*
X1386726Y886112D01*
X1386695Y886199D01*
G02X1386622Y886627I1225J429D01*
G37*
G36*
G01X1394022D02*
G02X1396618I1298J0D01*
G02X1395562Y885352I-1298J0D01*
G01X1395472Y885335D01*
X1394665Y883938D01*
X1394696Y883851D01*
G02X1394768Y883423I-1225J-426D01*
G02X1392174I-1297J0D01*
G02X1393229Y884698I1298J0D01*
G01X1393319Y884715D01*
X1394126Y886112D01*
X1394095Y886199D01*
G02X1394022Y886627I1225J429D01*
G37*
G36*
G01X1401422D02*
G02X1404018I1298J0D01*
G02X1402962Y885352I-1298J0D01*
G01X1402872Y885335D01*
X1402065Y883938D01*
X1402096Y883851D01*
G02X1402168Y883423I-1225J-426D01*
G02X1399574I-1297J0D01*
G02X1400629Y884698I1298J0D01*
G01X1400719Y884715D01*
X1401526Y886112D01*
X1401495Y886199D01*
G02X1401422Y886627I1225J429D01*
G37*
G36*
G01X1408822D02*
G02X1411418I1298J0D01*
G02X1410362Y885352I-1298J0D01*
G01X1410272Y885335D01*
X1409465Y883938D01*
X1409496Y883851D01*
G02X1409568Y883423I-1225J-426D01*
G02X1406974I-1297J0D01*
G02X1408029Y884698I1298J0D01*
G01X1408119Y884715D01*
X1408926Y886112D01*
X1408895Y886199D01*
G02X1408822Y886627I1225J429D01*
G37*
G36*
G01X1416222D02*
G02X1418818I1298J0D01*
G02X1417762Y885352I-1298J0D01*
G01X1417672Y885335D01*
X1416865Y883938D01*
X1416896Y883851D01*
G02X1416968Y883423I-1225J-426D01*
G02X1414374I-1297J0D01*
G02X1415429Y884698I1298J0D01*
G01X1415519Y884715D01*
X1416326Y886112D01*
X1416295Y886199D01*
G02X1416222Y886627I1225J429D01*
G37*
G36*
G01X1423622D02*
G02X1426218I1298J0D01*
G02X1425162Y885352I-1298J0D01*
G01X1425072Y885335D01*
X1424265Y883938D01*
X1424296Y883851D01*
G02X1424368Y883423I-1225J-426D01*
G02X1421774I-1297J0D01*
G02X1422829Y884698I1298J0D01*
G01X1422919Y884715D01*
X1423726Y886112D01*
X1423695Y886199D01*
G02X1423622Y886627I1225J429D01*
G37*
G36*
G01X1431022D02*
G02X1433618I1298J0D01*
G02X1432562Y885352I-1298J0D01*
G01X1432472Y885335D01*
X1431665Y883938D01*
X1431696Y883851D01*
G02X1431768Y883423I-1225J-426D01*
G02X1429174I-1297J0D01*
G02X1430229Y884698I1298J0D01*
G01X1430319Y884715D01*
X1431126Y886112D01*
X1431095Y886199D01*
G02X1431022Y886627I1225J429D01*
G37*
G36*
G01X1438422D02*
G02X1441018I1298J0D01*
G02X1439962Y885352I-1298J0D01*
G01X1439872Y885335D01*
X1439065Y883938D01*
X1439096Y883851D01*
G02X1439168Y883423I-1225J-426D01*
G02X1436574I-1297J0D01*
G02X1437629Y884698I1298J0D01*
G01X1437719Y884715D01*
X1438526Y886112D01*
X1438495Y886199D01*
G02X1438422Y886627I1225J429D01*
G37*
G36*
G01X1445822D02*
G02X1448418I1298J0D01*
G02X1447362Y885352I-1298J0D01*
G01X1447272Y885335D01*
X1446465Y883938D01*
X1446496Y883851D01*
G02X1446568Y883423I-1225J-426D01*
G02X1443974I-1297J0D01*
G02X1445029Y884698I1298J0D01*
G01X1445119Y884715D01*
X1445926Y886112D01*
X1445895Y886199D01*
G02X1445822Y886627I1225J429D01*
G37*
G36*
G01X1453222D02*
G02X1455818I1298J0D01*
G02X1454762Y885352I-1298J0D01*
G01X1454672Y885335D01*
X1453865Y883938D01*
X1453896Y883851D01*
G02X1453968Y883423I-1225J-426D01*
G02X1451374I-1297J0D01*
G02X1452429Y884698I1298J0D01*
G01X1452519Y884715D01*
X1453326Y886112D01*
X1453295Y886199D01*
G02X1453222Y886627I1225J429D01*
G37*
G36*
G01X1460622D02*
G02X1463218I1298J0D01*
G02X1462162Y885352I-1298J0D01*
G01X1462072Y885335D01*
X1461265Y883938D01*
X1461296Y883851D01*
G02X1461368Y883423I-1225J-426D01*
G02X1458774I-1297J0D01*
G02X1459829Y884698I1298J0D01*
G01X1459919Y884715D01*
X1460726Y886112D01*
X1460695Y886199D01*
G02X1460622Y886627I1225J429D01*
G37*
G36*
G01X1468022D02*
G02X1470618I1298J0D01*
G02X1469562Y885352I-1298J0D01*
G01X1469472Y885335D01*
X1468665Y883938D01*
X1468696Y883851D01*
G02X1468768Y883423I-1225J-426D01*
G02X1466174I-1297J0D01*
G02X1467229Y884698I1298J0D01*
G01X1467319Y884715D01*
X1468126Y886112D01*
X1468095Y886199D01*
G02X1468022Y886627I1225J429D01*
G37*
G36*
G01X1475422D02*
G02X1478018I1298J0D01*
G02X1476962Y885352I-1298J0D01*
G01X1476872Y885335D01*
X1476065Y883938D01*
X1476096Y883851D01*
G02X1476168Y883423I-1225J-426D01*
G02X1473574I-1297J0D01*
G02X1474629Y884698I1298J0D01*
G01X1474719Y884715D01*
X1475526Y886112D01*
X1475495Y886199D01*
G02X1475422Y886627I1225J429D01*
G37*
G36*
G01X1482822D02*
G02X1485418I1298J0D01*
G02X1484362Y885352I-1298J0D01*
G01X1484272Y885335D01*
X1483465Y883938D01*
X1483496Y883851D01*
G02X1483568Y883423I-1225J-426D01*
G02X1480974I-1297J0D01*
G02X1482029Y884698I1298J0D01*
G01X1482119Y884715D01*
X1482926Y886112D01*
X1482895Y886199D01*
G02X1482822Y886627I1225J429D01*
G37*
G36*
G01X1490222D02*
G02X1492818I1298J0D01*
G02X1491762Y885352I-1298J0D01*
G01X1491672Y885335D01*
X1490865Y883938D01*
X1490896Y883851D01*
G02X1490968Y883423I-1225J-426D01*
G02X1488374I-1297J0D01*
G02X1489429Y884698I1298J0D01*
G01X1489519Y884715D01*
X1490326Y886112D01*
X1490295Y886199D01*
G02X1490222Y886627I1225J429D01*
G37*
G36*
G01X1497622D02*
G02X1500218I1298J0D01*
G02X1499162Y885352I-1298J0D01*
G01X1499072Y885335D01*
X1498265Y883938D01*
X1498296Y883851D01*
G02X1498368Y883423I-1225J-426D01*
G02X1495774I-1297J0D01*
G02X1496829Y884698I1298J0D01*
G01X1496919Y884715D01*
X1497726Y886112D01*
X1497695Y886199D01*
G02X1497622Y886627I1225J429D01*
G37*
G36*
G01X355414Y1124651D02*
G02X358010I1298J0D01*
G02X357937Y1124223I-1298J1D01*
G01X357906Y1124136D01*
X358713Y1122739D01*
X358803Y1122722D01*
G02X359858Y1121447I-243J-1275D01*
G02X357264I-1297J0D01*
G02X357336Y1121876I1297J3D01*
G01X357367Y1121962D01*
X356560Y1123359D01*
X356470Y1123376D01*
G02X355414Y1124651I242J1275D01*
G37*
G36*
G01X362814D02*
G02X365408I1297J0D01*
G02X365336Y1124223I-1297J-2D01*
G01X365305Y1124136D01*
X366112Y1122739D01*
X366202Y1122722D01*
G02X367260Y1121447I-239J-1275D01*
G02X364664I-1298J0D01*
G02X364737Y1121874I1298J-2D01*
G01X364767Y1121960D01*
X363959Y1123359D01*
X363869Y1123376D01*
G02X362814Y1124651I243J1275D01*
G37*
G36*
G01X370214D02*
G02X372808I1297J0D01*
G02X372736Y1124223I-1297J-2D01*
G01X372705Y1124136D01*
X373512Y1122739D01*
X373602Y1122722D01*
G02X374660Y1121447I-239J-1275D01*
G02X372064I-1298J0D01*
G02X372137Y1121874I1298J-2D01*
G01X372167Y1121960D01*
X371359Y1123359D01*
X371269Y1123376D01*
G02X370214Y1124651I243J1275D01*
G37*
G36*
G01X377614D02*
G02X380208I1297J0D01*
G02X380136Y1124223I-1297J-2D01*
G01X380105Y1124136D01*
X380912Y1122739D01*
X381002Y1122722D01*
G02X382060Y1121447I-239J-1275D01*
G02X379464I-1298J0D01*
G02X379537Y1121874I1298J-2D01*
G01X379567Y1121960D01*
X378759Y1123359D01*
X378669Y1123376D01*
G02X377614Y1124651I243J1275D01*
G37*
G36*
G01X385014D02*
G02X387608I1297J0D01*
G02X387536Y1124223I-1297J-2D01*
G01X387505Y1124136D01*
X388312Y1122739D01*
X388402Y1122722D01*
G02X389460Y1121447I-239J-1275D01*
G02X386864I-1298J0D01*
G02X386937Y1121874I1298J-2D01*
G01X386967Y1121960D01*
X386159Y1123359D01*
X386069Y1123376D01*
G02X385014Y1124651I243J1275D01*
G37*
G36*
G01X392414D02*
G02X395008I1297J0D01*
G02X394936Y1124223I-1297J-2D01*
G01X394905Y1124136D01*
X395712Y1122739D01*
X395802Y1122722D01*
G02X396860Y1121447I-239J-1275D01*
G02X394264I-1298J0D01*
G02X394337Y1121874I1298J-2D01*
G01X394367Y1121960D01*
X393559Y1123359D01*
X393469Y1123376D01*
G02X392414Y1124651I243J1275D01*
G37*
G36*
G01X399814D02*
G02X402408I1297J0D01*
G02X402336Y1124223I-1297J-2D01*
G01X402305Y1124136D01*
X403112Y1122739D01*
X403202Y1122722D01*
G02X404260Y1121447I-239J-1275D01*
G02X401664I-1298J0D01*
G02X401737Y1121874I1298J-2D01*
G01X401767Y1121960D01*
X400959Y1123359D01*
X400869Y1123376D01*
G02X399814Y1124651I243J1275D01*
G37*
G36*
G01X407214D02*
G02X409808I1297J0D01*
G02X409736Y1124223I-1297J-2D01*
G01X409705Y1124136D01*
X410512Y1122739D01*
X410602Y1122722D01*
G02X411660Y1121447I-239J-1275D01*
G02X409064I-1298J0D01*
G02X409137Y1121874I1298J-2D01*
G01X409167Y1121960D01*
X408359Y1123359D01*
X408269Y1123376D01*
G02X407214Y1124651I243J1275D01*
G37*
G36*
G01X470114D02*
G02X472708I1297J0D01*
G02X471653Y1123376I-1298J0D01*
G01X471563Y1123359D01*
X470756Y1121962D01*
X470787Y1121875D01*
G02X470860Y1121447I-1225J-429D01*
G02X468264I-1298J0D01*
G02X469320Y1122722I1298J0D01*
G01X469410Y1122739D01*
X470217Y1124136D01*
X470186Y1124223D01*
G02X470114Y1124651I1225J426D01*
G37*
G36*
G01X477514D02*
G02X480108I1297J0D01*
G02X479053Y1123376I-1298J0D01*
G01X478963Y1123359D01*
X478156Y1121962D01*
X478187Y1121875D01*
G02X478260Y1121447I-1225J-429D01*
G02X475664I-1298J0D01*
G02X476720Y1122722I1298J0D01*
G01X476810Y1122739D01*
X477617Y1124136D01*
X477586Y1124223D01*
G02X477514Y1124651I1225J426D01*
G37*
G36*
G01X484914D02*
G02X487508I1297J0D01*
G02X486453Y1123376I-1298J0D01*
G01X486363Y1123359D01*
X485556Y1121962D01*
X485587Y1121875D01*
G02X485660Y1121447I-1225J-429D01*
G02X483064I-1298J0D01*
G02X484120Y1122722I1298J0D01*
G01X484210Y1122739D01*
X485017Y1124136D01*
X484986Y1124223D01*
G02X484914Y1124651I1225J426D01*
G37*
G36*
G01X492314D02*
G02X494908I1297J0D01*
G02X493853Y1123376I-1298J0D01*
G01X493763Y1123359D01*
X492956Y1121962D01*
X492987Y1121875D01*
G02X493060Y1121447I-1225J-429D01*
G02X490464I-1298J0D01*
G02X491520Y1122722I1298J0D01*
G01X491610Y1122739D01*
X492417Y1124136D01*
X492386Y1124223D01*
G02X492314Y1124651I1225J426D01*
G37*
G36*
G01X499714D02*
G02X502308I1297J0D01*
G02X501253Y1123376I-1298J0D01*
G01X501163Y1123359D01*
X500356Y1121962D01*
X500387Y1121875D01*
G02X500460Y1121447I-1225J-429D01*
G02X497864I-1298J0D01*
G02X498920Y1122722I1298J0D01*
G01X499010Y1122739D01*
X499817Y1124136D01*
X499786Y1124223D01*
G02X499714Y1124651I1225J426D01*
G37*
G36*
G01X507114D02*
G02X509708I1297J0D01*
G02X508653Y1123376I-1298J0D01*
G01X508563Y1123359D01*
X507756Y1121962D01*
X507787Y1121875D01*
G02X507860Y1121447I-1225J-429D01*
G02X505264I-1298J0D01*
G02X506320Y1122722I1298J0D01*
G01X506410Y1122739D01*
X507217Y1124136D01*
X507186Y1124223D01*
G02X507114Y1124651I1225J426D01*
G37*
G36*
G01X514514D02*
G02X517108I1297J0D01*
G02X516053Y1123376I-1298J0D01*
G01X515963Y1123359D01*
X515156Y1121962D01*
X515187Y1121875D01*
G02X515260Y1121447I-1225J-429D01*
G02X512664I-1298J0D01*
G02X513720Y1122722I1298J0D01*
G01X513810Y1122739D01*
X514617Y1124136D01*
X514586Y1124223D01*
G02X514514Y1124651I1225J426D01*
G37*
G36*
G01X521914D02*
G02X524508I1297J0D01*
G02X523453Y1123376I-1298J0D01*
G01X523363Y1123359D01*
X522556Y1121962D01*
X522587Y1121875D01*
G02X522660Y1121447I-1225J-429D01*
G02X520064I-1298J0D01*
G02X521120Y1122722I1298J0D01*
G01X521210Y1122739D01*
X522017Y1124136D01*
X521986Y1124223D01*
G02X521914Y1124651I1225J426D01*
G37*
G36*
G01X1331556D02*
G02X1334152I1298J0D01*
G02X1334079Y1124223I-1298J1D01*
G01X1334048Y1124136D01*
X1334855Y1122739D01*
X1334945Y1122722D01*
G02X1336000Y1121447I-243J-1275D01*
G02X1333406I-1297J0D01*
G02X1333478Y1121876I1297J3D01*
G01X1333509Y1121962D01*
X1332702Y1123359D01*
X1332612Y1123376D01*
G02X1331556Y1124651I242J1275D01*
G37*
G36*
G01X1338956D02*
G02X1341550I1297J0D01*
G02X1341478Y1124223I-1297J-2D01*
G01X1341447Y1124136D01*
X1342254Y1122739D01*
X1342344Y1122722D01*
G02X1343402Y1121447I-239J-1275D01*
G02X1340806I-1298J0D01*
G02X1340879Y1121874I1298J-2D01*
G01X1340909Y1121960D01*
X1340101Y1123359D01*
X1340011Y1123376D01*
G02X1338956Y1124651I243J1275D01*
G37*
G36*
G01X1346356D02*
G02X1348950I1297J0D01*
G02X1348878Y1124223I-1297J-2D01*
G01X1348847Y1124136D01*
X1349654Y1122739D01*
X1349744Y1122722D01*
G02X1350802Y1121447I-239J-1275D01*
G02X1348206I-1298J0D01*
G02X1348279Y1121874I1298J-2D01*
G01X1348309Y1121960D01*
X1347501Y1123359D01*
X1347411Y1123376D01*
G02X1346356Y1124651I243J1275D01*
G37*
G36*
G01X1353756D02*
G02X1356350I1297J0D01*
G02X1356278Y1124223I-1297J-2D01*
G01X1356247Y1124136D01*
X1357054Y1122739D01*
X1357144Y1122722D01*
G02X1358202Y1121447I-239J-1275D01*
G02X1355606I-1298J0D01*
G02X1355679Y1121874I1298J-2D01*
G01X1355709Y1121960D01*
X1354901Y1123359D01*
X1354811Y1123376D01*
G02X1353756Y1124651I243J1275D01*
G37*
G36*
G01X1361156D02*
G02X1363750I1297J0D01*
G02X1363678Y1124223I-1297J-2D01*
G01X1363647Y1124136D01*
X1364454Y1122739D01*
X1364544Y1122722D01*
G02X1365602Y1121447I-239J-1275D01*
G02X1363006I-1298J0D01*
G02X1363079Y1121874I1298J-2D01*
G01X1363109Y1121960D01*
X1362301Y1123359D01*
X1362211Y1123376D01*
G02X1361156Y1124651I243J1275D01*
G37*
G36*
G01X1368556D02*
G02X1371150I1297J0D01*
G02X1371078Y1124223I-1297J-2D01*
G01X1371047Y1124136D01*
X1371854Y1122739D01*
X1371944Y1122722D01*
G02X1373002Y1121447I-239J-1275D01*
G02X1370406I-1298J0D01*
G02X1370479Y1121874I1298J-2D01*
G01X1370509Y1121960D01*
X1369701Y1123359D01*
X1369611Y1123376D01*
G02X1368556Y1124651I243J1275D01*
G37*
G36*
G01X1375956D02*
G02X1378550I1297J0D01*
G02X1378478Y1124223I-1297J-2D01*
G01X1378447Y1124136D01*
X1379254Y1122739D01*
X1379344Y1122722D01*
G02X1380402Y1121447I-239J-1275D01*
G02X1377806I-1298J0D01*
G02X1377879Y1121874I1298J-2D01*
G01X1377909Y1121960D01*
X1377101Y1123359D01*
X1377011Y1123376D01*
G02X1375956Y1124651I243J1275D01*
G37*
G36*
G01X1383356D02*
G02X1385950I1297J0D01*
G02X1385878Y1124223I-1297J-2D01*
G01X1385847Y1124136D01*
X1386654Y1122739D01*
X1386744Y1122722D01*
G02X1387802Y1121447I-239J-1275D01*
G02X1385206I-1298J0D01*
G02X1385279Y1121874I1298J-2D01*
G01X1385309Y1121960D01*
X1384501Y1123359D01*
X1384411Y1123376D01*
G02X1383356Y1124651I243J1275D01*
G37*
G36*
G01X1446256D02*
G02X1448850I1297J0D01*
G02X1447795Y1123376I-1298J0D01*
G01X1447705Y1123359D01*
X1446898Y1121962D01*
X1446929Y1121875D01*
G02X1447002Y1121447I-1225J-429D01*
G02X1444406I-1298J0D01*
G02X1445462Y1122722I1298J0D01*
G01X1445552Y1122739D01*
X1446359Y1124136D01*
X1446328Y1124223D01*
G02X1446256Y1124651I1225J426D01*
G37*
G36*
G01X1453656D02*
G02X1456250I1297J0D01*
G02X1455195Y1123376I-1298J0D01*
G01X1455105Y1123359D01*
X1454298Y1121962D01*
X1454329Y1121875D01*
G02X1454402Y1121447I-1225J-429D01*
G02X1451806I-1298J0D01*
G02X1452862Y1122722I1298J0D01*
G01X1452952Y1122739D01*
X1453759Y1124136D01*
X1453728Y1124223D01*
G02X1453656Y1124651I1225J426D01*
G37*
G36*
G01X1461056D02*
G02X1463650I1297J0D01*
G02X1462595Y1123376I-1298J0D01*
G01X1462505Y1123359D01*
X1461698Y1121962D01*
X1461729Y1121875D01*
G02X1461802Y1121447I-1225J-429D01*
G02X1459206I-1298J0D01*
G02X1460262Y1122722I1298J0D01*
G01X1460352Y1122739D01*
X1461159Y1124136D01*
X1461128Y1124223D01*
G02X1461056Y1124651I1225J426D01*
G37*
G36*
G01X1468456D02*
G02X1471050I1297J0D01*
G02X1469995Y1123376I-1298J0D01*
G01X1469905Y1123359D01*
X1469098Y1121962D01*
X1469129Y1121875D01*
G02X1469202Y1121447I-1225J-429D01*
G02X1466606I-1298J0D01*
G02X1467662Y1122722I1298J0D01*
G01X1467752Y1122739D01*
X1468559Y1124136D01*
X1468528Y1124223D01*
G02X1468456Y1124651I1225J426D01*
G37*
G36*
G01X1475856D02*
G02X1478450I1297J0D01*
G02X1477395Y1123376I-1298J0D01*
G01X1477305Y1123359D01*
X1476498Y1121962D01*
X1476529Y1121875D01*
G02X1476602Y1121447I-1225J-429D01*
G02X1474006I-1298J0D01*
G02X1475062Y1122722I1298J0D01*
G01X1475152Y1122739D01*
X1475959Y1124136D01*
X1475928Y1124223D01*
G02X1475856Y1124651I1225J426D01*
G37*
G36*
G01X1483256D02*
G02X1485850I1297J0D01*
G02X1484795Y1123376I-1298J0D01*
G01X1484705Y1123359D01*
X1483898Y1121962D01*
X1483929Y1121875D01*
G02X1484002Y1121447I-1225J-429D01*
G02X1481406I-1298J0D01*
G02X1482462Y1122722I1298J0D01*
G01X1482552Y1122739D01*
X1483359Y1124136D01*
X1483328Y1124223D01*
G02X1483256Y1124651I1225J426D01*
G37*
G36*
G01X1490656D02*
G02X1493250I1297J0D01*
G02X1492195Y1123376I-1298J0D01*
G01X1492105Y1123359D01*
X1491298Y1121962D01*
X1491329Y1121875D01*
G02X1491402Y1121447I-1225J-429D01*
G02X1488806I-1298J0D01*
G02X1489862Y1122722I1298J0D01*
G01X1489952Y1122739D01*
X1490759Y1124136D01*
X1490728Y1124223D01*
G02X1490656Y1124651I1225J426D01*
G37*
G36*
G01X1498056D02*
G02X1500650I1297J0D01*
G02X1499595Y1123376I-1298J0D01*
G01X1499505Y1123359D01*
X1498698Y1121962D01*
X1498729Y1121875D01*
G02X1498802Y1121447I-1225J-429D01*
G02X1496206I-1298J0D01*
G02X1497262Y1122722I1298J0D01*
G01X1497352Y1122739D01*
X1498159Y1124136D01*
X1498128Y1124223D01*
G02X1498056Y1124651I1225J426D01*
G37*
G36*
G01X353564Y1127856D02*
G02X356158I1297J0D01*
G02X355103Y1126581I-1298J0D01*
G01X355013Y1126564D01*
X354205Y1125166D01*
X354236Y1125079D01*
G02X354308Y1124651I-1225J-426D01*
G02X351714I-1297J0D01*
G02X352769Y1125926I1298J0D01*
G01X352859Y1125943D01*
X353667Y1127341D01*
X353636Y1127428D01*
G02X353564Y1127856I1225J426D01*
G37*
G36*
G01X360964D02*
G02X363560I1298J0D01*
G02X362504Y1126581I-1298J0D01*
G01X362414Y1126564D01*
X361606Y1125166D01*
X361637Y1125079D01*
G02X361710Y1124651I-1225J-429D01*
G02X359114I-1298J0D01*
G02X360170Y1125926I1298J0D01*
G01X360260Y1125943D01*
X361068Y1127341D01*
X361037Y1127428D01*
G02X360964Y1127856I1225J429D01*
G37*
G36*
G01X368364D02*
G02X370960I1298J0D01*
G02X369904Y1126581I-1298J0D01*
G01X369814Y1126564D01*
X369006Y1125165D01*
X369036Y1125078D01*
G02X369108Y1124653I-1225J-426D01*
G01Y1124651D01*
G02X366514I-1297J0D01*
G02X367570Y1125926I1298J0D01*
G01X367661Y1125943D01*
X368468Y1127341D01*
X368437Y1127428D01*
G02X368364Y1127856I1225J429D01*
G37*
G36*
G01X375764D02*
G02X378360I1298J0D01*
G02X377304Y1126581I-1298J0D01*
G01X377214Y1126564D01*
X376406Y1125165D01*
X376436Y1125078D01*
G02X376508Y1124653I-1225J-426D01*
G01Y1124651D01*
G02X373914I-1297J0D01*
G02X374970Y1125926I1298J0D01*
G01X375061Y1125943D01*
X375868Y1127341D01*
X375837Y1127428D01*
G02X375764Y1127856I1225J429D01*
G37*
G36*
G01X383164D02*
G02X385760I1298J0D01*
G02X384704Y1126581I-1298J0D01*
G01X384614Y1126564D01*
X383806Y1125165D01*
X383836Y1125078D01*
G02X383908Y1124653I-1225J-426D01*
G01Y1124651D01*
G02X381314I-1297J0D01*
G02X382370Y1125926I1298J0D01*
G01X382461Y1125943D01*
X383268Y1127341D01*
X383237Y1127428D01*
G02X383164Y1127856I1225J429D01*
G37*
G36*
G01X390564D02*
G02X393160I1298J0D01*
G02X392104Y1126581I-1298J0D01*
G01X392014Y1126564D01*
X391206Y1125165D01*
X391236Y1125078D01*
G02X391308Y1124653I-1225J-426D01*
G01Y1124651D01*
G02X388714I-1297J0D01*
G02X389770Y1125926I1298J0D01*
G01X389861Y1125943D01*
X390668Y1127341D01*
X390637Y1127428D01*
G02X390564Y1127856I1225J429D01*
G37*
G36*
G01X397964D02*
G02X400560I1298J0D01*
G02X399504Y1126581I-1298J0D01*
G01X399414Y1126564D01*
X398606Y1125165D01*
X398636Y1125078D01*
G02X398708Y1124653I-1225J-426D01*
G01Y1124651D01*
G02X396114I-1297J0D01*
G02X397170Y1125926I1298J0D01*
G01X397261Y1125943D01*
X398068Y1127341D01*
X398037Y1127428D01*
G02X397964Y1127856I1225J429D01*
G37*
G36*
G01X405364D02*
G02X407960I1298J0D01*
G02X406904Y1126581I-1298J0D01*
G01X406814Y1126564D01*
X406006Y1125165D01*
X406036Y1125078D01*
G02X406108Y1124653I-1225J-426D01*
G01Y1124651D01*
G02X403514I-1297J0D01*
G02X404570Y1125926I1298J0D01*
G01X404661Y1125943D01*
X405468Y1127341D01*
X405437Y1127428D01*
G02X405364Y1127856I1225J429D01*
G37*
G36*
G01X471964D02*
G02X474560I1298J0D01*
G02X474487Y1127427I-1297J0D01*
G01X474456Y1127341D01*
X475263Y1125943D01*
X475353Y1125926D01*
G02X476408Y1124651I-243J-1275D01*
G02X473814I-1297J0D01*
G02X473886Y1125080I1297J3D01*
G01X473917Y1125166D01*
X473110Y1126564D01*
X473020Y1126581D01*
G02X471964Y1127856I242J1275D01*
G37*
G36*
G01X479364D02*
G02X481960I1298J0D01*
G02X481887Y1127427I-1297J0D01*
G01X481856Y1127341D01*
X482663Y1125943D01*
X482753Y1125926D01*
G02X483808Y1124651I-243J-1275D01*
G02X481214I-1297J0D01*
G02X481286Y1125080I1297J3D01*
G01X481317Y1125166D01*
X480510Y1126564D01*
X480420Y1126581D01*
G02X479364Y1127856I242J1275D01*
G37*
G36*
G01X486764D02*
G02X489360I1298J0D01*
G02X489287Y1127427I-1297J0D01*
G01X489256Y1127341D01*
X490063Y1125943D01*
X490153Y1125926D01*
G02X491208Y1124651I-243J-1275D01*
G02X488614I-1297J0D01*
G02X488686Y1125080I1297J3D01*
G01X488717Y1125166D01*
X487910Y1126564D01*
X487820Y1126581D01*
G02X486764Y1127856I242J1275D01*
G37*
G36*
G01X494164D02*
G02X496760I1298J0D01*
G02X496687Y1127427I-1297J0D01*
G01X496656Y1127341D01*
X497463Y1125943D01*
X497553Y1125926D01*
G02X498608Y1124651I-243J-1275D01*
G02X496014I-1297J0D01*
G02X496086Y1125080I1297J3D01*
G01X496117Y1125166D01*
X495310Y1126564D01*
X495220Y1126581D01*
G02X494164Y1127856I242J1275D01*
G37*
G36*
G01X501564D02*
G02X504160I1298J0D01*
G02X504087Y1127427I-1297J0D01*
G01X504056Y1127341D01*
X504863Y1125943D01*
X504953Y1125926D01*
G02X506008Y1124651I-243J-1275D01*
G02X503414I-1297J0D01*
G02X503486Y1125080I1297J3D01*
G01X503517Y1125166D01*
X502710Y1126564D01*
X502620Y1126581D01*
G02X501564Y1127856I242J1275D01*
G37*
G36*
G01X508964D02*
G02X511560I1298J0D01*
G02X511487Y1127427I-1297J0D01*
G01X511456Y1127341D01*
X512263Y1125943D01*
X512353Y1125926D01*
G02X513408Y1124651I-243J-1275D01*
G02X510814I-1297J0D01*
G02X510886Y1125080I1297J3D01*
G01X510917Y1125166D01*
X510110Y1126564D01*
X510020Y1126581D01*
G02X508964Y1127856I242J1275D01*
G37*
G36*
G01X516364D02*
G02X518960I1298J0D01*
G02X518887Y1127427I-1297J0D01*
G01X518856Y1127341D01*
X519663Y1125943D01*
X519753Y1125926D01*
G02X520808Y1124651I-243J-1275D01*
G02X518214I-1297J0D01*
G02X518286Y1125080I1297J3D01*
G01X518317Y1125166D01*
X517510Y1126564D01*
X517420Y1126581D01*
G02X516364Y1127856I242J1275D01*
G37*
G36*
G01X523764D02*
G02X526360I1298J0D01*
G02X526287Y1127427I-1297J0D01*
G01X526256Y1127341D01*
X527063Y1125943D01*
X527153Y1125926D01*
G02X528208Y1124651I-243J-1275D01*
G02X525614I-1297J0D01*
G02X525686Y1125080I1297J3D01*
G01X525717Y1125166D01*
X524910Y1126564D01*
X524820Y1126581D01*
G02X523764Y1127856I242J1275D01*
G37*
G36*
G01X1329706D02*
G02X1332300I1297J0D01*
G02X1331245Y1126581I-1298J0D01*
G01X1331155Y1126564D01*
X1330347Y1125166D01*
X1330378Y1125079D01*
G02X1330450Y1124651I-1225J-426D01*
G02X1327856I-1297J0D01*
G02X1328911Y1125926I1298J0D01*
G01X1329001Y1125943D01*
X1329809Y1127341D01*
X1329778Y1127428D01*
G02X1329706Y1127856I1225J426D01*
G37*
G36*
G01X1337106D02*
G02X1339702I1298J0D01*
G02X1338646Y1126581I-1298J0D01*
G01X1338556Y1126564D01*
X1337748Y1125166D01*
X1337779Y1125079D01*
G02X1337852Y1124651I-1225J-429D01*
G02X1335256I-1298J0D01*
G02X1336312Y1125926I1298J0D01*
G01X1336402Y1125943D01*
X1337210Y1127341D01*
X1337179Y1127428D01*
G02X1337106Y1127856I1225J429D01*
G37*
G36*
G01X1344506D02*
G02X1347102I1298J0D01*
G02X1346046Y1126581I-1298J0D01*
G01X1345956Y1126564D01*
X1345148Y1125165D01*
X1345178Y1125078D01*
G02X1345250Y1124653I-1225J-426D01*
G01Y1124651D01*
G02X1342656I-1297J0D01*
G02X1343712Y1125926I1298J0D01*
G01X1343803Y1125943D01*
X1344610Y1127341D01*
X1344579Y1127428D01*
G02X1344506Y1127856I1225J429D01*
G37*
G36*
G01X1351906D02*
G02X1354502I1298J0D01*
G02X1353446Y1126581I-1298J0D01*
G01X1353356Y1126564D01*
X1352548Y1125165D01*
X1352578Y1125078D01*
G02X1352650Y1124653I-1225J-426D01*
G01Y1124651D01*
G02X1350056I-1297J0D01*
G02X1351112Y1125926I1298J0D01*
G01X1351203Y1125943D01*
X1352010Y1127341D01*
X1351979Y1127428D01*
G02X1351906Y1127856I1225J429D01*
G37*
G36*
G01X1359306D02*
G02X1361902I1298J0D01*
G02X1360846Y1126581I-1298J0D01*
G01X1360756Y1126564D01*
X1359948Y1125165D01*
X1359978Y1125078D01*
G02X1360050Y1124653I-1225J-426D01*
G01Y1124651D01*
G02X1357456I-1297J0D01*
G02X1358512Y1125926I1298J0D01*
G01X1358603Y1125943D01*
X1359410Y1127341D01*
X1359379Y1127428D01*
G02X1359306Y1127856I1225J429D01*
G37*
G36*
G01X1366706D02*
G02X1369302I1298J0D01*
G02X1368246Y1126581I-1298J0D01*
G01X1368156Y1126564D01*
X1367348Y1125165D01*
X1367378Y1125078D01*
G02X1367450Y1124653I-1225J-426D01*
G01Y1124651D01*
G02X1364856I-1297J0D01*
G02X1365912Y1125926I1298J0D01*
G01X1366003Y1125943D01*
X1366810Y1127341D01*
X1366779Y1127428D01*
G02X1366706Y1127856I1225J429D01*
G37*
G36*
G01X1374106D02*
G02X1376702I1298J0D01*
G02X1375646Y1126581I-1298J0D01*
G01X1375556Y1126564D01*
X1374748Y1125165D01*
X1374778Y1125078D01*
G02X1374850Y1124653I-1225J-426D01*
G01Y1124651D01*
G02X1372256I-1297J0D01*
G02X1373312Y1125926I1298J0D01*
G01X1373403Y1125943D01*
X1374210Y1127341D01*
X1374179Y1127428D01*
G02X1374106Y1127856I1225J429D01*
G37*
G36*
G01X1381506D02*
G02X1384102I1298J0D01*
G02X1383046Y1126581I-1298J0D01*
G01X1382956Y1126564D01*
X1382148Y1125165D01*
X1382178Y1125078D01*
G02X1382250Y1124653I-1225J-426D01*
G01Y1124651D01*
G02X1379656I-1297J0D01*
G02X1380712Y1125926I1298J0D01*
G01X1380803Y1125943D01*
X1381610Y1127341D01*
X1381579Y1127428D01*
G02X1381506Y1127856I1225J429D01*
G37*
G36*
G01X1448106D02*
G02X1450702I1298J0D01*
G02X1450629Y1127427I-1297J0D01*
G01X1450598Y1127341D01*
X1451405Y1125943D01*
X1451495Y1125926D01*
G02X1452550Y1124651I-243J-1275D01*
G02X1449956I-1297J0D01*
G02X1450028Y1125080I1297J3D01*
G01X1450059Y1125166D01*
X1449252Y1126564D01*
X1449162Y1126581D01*
G02X1448106Y1127856I242J1275D01*
G37*
G36*
G01X1455506D02*
G02X1458102I1298J0D01*
G02X1458029Y1127427I-1297J0D01*
G01X1457998Y1127341D01*
X1458805Y1125943D01*
X1458895Y1125926D01*
G02X1459950Y1124651I-243J-1275D01*
G02X1457356I-1297J0D01*
G02X1457428Y1125080I1297J3D01*
G01X1457459Y1125166D01*
X1456652Y1126564D01*
X1456562Y1126581D01*
G02X1455506Y1127856I242J1275D01*
G37*
G36*
G01X1462906D02*
G02X1465502I1298J0D01*
G02X1465429Y1127427I-1297J0D01*
G01X1465398Y1127341D01*
X1466205Y1125943D01*
X1466295Y1125926D01*
G02X1467350Y1124651I-243J-1275D01*
G02X1464756I-1297J0D01*
G02X1464828Y1125080I1297J3D01*
G01X1464859Y1125166D01*
X1464052Y1126564D01*
X1463962Y1126581D01*
G02X1462906Y1127856I242J1275D01*
G37*
G36*
G01X1470306D02*
G02X1472902I1298J0D01*
G02X1472829Y1127427I-1297J0D01*
G01X1472798Y1127341D01*
X1473605Y1125943D01*
X1473695Y1125926D01*
G02X1474750Y1124651I-243J-1275D01*
G02X1472156I-1297J0D01*
G02X1472228Y1125080I1297J3D01*
G01X1472259Y1125166D01*
X1471452Y1126564D01*
X1471362Y1126581D01*
G02X1470306Y1127856I242J1275D01*
G37*
G36*
G01X1477706D02*
G02X1480302I1298J0D01*
G02X1480229Y1127427I-1297J0D01*
G01X1480198Y1127341D01*
X1481005Y1125943D01*
X1481095Y1125926D01*
G02X1482150Y1124651I-243J-1275D01*
G02X1479556I-1297J0D01*
G02X1479628Y1125080I1297J3D01*
G01X1479659Y1125166D01*
X1478852Y1126564D01*
X1478762Y1126581D01*
G02X1477706Y1127856I242J1275D01*
G37*
G36*
G01X1485106D02*
G02X1487702I1298J0D01*
G02X1487629Y1127427I-1297J0D01*
G01X1487598Y1127341D01*
X1488405Y1125943D01*
X1488495Y1125926D01*
G02X1489550Y1124651I-243J-1275D01*
G02X1486956I-1297J0D01*
G02X1487028Y1125080I1297J3D01*
G01X1487059Y1125166D01*
X1486252Y1126564D01*
X1486162Y1126581D01*
G02X1485106Y1127856I242J1275D01*
G37*
G36*
G01X1492506D02*
G02X1495102I1298J0D01*
G02X1495029Y1127427I-1297J0D01*
G01X1494998Y1127341D01*
X1495805Y1125943D01*
X1495895Y1125926D01*
G02X1496950Y1124651I-243J-1275D01*
G02X1494356I-1297J0D01*
G02X1494428Y1125080I1297J3D01*
G01X1494459Y1125166D01*
X1493652Y1126564D01*
X1493562Y1126581D01*
G02X1492506Y1127856I242J1275D01*
G37*
G36*
G01X1499906D02*
G02X1502502I1298J0D01*
G02X1502429Y1127427I-1297J0D01*
G01X1502398Y1127341D01*
X1503205Y1125943D01*
X1503295Y1125926D01*
G02X1504350Y1124651I-243J-1275D01*
G02X1501756I-1297J0D01*
G02X1501828Y1125080I1297J3D01*
G01X1501859Y1125166D01*
X1501052Y1126564D01*
X1500962Y1126581D01*
G02X1499906Y1127856I242J1275D01*
G37*
G36*
G01X348014Y1137469D02*
G02X350610I1298J0D01*
G02X350537Y1137040I-1297J0D01*
G01X350506Y1136954D01*
X351313Y1135556D01*
X351403Y1135539D01*
G02X352458Y1134264I-243J-1275D01*
G02X349864I-1297J0D01*
G02X349936Y1134693I1297J3D01*
G01X349967Y1134779D01*
X349160Y1136177D01*
X349070Y1136194D01*
G02X348014Y1137469I242J1275D01*
G37*
G36*
G01X355414D02*
G02X358010I1298J0D01*
G02X357937Y1137040I-1297J0D01*
G01X357906Y1136954D01*
X358713Y1135556D01*
X358803Y1135539D01*
G02X359858Y1134264I-243J-1275D01*
G02X357264I-1297J0D01*
G02X357336Y1134693I1297J3D01*
G01X357367Y1134779D01*
X356560Y1136177D01*
X356470Y1136194D01*
G02X355414Y1137469I242J1275D01*
G37*
G36*
G01X362814D02*
G02X365410I1298J0D01*
G02X365337Y1137041I-1298J1D01*
G01X365306Y1136954D01*
X366114Y1135556D01*
X366204Y1135539D01*
G02X367260Y1134264I-242J-1275D01*
G02X364664I-1298J0D01*
G02X364737Y1134692I1298J-1D01*
G01X364768Y1134779D01*
X363960Y1136177D01*
X363870Y1136194D01*
G02X362814Y1137469I242J1275D01*
G37*
G36*
G01X370214D02*
G02X372810I1298J0D01*
G02X372737Y1137041I-1298J1D01*
G01X372706Y1136954D01*
X373514Y1135556D01*
X373604Y1135539D01*
G02X374660Y1134264I-242J-1275D01*
G02X372064I-1298J0D01*
G02X372137Y1134692I1298J-1D01*
G01X372168Y1134779D01*
X371360Y1136177D01*
X371270Y1136194D01*
G02X370214Y1137469I242J1275D01*
G37*
G36*
G01X377614D02*
G02X380210I1298J0D01*
G02X380137Y1137041I-1298J1D01*
G01X380106Y1136954D01*
X380914Y1135556D01*
X381004Y1135539D01*
G02X382060Y1134264I-242J-1275D01*
G02X379464I-1298J0D01*
G02X379537Y1134692I1298J-1D01*
G01X379568Y1134779D01*
X378760Y1136177D01*
X378670Y1136194D01*
G02X377614Y1137469I242J1275D01*
G37*
G36*
G01X385014D02*
G02X387610I1298J0D01*
G02X387537Y1137041I-1298J1D01*
G01X387506Y1136954D01*
X388314Y1135556D01*
X388404Y1135539D01*
G02X389460Y1134264I-242J-1275D01*
G02X386864I-1298J0D01*
G02X386937Y1134692I1298J-1D01*
G01X386968Y1134779D01*
X386160Y1136177D01*
X386070Y1136194D01*
G02X385014Y1137469I242J1275D01*
G37*
G36*
G01X392414D02*
G02X395010I1298J0D01*
G02X394937Y1137041I-1298J1D01*
G01X394906Y1136954D01*
X395714Y1135556D01*
X395804Y1135539D01*
G02X396860Y1134264I-242J-1275D01*
G02X394264I-1298J0D01*
G02X394337Y1134692I1298J-1D01*
G01X394368Y1134779D01*
X393560Y1136177D01*
X393470Y1136194D01*
G02X392414Y1137469I242J1275D01*
G37*
G36*
G01X399814D02*
G02X402410I1298J0D01*
G02X402337Y1137041I-1298J1D01*
G01X402306Y1136954D01*
X403114Y1135556D01*
X403204Y1135539D01*
G02X404260Y1134264I-242J-1275D01*
G02X401664I-1298J0D01*
G02X401737Y1134692I1298J-1D01*
G01X401768Y1134779D01*
X400960Y1136177D01*
X400870Y1136194D01*
G02X399814Y1137469I242J1275D01*
G37*
G36*
G01X407214D02*
G02X409810I1298J0D01*
G02X409737Y1137041I-1298J1D01*
G01X409706Y1136954D01*
X410514Y1135556D01*
X410604Y1135539D01*
G02X411660Y1134264I-242J-1275D01*
G02X409064I-1298J0D01*
G02X409137Y1134692I1298J-1D01*
G01X409168Y1134779D01*
X408360Y1136177D01*
X408270Y1136194D01*
G02X407214Y1137469I242J1275D01*
G37*
G36*
G01X477514D02*
G02X480110I1298J0D01*
G02X479054Y1136194I-1298J0D01*
G01X478964Y1136177D01*
X478156Y1134779D01*
X478187Y1134692D01*
G02X478260Y1134264I-1225J-429D01*
G02X475664I-1298J0D01*
G02X476720Y1135539I1298J0D01*
G01X476810Y1135556D01*
X477618Y1136954D01*
X477587Y1137041D01*
G02X477514Y1137469I1225J429D01*
G37*
G36*
G01X484914D02*
G02X487510I1298J0D01*
G02X486454Y1136194I-1298J0D01*
G01X486364Y1136177D01*
X485557Y1134779D01*
X485587Y1134692D01*
G02X485660Y1134264I-1225J-429D01*
G02X483064I-1298J0D01*
G02X484121Y1135539I1297J0D01*
G01X484211Y1135556D01*
X485018Y1136954D01*
X484987Y1137041D01*
G02X484914Y1137469I1225J429D01*
G37*
G36*
G01X492314D02*
G02X494910I1298J0D01*
G02X493854Y1136194I-1298J0D01*
G01X493764Y1136177D01*
X492957Y1134779D01*
X492987Y1134692D01*
G02X493060Y1134264I-1225J-429D01*
G02X490464I-1298J0D01*
G02X491521Y1135539I1297J0D01*
G01X491611Y1135556D01*
X492418Y1136954D01*
X492387Y1137041D01*
G02X492314Y1137469I1225J429D01*
G37*
G36*
G01X499714D02*
G02X502310I1298J0D01*
G02X501254Y1136194I-1298J0D01*
G01X501164Y1136177D01*
X500357Y1134779D01*
X500387Y1134692D01*
G02X500460Y1134264I-1225J-429D01*
G02X497864I-1298J0D01*
G02X498921Y1135539I1297J0D01*
G01X499011Y1135556D01*
X499818Y1136954D01*
X499787Y1137041D01*
G02X499714Y1137469I1225J429D01*
G37*
G36*
G01X507114D02*
G02X509710I1298J0D01*
G02X508654Y1136194I-1298J0D01*
G01X508564Y1136177D01*
X507757Y1134779D01*
X507787Y1134692D01*
G02X507860Y1134264I-1225J-429D01*
G02X505264I-1298J0D01*
G02X506321Y1135539I1297J0D01*
G01X506411Y1135556D01*
X507218Y1136954D01*
X507187Y1137041D01*
G02X507114Y1137469I1225J429D01*
G37*
G36*
G01X514514D02*
G02X517110I1298J0D01*
G02X516054Y1136194I-1298J0D01*
G01X515964Y1136177D01*
X515157Y1134779D01*
X515187Y1134692D01*
G02X515260Y1134264I-1225J-429D01*
G02X512664I-1298J0D01*
G02X513721Y1135539I1297J0D01*
G01X513811Y1135556D01*
X514618Y1136954D01*
X514587Y1137041D01*
G02X514514Y1137469I1225J429D01*
G37*
G36*
G01X521914D02*
G02X524510I1298J0D01*
G02X523454Y1136194I-1298J0D01*
G01X523364Y1136177D01*
X522557Y1134779D01*
X522587Y1134692D01*
G02X522660Y1134264I-1225J-429D01*
G02X520064I-1298J0D01*
G02X521121Y1135539I1297J0D01*
G01X521211Y1135556D01*
X522018Y1136954D01*
X521987Y1137041D01*
G02X521914Y1137469I1225J429D01*
G37*
G36*
G01X533014D02*
G02X535610I1298J0D01*
G02X534554Y1136194I-1298J0D01*
G01X534464Y1136177D01*
X533656Y1134779D01*
X533687Y1134692D01*
G02X533760Y1134264I-1225J-429D01*
G02X531164I-1298J0D01*
G02X532220Y1135539I1298J0D01*
G01X532310Y1135556D01*
X533118Y1136954D01*
X533087Y1137041D01*
G02X533014Y1137469I1225J429D01*
G37*
G36*
G01X1324156D02*
G02X1326752I1298J0D01*
G02X1326679Y1137040I-1297J0D01*
G01X1326648Y1136954D01*
X1327455Y1135556D01*
X1327545Y1135539D01*
G02X1328600Y1134264I-243J-1275D01*
G02X1326006I-1297J0D01*
G02X1326078Y1134693I1297J3D01*
G01X1326109Y1134779D01*
X1325302Y1136177D01*
X1325212Y1136194D01*
G02X1324156Y1137469I242J1275D01*
G37*
G36*
G01X1331556D02*
G02X1334152I1298J0D01*
G02X1334079Y1137040I-1297J0D01*
G01X1334048Y1136954D01*
X1334855Y1135556D01*
X1334945Y1135539D01*
G02X1336000Y1134264I-243J-1275D01*
G02X1333406I-1297J0D01*
G02X1333478Y1134693I1297J3D01*
G01X1333509Y1134779D01*
X1332702Y1136177D01*
X1332612Y1136194D01*
G02X1331556Y1137469I242J1275D01*
G37*
G36*
G01X1338956D02*
G02X1341552I1298J0D01*
G02X1341479Y1137041I-1298J1D01*
G01X1341448Y1136954D01*
X1342256Y1135556D01*
X1342346Y1135539D01*
G02X1343402Y1134264I-242J-1275D01*
G02X1340806I-1298J0D01*
G02X1340879Y1134692I1298J-1D01*
G01X1340910Y1134779D01*
X1340102Y1136177D01*
X1340012Y1136194D01*
G02X1338956Y1137469I242J1275D01*
G37*
G36*
G01X1346356D02*
G02X1348952I1298J0D01*
G02X1348879Y1137041I-1298J1D01*
G01X1348848Y1136954D01*
X1349656Y1135556D01*
X1349746Y1135539D01*
G02X1350802Y1134264I-242J-1275D01*
G02X1348206I-1298J0D01*
G02X1348279Y1134692I1298J-1D01*
G01X1348310Y1134779D01*
X1347502Y1136177D01*
X1347412Y1136194D01*
G02X1346356Y1137469I242J1275D01*
G37*
G36*
G01X1353756D02*
G02X1356352I1298J0D01*
G02X1356279Y1137041I-1298J1D01*
G01X1356248Y1136954D01*
X1357056Y1135556D01*
X1357146Y1135539D01*
G02X1358202Y1134264I-242J-1275D01*
G02X1355606I-1298J0D01*
G02X1355679Y1134692I1298J-1D01*
G01X1355710Y1134779D01*
X1354902Y1136177D01*
X1354812Y1136194D01*
G02X1353756Y1137469I242J1275D01*
G37*
G36*
G01X1361156D02*
G02X1363752I1298J0D01*
G02X1363679Y1137041I-1298J1D01*
G01X1363648Y1136954D01*
X1364456Y1135556D01*
X1364546Y1135539D01*
G02X1365602Y1134264I-242J-1275D01*
G02X1363006I-1298J0D01*
G02X1363079Y1134692I1298J-1D01*
G01X1363110Y1134779D01*
X1362302Y1136177D01*
X1362212Y1136194D01*
G02X1361156Y1137469I242J1275D01*
G37*
G36*
G01X1368556D02*
G02X1371152I1298J0D01*
G02X1371079Y1137041I-1298J1D01*
G01X1371048Y1136954D01*
X1371856Y1135556D01*
X1371946Y1135539D01*
G02X1373002Y1134264I-242J-1275D01*
G02X1370406I-1298J0D01*
G02X1370479Y1134692I1298J-1D01*
G01X1370510Y1134779D01*
X1369702Y1136177D01*
X1369612Y1136194D01*
G02X1368556Y1137469I242J1275D01*
G37*
G36*
G01X1375956D02*
G02X1378552I1298J0D01*
G02X1378479Y1137041I-1298J1D01*
G01X1378448Y1136954D01*
X1379256Y1135556D01*
X1379346Y1135539D01*
G02X1380402Y1134264I-242J-1275D01*
G02X1377806I-1298J0D01*
G02X1377879Y1134692I1298J-1D01*
G01X1377910Y1134779D01*
X1377102Y1136177D01*
X1377012Y1136194D01*
G02X1375956Y1137469I242J1275D01*
G37*
G36*
G01X1383356D02*
G02X1385952I1298J0D01*
G02X1385879Y1137041I-1298J1D01*
G01X1385848Y1136954D01*
X1386656Y1135556D01*
X1386746Y1135539D01*
G02X1387802Y1134264I-242J-1275D01*
G02X1385206I-1298J0D01*
G02X1385279Y1134692I1298J-1D01*
G01X1385310Y1134779D01*
X1384502Y1136177D01*
X1384412Y1136194D01*
G02X1383356Y1137469I242J1275D01*
G37*
G36*
G01X1453656D02*
G02X1456252I1298J0D01*
G02X1455196Y1136194I-1298J0D01*
G01X1455106Y1136177D01*
X1454298Y1134779D01*
X1454329Y1134692D01*
G02X1454402Y1134264I-1225J-429D01*
G02X1451806I-1298J0D01*
G02X1452862Y1135539I1298J0D01*
G01X1452952Y1135556D01*
X1453760Y1136954D01*
X1453729Y1137041D01*
G02X1453656Y1137469I1225J429D01*
G37*
G36*
G01X1461056D02*
G02X1463652I1298J0D01*
G02X1462596Y1136194I-1298J0D01*
G01X1462506Y1136177D01*
X1461699Y1134779D01*
X1461729Y1134692D01*
G02X1461802Y1134264I-1225J-429D01*
G02X1459206I-1298J0D01*
G02X1460263Y1135539I1297J0D01*
G01X1460353Y1135556D01*
X1461160Y1136954D01*
X1461129Y1137041D01*
G02X1461056Y1137469I1225J429D01*
G37*
G36*
G01X1468456D02*
G02X1471052I1298J0D01*
G02X1469996Y1136194I-1298J0D01*
G01X1469906Y1136177D01*
X1469099Y1134779D01*
X1469129Y1134692D01*
G02X1469202Y1134264I-1225J-429D01*
G02X1466606I-1298J0D01*
G02X1467663Y1135539I1297J0D01*
G01X1467753Y1135556D01*
X1468560Y1136954D01*
X1468529Y1137041D01*
G02X1468456Y1137469I1225J429D01*
G37*
G36*
G01X1475856D02*
G02X1478452I1298J0D01*
G02X1477396Y1136194I-1298J0D01*
G01X1477306Y1136177D01*
X1476499Y1134779D01*
X1476529Y1134692D01*
G02X1476602Y1134264I-1225J-429D01*
G02X1474006I-1298J0D01*
G02X1475063Y1135539I1297J0D01*
G01X1475153Y1135556D01*
X1475960Y1136954D01*
X1475929Y1137041D01*
G02X1475856Y1137469I1225J429D01*
G37*
G36*
G01X1483256D02*
G02X1485852I1298J0D01*
G02X1484796Y1136194I-1298J0D01*
G01X1484706Y1136177D01*
X1483899Y1134779D01*
X1483929Y1134692D01*
G02X1484002Y1134264I-1225J-429D01*
G02X1481406I-1298J0D01*
G02X1482463Y1135539I1297J0D01*
G01X1482553Y1135556D01*
X1483360Y1136954D01*
X1483329Y1137041D01*
G02X1483256Y1137469I1225J429D01*
G37*
G36*
G01X1490656D02*
G02X1493252I1298J0D01*
G02X1492196Y1136194I-1298J0D01*
G01X1492106Y1136177D01*
X1491299Y1134779D01*
X1491329Y1134692D01*
G02X1491402Y1134264I-1225J-429D01*
G02X1488806I-1298J0D01*
G02X1489863Y1135539I1297J0D01*
G01X1489953Y1135556D01*
X1490760Y1136954D01*
X1490729Y1137041D01*
G02X1490656Y1137469I1225J429D01*
G37*
G36*
G01X1498056D02*
G02X1500652I1298J0D01*
G02X1499596Y1136194I-1298J0D01*
G01X1499506Y1136177D01*
X1498699Y1134779D01*
X1498729Y1134692D01*
G02X1498802Y1134264I-1225J-429D01*
G02X1496206I-1298J0D01*
G02X1497263Y1135539I1297J0D01*
G01X1497353Y1135556D01*
X1498160Y1136954D01*
X1498129Y1137041D01*
G02X1498056Y1137469I1225J429D01*
G37*
G36*
G01X1509156D02*
G02X1511752I1298J0D01*
G02X1510696Y1136194I-1298J0D01*
G01X1510606Y1136177D01*
X1509798Y1134779D01*
X1509829Y1134692D01*
G02X1509902Y1134264I-1225J-429D01*
G02X1507306I-1298J0D01*
G02X1508362Y1135539I1298J0D01*
G01X1508452Y1135556D01*
X1509260Y1136954D01*
X1509229Y1137041D01*
G02X1509156Y1137469I1225J429D01*
G37*
G36*
G01X360964Y1140973D02*
G02X363558I1297J0D01*
G02X362496Y1139697I-1298J0D01*
G01X362401Y1139679D01*
X361559Y1138084D01*
X361598Y1137995D01*
G02X361710Y1137469I-1186J-527D01*
G02X359114I-1298J0D01*
G02X360177Y1138745I1297J0D01*
G01X360272Y1138763D01*
X361114Y1140358D01*
X361075Y1140447D01*
G02X360964Y1140971I1186J525D01*
G01Y1140973D01*
G37*
G36*
G01X368364D02*
G02X370958I1297J0D01*
G02X369896Y1139697I-1298J0D01*
G01X369801Y1139679D01*
X368959Y1138084D01*
X368998Y1137995D01*
G02X369110Y1137469I-1186J-527D01*
G02X366514I-1298J0D01*
G02X367577Y1138745I1297J0D01*
G01X367672Y1138763D01*
X368514Y1140358D01*
X368475Y1140447D01*
G02X368364Y1140971I1186J525D01*
G01Y1140973D01*
G37*
G36*
G01X375764D02*
G02X378358I1297J0D01*
G02X377296Y1139697I-1298J0D01*
G01X377201Y1139679D01*
X376359Y1138084D01*
X376398Y1137995D01*
G02X376510Y1137469I-1186J-527D01*
G02X373914I-1298J0D01*
G02X374977Y1138745I1297J0D01*
G01X375072Y1138763D01*
X375914Y1140358D01*
X375875Y1140447D01*
G02X375764Y1140971I1186J525D01*
G01Y1140973D01*
G37*
G36*
G01X383164D02*
G02X385758I1297J0D01*
G02X384696Y1139697I-1298J0D01*
G01X384601Y1139679D01*
X383759Y1138084D01*
X383798Y1137995D01*
G02X383910Y1137469I-1186J-527D01*
G02X381314I-1298J0D01*
G02X382377Y1138745I1297J0D01*
G01X382472Y1138763D01*
X383314Y1140358D01*
X383275Y1140447D01*
G02X383164Y1140971I1186J525D01*
G01Y1140973D01*
G37*
G36*
G01X390564D02*
G02X393158I1297J0D01*
G02X392096Y1139697I-1298J0D01*
G01X392001Y1139679D01*
X391159Y1138084D01*
X391198Y1137995D01*
G02X391310Y1137469I-1186J-527D01*
G02X388714I-1298J0D01*
G02X389777Y1138745I1297J0D01*
G01X389872Y1138763D01*
X390714Y1140358D01*
X390675Y1140447D01*
G02X390564Y1140971I1186J525D01*
G01Y1140973D01*
G37*
G36*
G01X397964D02*
G02X400558I1297J0D01*
G02X399496Y1139697I-1298J0D01*
G01X399401Y1139679D01*
X398559Y1138084D01*
X398598Y1137995D01*
G02X398710Y1137469I-1186J-527D01*
G02X396114I-1298J0D01*
G02X397177Y1138745I1297J0D01*
G01X397272Y1138763D01*
X398114Y1140358D01*
X398075Y1140447D01*
G02X397964Y1140971I1186J525D01*
G01Y1140973D01*
G37*
G36*
G01X405364D02*
G02X407958I1297J0D01*
G02X406896Y1139697I-1298J0D01*
G01X406801Y1139679D01*
X405959Y1138084D01*
X405998Y1137995D01*
G02X406110Y1137469I-1186J-527D01*
G02X403514I-1298J0D01*
G02X404577Y1138745I1297J0D01*
G01X404672Y1138763D01*
X405514Y1140358D01*
X405475Y1140447D01*
G02X405364Y1140971I1186J525D01*
G01Y1140973D01*
G37*
G36*
G01X471964D02*
G02X474558I1297J0D01*
G02X474447Y1140448I-1297J0D01*
G01X474408Y1140359D01*
X475252Y1138763D01*
X475347Y1138745D01*
G02X476410Y1137469I-234J-1276D01*
G02X473814I-1298J0D01*
G02X473926Y1137994I1297J-2D01*
G01X473965Y1138083D01*
X473121Y1139679D01*
X473026Y1139697D01*
G02X471964Y1140973I236J1276D01*
G37*
G36*
G01X479364D02*
G02X481958I1297J0D01*
G02X481847Y1140448I-1297J0D01*
G01X481808Y1140359D01*
X482652Y1138763D01*
X482747Y1138745D01*
G02X483810Y1137469I-234J-1276D01*
G02X481214I-1298J0D01*
G02X481326Y1137994I1297J-2D01*
G01X481365Y1138083D01*
X480521Y1139679D01*
X480426Y1139697D01*
G02X479364Y1140973I236J1276D01*
G37*
G36*
G01X486764D02*
G02X489358I1297J0D01*
G02X489247Y1140448I-1297J0D01*
G01X489208Y1140359D01*
X490052Y1138763D01*
X490147Y1138745D01*
G02X491210Y1137469I-234J-1276D01*
G02X488614I-1298J0D01*
G02X488726Y1137994I1297J-2D01*
G01X488765Y1138083D01*
X487921Y1139679D01*
X487826Y1139697D01*
G02X486764Y1140973I236J1276D01*
G37*
G36*
G01X494164D02*
G02X496758I1297J0D01*
G02X496647Y1140448I-1297J0D01*
G01X496608Y1140359D01*
X497452Y1138763D01*
X497547Y1138745D01*
G02X498610Y1137469I-234J-1276D01*
G02X496014I-1298J0D01*
G02X496126Y1137994I1297J-2D01*
G01X496165Y1138083D01*
X495321Y1139679D01*
X495226Y1139697D01*
G02X494164Y1140973I236J1276D01*
G37*
G36*
G01X501564D02*
G02X504158I1297J0D01*
G02X504047Y1140448I-1297J0D01*
G01X504008Y1140359D01*
X504852Y1138763D01*
X504947Y1138745D01*
G02X506010Y1137469I-234J-1276D01*
G02X503414I-1298J0D01*
G02X503526Y1137994I1297J-2D01*
G01X503565Y1138083D01*
X502721Y1139679D01*
X502626Y1139697D01*
G02X501564Y1140973I236J1276D01*
G37*
G36*
G01X508964D02*
G02X511558I1297J0D01*
G02X511447Y1140448I-1297J0D01*
G01X511408Y1140359D01*
X512252Y1138763D01*
X512347Y1138745D01*
G02X513410Y1137469I-234J-1276D01*
G02X510814I-1298J0D01*
G02X510926Y1137994I1297J-2D01*
G01X510965Y1138083D01*
X510121Y1139679D01*
X510026Y1139697D01*
G02X508964Y1140973I236J1276D01*
G37*
G36*
G01X516364D02*
G02X518958I1297J0D01*
G02X518847Y1140448I-1297J0D01*
G01X518808Y1140359D01*
X519652Y1138763D01*
X519747Y1138745D01*
G02X520810Y1137469I-234J-1276D01*
G02X518214I-1298J0D01*
G02X518326Y1137994I1297J-2D01*
G01X518365Y1138083D01*
X517521Y1139679D01*
X517426Y1139697D01*
G02X516364Y1140973I236J1276D01*
G37*
G36*
G01X523764D02*
G02X526358I1297J0D01*
G02X526247Y1140448I-1297J0D01*
G01X526208Y1140359D01*
X527052Y1138763D01*
X527147Y1138745D01*
G02X528210Y1137469I-234J-1276D01*
G02X525614I-1298J0D01*
G02X525726Y1137994I1297J-2D01*
G01X525765Y1138083D01*
X524921Y1139679D01*
X524826Y1139697D01*
G02X523764Y1140973I236J1276D01*
G37*
G36*
G01X1337106D02*
G02X1339700I1297J0D01*
G02X1338638Y1139697I-1298J0D01*
G01X1338543Y1139679D01*
X1337701Y1138084D01*
X1337740Y1137995D01*
G02X1337852Y1137469I-1186J-527D01*
G02X1335256I-1298J0D01*
G02X1336319Y1138745I1297J0D01*
G01X1336414Y1138763D01*
X1337256Y1140358D01*
X1337217Y1140447D01*
G02X1337106Y1140971I1186J525D01*
G01Y1140973D01*
G37*
G36*
G01X1344506D02*
G02X1347100I1297J0D01*
G02X1346038Y1139697I-1298J0D01*
G01X1345943Y1139679D01*
X1345101Y1138084D01*
X1345140Y1137995D01*
G02X1345252Y1137469I-1186J-527D01*
G02X1342656I-1298J0D01*
G02X1343719Y1138745I1297J0D01*
G01X1343814Y1138763D01*
X1344656Y1140358D01*
X1344617Y1140447D01*
G02X1344506Y1140971I1186J525D01*
G01Y1140973D01*
G37*
G36*
G01X1351906D02*
G02X1354500I1297J0D01*
G02X1353438Y1139697I-1298J0D01*
G01X1353343Y1139679D01*
X1352501Y1138084D01*
X1352540Y1137995D01*
G02X1352652Y1137469I-1186J-527D01*
G02X1350056I-1298J0D01*
G02X1351119Y1138745I1297J0D01*
G01X1351214Y1138763D01*
X1352056Y1140358D01*
X1352017Y1140447D01*
G02X1351906Y1140971I1186J525D01*
G01Y1140973D01*
G37*
G36*
G01X1359306D02*
G02X1361900I1297J0D01*
G02X1360838Y1139697I-1298J0D01*
G01X1360743Y1139679D01*
X1359901Y1138084D01*
X1359940Y1137995D01*
G02X1360052Y1137469I-1186J-527D01*
G02X1357456I-1298J0D01*
G02X1358519Y1138745I1297J0D01*
G01X1358614Y1138763D01*
X1359456Y1140358D01*
X1359417Y1140447D01*
G02X1359306Y1140971I1186J525D01*
G01Y1140973D01*
G37*
G36*
G01X1366706D02*
G02X1369300I1297J0D01*
G02X1368238Y1139697I-1298J0D01*
G01X1368143Y1139679D01*
X1367301Y1138084D01*
X1367340Y1137995D01*
G02X1367452Y1137469I-1186J-527D01*
G02X1364856I-1298J0D01*
G02X1365919Y1138745I1297J0D01*
G01X1366014Y1138763D01*
X1366856Y1140358D01*
X1366817Y1140447D01*
G02X1366706Y1140971I1186J525D01*
G01Y1140973D01*
G37*
G36*
G01X1374106D02*
G02X1376700I1297J0D01*
G02X1375638Y1139697I-1298J0D01*
G01X1375543Y1139679D01*
X1374701Y1138084D01*
X1374740Y1137995D01*
G02X1374852Y1137469I-1186J-527D01*
G02X1372256I-1298J0D01*
G02X1373319Y1138745I1297J0D01*
G01X1373414Y1138763D01*
X1374256Y1140358D01*
X1374217Y1140447D01*
G02X1374106Y1140971I1186J525D01*
G01Y1140973D01*
G37*
G36*
G01X1381506D02*
G02X1384100I1297J0D01*
G02X1383038Y1139697I-1298J0D01*
G01X1382943Y1139679D01*
X1382101Y1138084D01*
X1382140Y1137995D01*
G02X1382252Y1137469I-1186J-527D01*
G02X1379656I-1298J0D01*
G02X1380719Y1138745I1297J0D01*
G01X1380814Y1138763D01*
X1381656Y1140358D01*
X1381617Y1140447D01*
G02X1381506Y1140971I1186J525D01*
G01Y1140973D01*
G37*
G36*
G01X1448106D02*
G02X1450700I1297J0D01*
G02X1450589Y1140448I-1297J0D01*
G01X1450550Y1140359D01*
X1451394Y1138763D01*
X1451489Y1138745D01*
G02X1452552Y1137469I-234J-1276D01*
G02X1449956I-1298J0D01*
G02X1450068Y1137994I1297J-2D01*
G01X1450107Y1138083D01*
X1449263Y1139679D01*
X1449168Y1139697D01*
G02X1448106Y1140973I236J1276D01*
G37*
G36*
G01X1455506D02*
G02X1458100I1297J0D01*
G02X1457989Y1140448I-1297J0D01*
G01X1457950Y1140359D01*
X1458794Y1138763D01*
X1458889Y1138745D01*
G02X1459952Y1137469I-234J-1276D01*
G02X1457356I-1298J0D01*
G02X1457468Y1137994I1297J-2D01*
G01X1457507Y1138083D01*
X1456663Y1139679D01*
X1456568Y1139697D01*
G02X1455506Y1140973I236J1276D01*
G37*
G36*
G01X1462906D02*
G02X1465500I1297J0D01*
G02X1465389Y1140448I-1297J0D01*
G01X1465350Y1140359D01*
X1466194Y1138763D01*
X1466289Y1138745D01*
G02X1467352Y1137469I-234J-1276D01*
G02X1464756I-1298J0D01*
G02X1464868Y1137994I1297J-2D01*
G01X1464907Y1138083D01*
X1464063Y1139679D01*
X1463968Y1139697D01*
G02X1462906Y1140973I236J1276D01*
G37*
G36*
G01X1470306D02*
G02X1472900I1297J0D01*
G02X1472789Y1140448I-1297J0D01*
G01X1472750Y1140359D01*
X1473594Y1138763D01*
X1473689Y1138745D01*
G02X1474752Y1137469I-234J-1276D01*
G02X1472156I-1298J0D01*
G02X1472268Y1137994I1297J-2D01*
G01X1472307Y1138083D01*
X1471463Y1139679D01*
X1471368Y1139697D01*
G02X1470306Y1140973I236J1276D01*
G37*
G36*
G01X1477706D02*
G02X1480300I1297J0D01*
G02X1480189Y1140448I-1297J0D01*
G01X1480150Y1140359D01*
X1480994Y1138763D01*
X1481089Y1138745D01*
G02X1482152Y1137469I-234J-1276D01*
G02X1479556I-1298J0D01*
G02X1479668Y1137994I1297J-2D01*
G01X1479707Y1138083D01*
X1478863Y1139679D01*
X1478768Y1139697D01*
G02X1477706Y1140973I236J1276D01*
G37*
G36*
G01X1485106D02*
G02X1487700I1297J0D01*
G02X1487589Y1140448I-1297J0D01*
G01X1487550Y1140359D01*
X1488394Y1138763D01*
X1488489Y1138745D01*
G02X1489552Y1137469I-234J-1276D01*
G02X1486956I-1298J0D01*
G02X1487068Y1137994I1297J-2D01*
G01X1487107Y1138083D01*
X1486263Y1139679D01*
X1486168Y1139697D01*
G02X1485106Y1140973I236J1276D01*
G37*
G36*
G01X1492506D02*
G02X1495100I1297J0D01*
G02X1494989Y1140448I-1297J0D01*
G01X1494950Y1140359D01*
X1495794Y1138763D01*
X1495889Y1138745D01*
G02X1496952Y1137469I-234J-1276D01*
G02X1494356I-1298J0D01*
G02X1494468Y1137994I1297J-2D01*
G01X1494507Y1138083D01*
X1493663Y1139679D01*
X1493568Y1139697D01*
G02X1492506Y1140973I236J1276D01*
G37*
G36*
G01X1499906D02*
G02X1502500I1297J0D01*
G02X1502389Y1140448I-1297J0D01*
G01X1502350Y1140359D01*
X1503194Y1138763D01*
X1503289Y1138745D01*
G02X1504352Y1137469I-234J-1276D01*
G02X1501756I-1298J0D01*
G02X1501868Y1137994I1297J-2D01*
G01X1501907Y1138083D01*
X1501063Y1139679D01*
X1500968Y1139697D01*
G02X1499906Y1140973I236J1276D01*
G37*
G36*
G01X1143020Y1540382D02*
G03X1143411Y1540758I-8J400D01*
G02X1145410Y1542642I1999J-119D01*
G02X1147412Y1540640I0J-2002D01*
G02X1145450Y1538638I-2002J0D01*
G03X1145059Y1538262I8J-400D01*
G02X1143060Y1536378I-1999J119D01*
G02X1141058Y1538380I0J2002D01*
G02X1143020Y1540382I2002J0D01*
G37*
G36*
G01X1162980Y1551449D02*
G03X1163635I328J229D01*
G02X1166917I1641J-1147D01*
G03X1167572I327J229D01*
G02X1169213Y1552304I1641J-1147D01*
G02Y1548298I0J-2003D01*
G02X1167572Y1549153I0J2002D01*
G03X1166917I-328J-229D01*
G02X1163635I-1641J1147D01*
G03X1162980I-327J-229D01*
G02X1159698I-1641J1147D01*
G03X1159043I-328J-229D01*
G02X1155761I-1641J1147D01*
G03X1155106I-328J-229D01*
G02X1151824I-1641J1147D01*
G03X1151169I-328J-229D01*
G02X1149528Y1548298I-1641J1147D01*
G02Y1552304I0J2003D01*
G02X1151169Y1551449I0J-2002D01*
G03X1151824I327J229D01*
G02X1155106I1641J-1147D01*
G03X1155761I328J229D01*
G02X1159043I1641J-1147D01*
G03X1159698I327J229D01*
G02X1162980I1641J-1147D01*
G37*
G36*
G01X1139652Y1550301D02*
Y1550302D01*
G02X1140157Y1551631I2002J0D01*
G02X1139688Y1552918I1533J1288D01*
G01Y1552920D01*
G02X1143692I2002J0D01*
G01Y1552919D01*
G02X1143187Y1551590I-2002J0D01*
G02X1143656Y1550303I-1533J-1288D01*
G01Y1550301D01*
G02X1139652I-2002J0D01*
G37*
G36*
G01X1101405Y1550386D02*
G03X1101083Y1550900I-382J119D01*
G02X1098098Y1554364I517J3464D01*
G02X1105102I3502J0D01*
G02X1104945Y1553324I-3502J-3D01*
G03X1105267Y1552810I382J-119D01*
G02X1108252Y1549346I-517J-3464D01*
G02X1101248I-3502J0D01*
G02X1101405Y1550386I3502J3D01*
G37*
G36*
G01X1143823Y1573272D02*
G03X1143551I-136J-147D01*
G02X1142188Y1572736I-1363J1466D01*
G01X1142187D01*
G02Y1576740I0J2002D01*
G01X1142188D01*
G02X1143551Y1576204I0J-2002D01*
G03X1143823I136J147D01*
G02X1145186Y1576740I1363J-1466D01*
G01X1145187D01*
G02Y1572736I0J-2002D01*
G01X1145186D01*
G02X1143823Y1573272I0J2002D01*
G37*
G36*
G01X1153823D02*
G03X1153551I-136J-147D01*
G02X1152188Y1572736I-1363J1466D01*
G01X1152187D01*
G02Y1576740I0J2002D01*
G01X1152188D01*
G02X1153551Y1576204I0J-2002D01*
G03X1153823I136J147D01*
G02X1155186Y1576740I1363J-1466D01*
G01X1155187D01*
G02Y1572736I0J-2002D01*
G01X1155186D01*
G02X1153823Y1573272I0J2002D01*
G37*
G36*
G01X1163231D02*
G03X1162959I-136J-147D01*
G02X1161596Y1572736I-1363J1466D01*
G01X1161595D01*
G02Y1576740I0J2002D01*
G01X1161596D01*
G02X1162959Y1576204I0J-2002D01*
G03X1163231I136J147D01*
G02X1164594Y1576740I1363J-1466D01*
G01X1164595D01*
G02Y1572736I0J-2002D01*
G01X1164594D01*
G02X1163231Y1573272I0J2002D01*
G37*
G36*
G01X1173231D02*
G03X1172959I-136J-147D01*
G02X1171596Y1572736I-1363J1466D01*
G01X1171595D01*
G02Y1576740I0J2002D01*
G01X1171596D01*
G02X1172959Y1576204I0J-2002D01*
G03X1173231I136J147D01*
G02X1174594Y1576740I1363J-1466D01*
G01X1174595D01*
G02Y1572736I0J-2002D01*
G01X1174594D01*
G02X1173231Y1573272I0J2002D01*
G37*
G36*
G01X1133823Y1581272D02*
G03X1133551I-136J-147D01*
G02X1132188Y1580736I-1363J1466D01*
G01X1132187D01*
G02Y1584740I0J2002D01*
G01X1132188D01*
G02X1133551Y1584204I0J-2002D01*
G03X1133823I136J147D01*
G02X1135186Y1584740I1363J-1466D01*
G01X1135187D01*
G02Y1580736I0J-2002D01*
G01X1135186D01*
G02X1133823Y1581272I0J2002D01*
G37*
G36*
G01X1143823D02*
G03X1143551I-136J-147D01*
G02X1142188Y1580736I-1363J1466D01*
G01X1142187D01*
G02Y1584740I0J2002D01*
G01X1142188D01*
G02X1143551Y1584204I0J-2002D01*
G03X1143823I136J147D01*
G02X1145186Y1584740I1363J-1466D01*
G01X1145187D01*
G02Y1580736I0J-2002D01*
G01X1145186D01*
G02X1143823Y1581272I0J2002D01*
G37*
G36*
G01X1153823D02*
G03X1153551I-136J-147D01*
G02X1152188Y1580736I-1363J1466D01*
G01X1152187D01*
G02Y1584740I0J2002D01*
G01X1152188D01*
G02X1153551Y1584204I0J-2002D01*
G03X1153823I136J147D01*
G02X1155186Y1584740I1363J-1466D01*
G01X1155187D01*
G02Y1580736I0J-2002D01*
G01X1155186D01*
G02X1153823Y1581272I0J2002D01*
G37*
G36*
G01X1163231D02*
G03X1162959I-136J-147D01*
G02X1161596Y1580736I-1363J1466D01*
G01X1161595D01*
G02Y1584740I0J2002D01*
G01X1161596D01*
G02X1162959Y1584204I0J-2002D01*
G03X1163231I136J147D01*
G02X1164594Y1584740I1363J-1466D01*
G01X1164595D01*
G02Y1580736I0J-2002D01*
G01X1164594D01*
G02X1163231Y1581272I0J2002D01*
G37*
G36*
G01X1173231D02*
G03X1172959I-136J-147D01*
G02X1171596Y1580736I-1363J1466D01*
G01X1171595D01*
G02Y1584740I0J2002D01*
G01X1171596D01*
G02X1172959Y1584204I0J-2002D01*
G03X1173231I136J147D01*
G02X1174594Y1584740I1363J-1466D01*
G01X1174595D01*
G02Y1580736I0J-2002D01*
G01X1174594D01*
G02X1173231Y1581272I0J2002D01*
G37*
G36*
G01X1133823Y1589272D02*
G03X1133551I-136J-147D01*
G02X1132188Y1588736I-1363J1466D01*
G01X1132187D01*
G02Y1592740I0J2002D01*
G01X1132188D01*
G02X1133551Y1592204I0J-2002D01*
G03X1133823I136J147D01*
G02X1135186Y1592740I1363J-1466D01*
G01X1135187D01*
G02Y1588736I0J-2002D01*
G01X1135186D01*
G02X1133823Y1589272I0J2002D01*
G37*
G36*
G01X1143823D02*
G03X1143551I-136J-147D01*
G02X1142188Y1588736I-1363J1466D01*
G01X1142187D01*
G02Y1592740I0J2002D01*
G01X1142188D01*
G02X1143551Y1592204I0J-2002D01*
G03X1143823I136J147D01*
G02X1145186Y1592740I1363J-1466D01*
G01X1145187D01*
G02Y1588736I0J-2002D01*
G01X1145186D01*
G02X1143823Y1589272I0J2002D01*
G37*
G36*
G01X1153823D02*
G03X1153551I-136J-147D01*
G02X1152188Y1588736I-1363J1466D01*
G01X1152187D01*
G02Y1592740I0J2002D01*
G01X1152188D01*
G02X1153551Y1592204I0J-2002D01*
G03X1153823I136J147D01*
G02X1155186Y1592740I1363J-1466D01*
G01X1155187D01*
G02Y1588736I0J-2002D01*
G01X1155186D01*
G02X1153823Y1589272I0J2002D01*
G37*
G36*
G01X1163231D02*
G03X1162959I-136J-147D01*
G02X1161596Y1588736I-1363J1466D01*
G01X1161595D01*
G02Y1592740I0J2002D01*
G01X1161596D01*
G02X1162959Y1592204I0J-2002D01*
G03X1163231I136J147D01*
G02X1164594Y1592740I1363J-1466D01*
G01X1164595D01*
G02Y1588736I0J-2002D01*
G01X1164594D01*
G02X1163231Y1589272I0J2002D01*
G37*
G36*
G01X1173231D02*
G03X1172959I-136J-147D01*
G02X1171596Y1588736I-1363J1466D01*
G01X1171595D01*
G02Y1592740I0J2002D01*
G01X1171596D01*
G02X1172959Y1592204I0J-2002D01*
G03X1173231I136J147D01*
G02X1174594Y1592740I1363J-1466D01*
G01X1174595D01*
G02Y1588736I0J-2002D01*
G01X1174594D01*
G02X1173231Y1589272I0J2002D01*
G37*
G36*
G01X810826Y1715542D02*
X816058Y1720774D01*
G02X816942Y1721140I884J-885D01*
G01X901218D01*
G02X902102Y1720774I0J-1251D01*
G01X909144Y1713732D01*
G02X909510Y1712848I-885J-884D01*
G01Y1667648D01*
X918518Y1658640D01*
X1064818D01*
G02X1065702Y1658274I0J-1251D01*
G01X1085876Y1638100D01*
X1102078D01*
G02X1102962Y1637734I0J-1251D01*
G01X1105274Y1635422D01*
G02X1105640Y1634538I-885J-884D01*
G01Y1606962D01*
G02X1105274Y1606078I-1251J0D01*
G01X1103642Y1604446D01*
G02X1102758Y1604080I-884J885D01*
G01X1081112D01*
X1080194Y1603162D01*
Y1602842D01*
X1081707Y1601328D01*
G02X1082362Y1600268I-1907J-1911D01*
G03X1083025Y1600111I380J126D01*
G01X1083178Y1600264D01*
G02X1084062Y1600630I884J-885D01*
G01X1095052D01*
G02X1095199Y1600621I-3J-1250D01*
G01X1095210Y1600620D01*
X1106448D01*
G02X1107332Y1600254I0J-1251D01*
G01X1108636Y1598950D01*
G02X1109002Y1598066I-885J-884D01*
G01Y1565342D01*
G02X1108636Y1564458I-1251J0D01*
G01X1106544Y1562366D01*
G02X1105660Y1562000I-884J885D01*
G01X1084682D01*
G02X1083798Y1562366I0J1251D01*
G01X1082380Y1563784D01*
G03X1081801Y1563770I-283J-283D01*
G02X1081707Y1563672I-1995J1819D01*
G01X1080842Y1562807D01*
X1080645Y1562602D01*
G02X1080216Y1562313I-898J870D01*
G01X1079671Y1562092D01*
G02X1079201Y1562000I-471J1158D01*
G01X945581D01*
G02X943672Y1562793I2J2700D01*
G01X941807Y1564658D01*
X941602Y1564855D01*
G02X941313Y1565284I870J898D01*
G01X941092Y1565829D01*
G02X941000Y1566299I1158J471D01*
G01Y1599900D01*
X940822Y1600078D01*
X940214D01*
X936892Y1596756D01*
G02X936008Y1596390I-884J885D01*
G01X927766D01*
X923290Y1591914D01*
Y1578352D01*
G02X922924Y1577468I-1251J0D01*
G01X922132Y1576676D01*
G02X921248Y1576310I-884J885D01*
G01X906872D01*
G02X905988Y1576676I0J1251D01*
G01X905196Y1577468D01*
G02X904830Y1578352I885J884D01*
G01Y1591896D01*
X904388Y1592338D01*
G02X904022Y1593222I885J884D01*
G01Y1603382D01*
X896864Y1610540D01*
X889128D01*
X882022Y1603434D01*
Y1593152D01*
G02X881656Y1592268I-1251J0D01*
G01X881310Y1591922D01*
Y1578402D01*
G02X880944Y1577518I-1251J0D01*
G01X880112Y1576686D01*
G02X879228Y1576320I-884J885D01*
G01X864892D01*
G02X864008Y1576686I0J1251D01*
G01X863206Y1577488D01*
G02X862840Y1578372I885J884D01*
G01Y1591966D01*
X862488Y1592318D01*
G02X862122Y1593202I885J884D01*
G01Y1602864D01*
X854886Y1610100D01*
X846166D01*
X839980Y1603914D01*
Y1593162D01*
G02X839614Y1592278I-1251J0D01*
G01X839280Y1591944D01*
Y1578322D01*
G02X838914Y1577438I-1251J0D01*
G01X838162Y1576686D01*
G02X837278Y1576320I-884J885D01*
G01X822872D01*
G02X821988Y1576686I0J1251D01*
G01X821236Y1577438D01*
G02X820870Y1578322I885J884D01*
G01Y1591816D01*
X820488Y1592198D01*
G02X820122Y1593082I885J884D01*
G01Y1603042D01*
X812654Y1610510D01*
X804298D01*
X798022Y1604234D01*
Y1593104D01*
G02X797656Y1592220I-1251J0D01*
G01X797290Y1591854D01*
Y1578352D01*
G02X796924Y1577468I-1251J0D01*
G01X796142Y1576686D01*
G02X795258Y1576320I-884J885D01*
G01X780872D01*
G02X779988Y1576686I0J1251D01*
G01X779236Y1577438D01*
G02X778870Y1578322I885J884D01*
G01Y1591954D01*
X774954Y1595870D01*
X751976D01*
X751087Y1594981D01*
X751101Y1594883D01*
G02X751114Y1594683I-1489J-197D01*
G02X749612Y1593181I-1502J0D01*
G02X749412Y1593194I-3J1502D01*
G01X749314Y1593208D01*
X748022Y1591915D01*
Y1590733D01*
G02X747656Y1589849I-1251J0D01*
G01X746824Y1589017D01*
G02X745940Y1588651I-884J885D01*
G01X745090D01*
Y1578308D01*
G02X744730Y1577431I-1250J1D01*
G01X743935Y1576624D01*
G02X743045Y1576251I-891J877D01*
G01X727872D01*
G02X726622Y1577501I0J1250D01*
G01Y1600869D01*
G02X726988Y1601753I1251J0D01*
G01X727560Y1602325D01*
X727554Y1602415D01*
G02X727550Y1602518I1498J110D01*
G02X727922Y1603507I1501J0D01*
G01Y1606915D01*
X727488Y1607349D01*
G02X727122Y1608233I885J884D01*
G01Y1626712D01*
G02X727488Y1627596I1251J0D01*
G01X757976Y1658084D01*
G02X758860Y1658450I884J-885D01*
G01X776714D01*
X810460Y1692196D01*
Y1714658D01*
G02X810826Y1715542I1251J0D01*
G37*
G36*
G01X1411037Y1711457D02*
G03X1411142Y1712134I-151J370D01*
G02X1421732I5295J6330D01*
G03X1421837Y1711457I256J-307D01*
G02X1430690Y1698267I-5399J-13190D01*
G02X1402184I-14253J0D01*
G02X1411037Y1711457I14252J0D01*
G37*
G36*
G01X435643Y1711458D02*
G03X435748Y1712135I-151J370D01*
G02X446338I5295J6330D01*
G03X446443Y1711458I256J-307D01*
G02X455296Y1698268I-5399J-13190D01*
G02X426790I-14253J0D01*
G02X435643Y1711458I14252J0D01*
G37*
G54D105*
X1137717Y1558020D03*
G54D102*
X1290005Y293768D03*
G54D98*
X1455787Y1421784D03*
X1710550Y691327D03*
X93547Y692260D03*
X479646Y1421784D03*
G54D103*
X1175215Y1532913D03*
X1131715D03*
G54D83*
X1307572Y-26511D03*
X1040152Y-16511D03*
X1015152D03*
X1307572Y13489D03*
X1282572Y23489D03*
X1307572D03*
X1282572Y13489D03*
X1040152Y23489D03*
Y13489D03*
X973180Y-6500D03*
X998180D03*
X1015152Y13489D03*
X1282572Y-16511D03*
X973180Y-26500D03*
X998180D03*
Y-16500D03*
X1015152Y23489D03*
X1307572Y-16511D03*
X973180Y-16500D03*
X1474931Y23489D03*
X1499931D03*
X705760Y-26500D03*
X730760D03*
X705760Y-6500D03*
Y-16500D03*
X730760D03*
Y-6500D03*
X1474931Y13489D03*
X998180Y3500D03*
X973180D03*
X1499931Y13489D03*
X998180Y13500D03*
Y23500D03*
X973180D03*
Y13500D03*
X1499931Y-16511D03*
X1474931D03*
X1324471Y23489D03*
X1349471D03*
X822720Y3500D03*
X847720D03*
X822720Y23500D03*
Y13500D03*
X847720D03*
Y23500D03*
X1324471Y-16511D03*
X1349471D03*
X1324471Y13489D03*
X1349471D03*
X1307572Y-36511D03*
X1282572D03*
Y-26511D03*
X1307572Y-6511D03*
Y3489D03*
X1282572D03*
Y-6511D03*
X1015152Y-36511D03*
Y-26511D03*
X1040152D03*
Y-36511D03*
X1015152Y3489D03*
Y-6511D03*
X1040152D03*
Y3489D03*
X1499931Y-26511D03*
Y-36511D03*
X1474931D03*
Y-26511D03*
X1499931Y-6511D03*
Y3489D03*
X1474931D03*
Y-6511D03*
X1324471Y-36511D03*
Y-26511D03*
X1349471D03*
Y-36511D03*
X1324471Y3489D03*
Y-6511D03*
X1349471D03*
Y3489D03*
G54D90*
X70472Y173228D03*
Y236220D03*
G54D94*
X1565236Y184783D03*
Y264035D03*
G54D95*
X929331Y160413D03*
X922441Y237697D03*
X1534712Y20354D03*
X1787330Y24291D03*
X505185Y41142D03*
X757803Y45079D03*
X312921Y24291D03*
G54D93*
X676508Y224606D03*
G54D92*
Y145866D03*
G54D89*
X1829725Y130315D03*
G54D85*
X791280Y1704890D03*
X1066280D03*
G54D100*
X1405118Y112008D03*
G54D82*
X1341752Y-31511D03*
Y-21511D03*
Y-11511D03*
Y-1511D03*
X1482650Y-31511D03*
Y-21511D03*
Y-11511D03*
Y-1511D03*
X90998Y1517237D03*
X78120Y1517136D03*
X99750Y1563678D03*
X75922Y1560674D03*
X404030Y1593690D03*
X957156Y228863D03*
X899830Y973184D03*
X1380522Y261936D03*
X1388754Y255503D03*
X1380638Y247394D03*
X1386630Y240351D03*
X397406Y1634842D03*
X1031950Y385471D03*
X736710Y605542D03*
X527310Y96447D03*
X414406Y1626692D03*
X460910Y1627472D03*
X64410Y1600802D03*
X1340420Y540122D03*
X704770Y204921D03*
X896060Y482922D03*
X716698Y210721D03*
X704770Y216732D03*
X895340Y499582D03*
X907470Y213680D03*
X902350Y220768D03*
X953970Y206575D03*
X716698Y198887D03*
X704770Y193110D03*
Y181299D03*
X947496Y227835D03*
X705800Y169488D03*
X947496Y213697D03*
X907470Y227854D03*
X941050Y530552D03*
X968286Y482241D03*
X716698Y175387D03*
X902350Y206594D03*
X944032Y435931D03*
X716698Y187387D03*
X944250Y196189D03*
X954420Y512952D03*
Y498852D03*
G54D101*
X1247638Y269488D03*
G54D97*
X1550708Y991220D03*
X525275Y1171319D03*
X1332204D03*
X1326240Y811122D03*
X1501417Y1171319D03*
X1507381Y811122D03*
X1282913Y991220D03*
X306771D03*
X574566D03*
X350098Y811122D03*
X531240D03*
X356062Y1171319D03*
G54D81*
X723041Y-11500D03*
Y-21500D03*
X840001Y8500D03*
Y18500D03*
X980899Y-21500D03*
Y-11500D03*
Y8500D03*
Y18500D03*
X1032433Y-31511D03*
Y-21511D03*
Y-11511D03*
Y-1511D03*
X1290291Y-31511D03*
Y-21511D03*
Y-11511D03*
Y-1511D03*
X62813Y414300D03*
X47619Y417205D03*
X1386273Y270370D03*
X615573Y178034D03*
X628195Y174214D03*
X1282645Y253971D03*
X941059Y426211D03*
X901829Y514430D03*
X889439Y491299D03*
X1407029Y154432D03*
X922879Y530276D03*
X946727Y506252D03*
G54D96*
X1819208Y1420330D03*
X38346D03*
G54D84*
X19685Y-29134D03*
X1837795D03*
X1808192Y1569255D03*
X41870Y1511291D03*
X1812980Y502472D03*
X49280Y337402D03*
X441043Y1672205D03*
X1416437Y1672204D03*
X2081889Y1803261D03*
Y-29134D03*
G54D91*
X1057658Y204724D03*
X805690D03*
G54D99*
X763602Y605413D03*
X1739744D03*
X1094075Y605378D03*
X117933D03*
G54D104*
X841240Y1420330D03*
X1016240D03*
G54D88*
X1680327Y277236D03*
X1153555Y277208D03*
X704185Y277236D03*
X177413Y277208D03*
G54D86*
X177311Y1657953D03*
G54D87*
X1680232D03*
%LPC*%
G75*
G36*
G01X817460Y1718640D02*
X900700D01*
X907010Y1712330D01*
Y1667130D01*
G03X907376Y1666246I1251J0D01*
G01X917116Y1656506D01*
G03X918000Y1656140I884J885D01*
G01X1064300D01*
X1084474Y1635966D01*
G03X1085358Y1635600I884J885D01*
G01X1101560D01*
X1103140Y1634020D01*
Y1607480D01*
X1102240Y1606580D01*
X943698D01*
G03X942814Y1606214I0J-1251D01*
G01X935490Y1598890D01*
X927248D01*
G03X926364Y1598524I0J-1251D01*
G01X921156Y1593316D01*
G03X920790Y1592432I885J-884D01*
G01Y1578870D01*
X920730Y1578810D01*
X907390D01*
X907330Y1578870D01*
Y1592414D01*
G03X906964Y1593298I-1251J0D01*
G01X906522Y1593740D01*
Y1603900D01*
G03X906156Y1604784I-1251J0D01*
G01X898266Y1612674D01*
G03X897382Y1613040I-884J-885D01*
G01X888610D01*
G03X887726Y1612674I0J-1251D01*
G01X879888Y1604836D01*
G03X879522Y1603952I885J-884D01*
G01Y1593670D01*
X879176Y1593324D01*
G03X878810Y1592440I885J-884D01*
G01Y1578920D01*
X878710Y1578820D01*
X865410D01*
X865340Y1578890D01*
Y1592484D01*
G03X864974Y1593368I-1251J0D01*
G01X864622Y1593720D01*
Y1603382D01*
G03X864256Y1604266I-1251J0D01*
G01X856288Y1612234D01*
G03X855404Y1612600I-884J-885D01*
G01X845648D01*
G03X844764Y1612234I0J-1251D01*
G01X837846Y1605316D01*
G03X837480Y1604432I885J-884D01*
G01Y1593680D01*
X837146Y1593346D01*
G03X836780Y1592462I885J-884D01*
G01Y1578840D01*
X836760Y1578820D01*
X823390D01*
X823370Y1578840D01*
Y1592334D01*
G03X823004Y1593218I-1251J0D01*
G01X822622Y1593600D01*
Y1603560D01*
G03X822256Y1604444I-1251J0D01*
G01X814056Y1612644D01*
G03X813172Y1613010I-884J-885D01*
G01X803780D01*
G03X802896Y1612644I0J-1251D01*
G01X795888Y1605636D01*
G03X795522Y1604752I885J-884D01*
G01Y1593622D01*
X795156Y1593256D01*
G03X794790Y1592372I885J-884D01*
G01Y1578870D01*
X794740Y1578820D01*
X781390D01*
X781370Y1578840D01*
Y1592472D01*
G03X781004Y1593356I-1251J0D01*
G01X776356Y1598004D01*
G03X775472Y1598370I-884J-885D01*
G01X751458D01*
G03X750574Y1598004I0J-1251D01*
G01X745888Y1593317D01*
G03X745522Y1592433I885J-884D01*
G01Y1591251D01*
X745422Y1591151D01*
X744540D01*
G03X743656Y1590785I0J-1251D01*
G01X742956Y1590085D01*
G03X742590Y1589201I885J-884D01*
G01Y1578820D01*
X742522Y1578751D01*
X729122D01*
Y1600351D01*
X730056Y1601285D01*
G03X730360Y1601779I-884J885D01*
G03X730554Y1602518I-1308J738D01*
G03X730438Y1603098I-1502J1D01*
G01X730422Y1603135D01*
Y1607433D01*
G03X730056Y1608317I-1251J0D01*
G01X729622Y1608751D01*
Y1626194D01*
X759378Y1655950D01*
X777232D01*
G03X778116Y1656316I0J1251D01*
G01X812594Y1690794D01*
G03X812960Y1691678I-885J884D01*
G01Y1714140D01*
X817460Y1718640D01*
G37*
G36*
G01X1077918Y1601500D02*
G02X1078058Y1601442I-1J-200D01*
G01X1079940Y1599560D01*
G03X1080000Y1599504I882J885D01*
G01Y1565496D01*
G03X1079940Y1565440I822J-941D01*
G01X1079067Y1564567D01*
G03X1079004Y1564500I879J-889D01*
G01X945496D01*
G03X945440Y1564560I-941J-822D01*
G01X943567Y1566433D01*
X943566Y1566434D01*
G03X943500Y1566496I-888J-880D01*
G01Y1600504D01*
G03X943560Y1600560I-822J941D01*
G01X944440Y1601440D01*
G03X944496Y1601500I-885J882D01*
G01X1077918D01*
G37*
G36*
G01X1105930Y1598120D02*
X1106502Y1597548D01*
Y1565860D01*
X1105142Y1564500D01*
X1085200D01*
X1084200Y1565500D01*
Y1597750D01*
X1084580Y1598130D01*
X1094904D01*
X1094915Y1598129D01*
G03X1095062Y1598120I150J1241D01*
G01X1105930D01*
G37*
%LPD*%
G75*
G54D15*
X16925Y203366D03*
X17061Y196368D03*
X24720Y216362D03*
Y232362D03*
Y224362D03*
Y240362D03*
X16420Y420662D03*
X26500Y672862D03*
Y675862D03*
X27300Y764200D03*
X27520Y1245162D03*
X33500Y200862D03*
X33670Y192862D03*
Y208362D03*
X30795Y213358D03*
X33670Y232362D03*
X42500Y224409D03*
X30795Y227366D03*
X33670Y240362D03*
X40000Y298707D03*
X36000Y295952D03*
X40000Y293392D03*
X33105Y304972D03*
X35740Y363337D03*
X39320Y392269D03*
X40940Y387302D03*
X43020Y382942D03*
X41933Y395652D03*
X45960Y428806D03*
X38220Y589862D03*
Y592862D03*
X33020Y595232D03*
X32720Y598402D03*
X34790Y666595D03*
X31390D03*
X38470Y688122D03*
Y683122D03*
Y680622D03*
Y685622D03*
Y693122D03*
Y690622D03*
Y695622D03*
X34899Y711400D03*
X45700Y724100D03*
X45800Y726874D03*
X43841Y1248688D03*
X44833Y1656759D03*
X48269Y1672771D03*
X62020Y295952D03*
X62731Y305426D03*
X59322Y360702D03*
X51114Y360862D03*
X53406Y402862D03*
X49360Y428806D03*
X61171D03*
X47619Y418655D03*
X47618Y415613D03*
X48400Y586000D03*
X57595Y603476D03*
X59500Y738700D03*
X56777Y1314165D03*
X56799Y1520094D03*
Y1536094D03*
Y1540094D03*
Y1560094D03*
X59833Y1604359D03*
X54333Y1613359D03*
X50333D03*
X54478Y1663669D03*
X54535Y1658447D03*
X57833Y1671809D03*
X53333Y1671862D03*
X65000Y1681900D03*
X58325Y1679275D03*
X78269Y26474D03*
X74869D03*
X65937Y28403D03*
Y48720D03*
X77165Y278798D03*
Y295798D03*
Y286262D03*
Y303262D03*
X63429Y360702D03*
X67681D03*
X77220Y379022D03*
Y381522D03*
X68020Y395222D03*
X75516Y420319D03*
Y424319D03*
X64571Y428806D03*
X63540Y438802D03*
X72610Y441262D03*
Y444762D03*
X72981Y466385D03*
X77000Y485362D03*
X74550Y487812D03*
X80300Y641862D03*
X80241Y659011D03*
X80123Y664031D03*
X80135Y667933D03*
X74559Y667814D03*
X78080Y701832D03*
X63930Y739300D03*
X73759Y754726D03*
X68315Y765664D03*
X73759Y759246D03*
X72485Y1304152D03*
X75485D03*
X78485D03*
X72485Y1307152D03*
X75485D03*
X69485Y1304152D03*
Y1307152D03*
X65600Y1318588D03*
X65240Y1326068D03*
X75485Y1316152D03*
X72485Y1313152D03*
Y1310152D03*
X75485Y1313152D03*
Y1310152D03*
X69485D03*
X69809Y1333918D03*
Y1331418D03*
Y1336418D03*
X72809Y1333918D03*
Y1331418D03*
Y1336418D03*
X75809Y1333918D03*
Y1331418D03*
Y1336418D03*
X72909Y1339938D03*
X79009Y1340238D03*
X75909Y1339938D03*
X73027Y1347925D03*
X73059Y1345138D03*
X72987Y1342535D03*
X75909Y1342438D03*
X79009Y1342738D03*
Y1345238D03*
X78977Y1348025D03*
X75859Y1348138D03*
Y1345138D03*
X76369Y1507456D03*
X76680Y1530482D03*
X72774Y1546519D03*
X75922Y1558974D03*
Y1562374D03*
X77618Y1572504D03*
X74218D03*
X77040Y1601102D03*
X65120Y1609909D03*
X65520Y1615972D03*
X74100Y1613300D03*
X77833Y1678902D03*
X73833Y1674252D03*
X69833Y1678582D03*
X85374Y19538D03*
X81974D03*
X92442Y26474D03*
X89042D03*
X87620Y285321D03*
X87845Y278798D03*
Y295798D03*
X87820Y302821D03*
X87520Y395865D03*
Y391391D03*
Y382219D03*
X85826Y428319D03*
X84410Y438519D03*
X83320Y445212D03*
X94439Y450081D03*
X81505Y447377D03*
X79400Y482862D03*
X91027Y643276D03*
X89859Y628246D03*
X86459D03*
X82961Y657111D03*
X95725Y654540D03*
X95860Y659622D03*
X83165Y652564D03*
X91078Y649584D03*
X83208Y646436D03*
X83250Y665428D03*
X84470Y668702D03*
X86433Y688160D03*
X81285Y689804D03*
X84035Y697604D03*
X93547Y692260D03*
X83004Y705141D03*
X97295Y699786D03*
X85095Y722164D03*
X95849Y716358D03*
X91610Y721414D03*
X82357Y737803D03*
X84623Y741249D03*
X81966Y759246D03*
X85877Y759275D03*
X93485Y1304152D03*
X87485D03*
X90485D03*
X93485Y1307152D03*
X84485Y1304152D03*
X81485D03*
X93485Y1318152D03*
Y1315652D03*
Y1310152D03*
Y1313152D03*
X94209Y1337738D03*
X81809Y1340238D03*
X84809D03*
X87809D03*
X90809D03*
X94209D03*
X84809Y1345238D03*
X81809Y1342738D03*
X84809D03*
X81809Y1348238D03*
Y1345238D03*
X84809Y1348238D03*
X87809D03*
Y1345238D03*
Y1342738D03*
X94209D03*
Y1348238D03*
Y1345238D03*
X90809Y1348238D03*
Y1345238D03*
Y1342738D03*
X88520Y1484482D03*
Y1491482D03*
Y1487982D03*
Y1494982D03*
X89264Y1507611D03*
X92664D03*
X79769Y1507456D03*
X87500Y1567069D03*
X91500D03*
X90713Y1581852D03*
Y1597867D03*
X81008Y1589872D03*
X90788Y1615821D03*
Y1601867D03*
X81900Y1613300D03*
X85800D03*
X90698Y1630362D03*
X90788Y1619821D03*
X90698Y1642362D03*
X90407Y1656672D03*
X88333Y1661334D03*
X81833Y1674526D03*
X86245Y1694362D03*
X96420Y1693803D03*
X86030Y1683092D03*
X99547Y19538D03*
X110320D03*
X96147D03*
X106615Y26474D03*
X103215D03*
X113490Y216596D03*
X113400Y232128D03*
X110937Y285495D03*
Y302854D03*
X107200Y393562D03*
X107301Y388071D03*
X107419Y487807D03*
X104875Y490980D03*
X102384Y505374D03*
X112480Y507792D03*
X110689Y498271D03*
X110464Y505374D03*
X101983Y518100D03*
X99880Y526300D03*
X110060Y515279D03*
X99773Y515606D03*
X105587Y520727D03*
X106110Y633732D03*
X107489Y630917D03*
X110374Y630879D03*
X102269Y634466D03*
X107045Y661917D03*
X99021Y663732D03*
X103397Y667272D03*
X102120Y688650D03*
X102060Y692100D03*
X102420Y697262D03*
X96626Y736187D03*
X110527Y758869D03*
X108465Y1304292D03*
Y1307292D03*
X105475Y1304222D03*
Y1307222D03*
X102485Y1304152D03*
X99485D03*
X96485D03*
X102485Y1307152D03*
X99485D03*
X96485D03*
X108465Y1318292D03*
Y1310292D03*
Y1313292D03*
Y1315792D03*
X105475Y1318222D03*
Y1310222D03*
Y1313222D03*
Y1315722D03*
X99485Y1318152D03*
X96485D03*
Y1315652D03*
Y1310152D03*
Y1313152D03*
X99485Y1310152D03*
Y1313152D03*
Y1315652D03*
X102485Y1318152D03*
Y1310152D03*
Y1313152D03*
Y1315652D03*
X96809Y1340238D03*
Y1345238D03*
Y1348238D03*
Y1342738D03*
X112270Y1518907D03*
X99274Y1529169D03*
X96570Y1546187D03*
X99750Y1565378D03*
Y1561978D03*
X103902Y1584337D03*
X102251Y1576504D03*
X105651D03*
X104318Y1589352D03*
X100620Y1596367D03*
X101500Y1604400D03*
X100020Y1615821D03*
X98738Y1605867D03*
X104400Y1632385D03*
X104430Y1628012D03*
X104318Y1637862D03*
X99600Y1668332D03*
X99645Y1663217D03*
X99980Y1687921D03*
Y1698921D03*
X113720Y19538D03*
X127894D03*
X124494D03*
X120789Y26474D03*
X117389D03*
X115850Y186362D03*
X122000Y207362D03*
X116920Y207462D03*
X118920Y278875D03*
X119220Y306236D03*
X119920Y379362D03*
X119457Y392071D03*
Y388071D03*
X125070Y486736D03*
X125013Y491829D03*
X124124Y495883D03*
X116171Y485041D03*
X112483Y510637D03*
X116411Y497707D03*
X118652Y528860D03*
X129762Y531942D03*
X115793Y528188D03*
X112393D03*
X111920Y632922D03*
X114540Y633032D03*
X117750Y633232D03*
X120440Y633347D03*
X121400Y638062D03*
X125890Y644163D03*
X122329Y654660D03*
X122280Y651934D03*
X124431Y649570D03*
X122575Y671930D03*
X118019Y661371D03*
X124737Y735726D03*
X118737D03*
X121737D03*
Y738726D03*
X118737D03*
X124737D03*
X123220Y1324662D03*
X120220D03*
X112749Y1532594D03*
Y1528594D03*
Y1552594D03*
Y1556594D03*
X117707Y1553759D03*
X125033Y1589352D03*
X116798D03*
X123230Y1597350D03*
X119500Y1622380D03*
X124795Y1681846D03*
X128195Y1674362D03*
X114645Y1698862D03*
X117220Y1683437D03*
X127195Y1696362D03*
Y1700362D03*
Y1704362D03*
X125082Y1727092D03*
X123394Y1723472D03*
X117426Y1726622D03*
X125720Y1719262D03*
X141520Y181462D03*
X139720Y179162D03*
X143470Y184012D03*
X133590Y212382D03*
X129394Y278875D03*
X129375Y274800D03*
X129394Y306236D03*
X135220Y397071D03*
X132490Y420062D03*
X138042Y480238D03*
X132833D03*
X136982Y497090D03*
X131737Y496295D03*
X135006Y487753D03*
X131295Y487822D03*
X141325Y503806D03*
X141462Y507600D03*
X141329Y510487D03*
X141220Y498810D03*
X138878Y512550D03*
X138408Y507366D03*
X139153Y516453D03*
X133160Y532002D03*
X132600Y537072D03*
Y540472D03*
X133467Y634531D03*
X131740Y640103D03*
X131600Y646861D03*
X131330Y665740D03*
X142960Y690807D03*
X140460D03*
X142754Y698811D03*
X140254D03*
X142778Y706835D03*
X140278D03*
X140326Y721660D03*
X142826D03*
X140142Y1392545D03*
Y1396275D03*
X129627Y1556360D03*
X129586Y1553759D03*
X129813Y1604367D03*
X130533Y1622321D03*
X129533Y1637862D03*
X137420Y1708362D03*
X144520Y1717562D03*
X141642Y1717592D03*
X134557Y1722778D03*
X137852Y1726572D03*
X160360Y19538D03*
X156655Y26474D03*
X153255D03*
X147924Y28258D03*
X148784Y48720D03*
X145720Y186462D03*
Y202862D03*
Y206362D03*
X156670Y344542D03*
X159170D03*
X154220Y375682D03*
X158110Y376172D03*
X160090Y391170D03*
Y397470D03*
X152826Y439397D03*
Y434362D03*
X156306Y449045D03*
X153360Y449112D03*
X149557Y494353D03*
X150113Y488487D03*
X161267Y503143D03*
X149472Y506810D03*
X160000Y510052D03*
X152470Y495383D03*
X151378Y526924D03*
X149512Y514810D03*
X150800Y512021D03*
X153737Y514893D03*
X149504Y519881D03*
X154647Y521783D03*
X150877Y757969D03*
X151277Y1339183D03*
X153877D03*
X156477D03*
X156417Y1336343D03*
X151217Y1336393D03*
X153817D03*
X156417Y1333843D03*
X151217Y1333893D03*
X153817D03*
X151277Y1346883D03*
X153877D03*
X151277Y1349383D03*
X153877D03*
X156477Y1346883D03*
Y1349383D03*
Y1344383D03*
X151277D03*
X153877D03*
X156477Y1341883D03*
X151277D03*
X153877D03*
X147307Y1404745D03*
X149568Y1395145D03*
Y1397695D03*
X152684Y1403451D03*
X157490Y1421454D03*
X154990D03*
X159858Y1409361D03*
X155858Y1406669D03*
Y1409390D03*
X157530Y1432124D03*
X155030D03*
X157530Y1424124D03*
X155030D03*
X157530Y1429124D03*
X155030Y1426624D03*
Y1429124D03*
X157530Y1426624D03*
Y1435124D03*
X155030D03*
X157530Y1437754D03*
X155030D03*
X146390Y1504240D03*
X145538Y1517374D03*
X148938D03*
X153600Y1505600D03*
X147067Y1545985D03*
X157441Y1581932D03*
X146312Y1569525D03*
X149712D03*
X152026Y1614138D03*
X158335Y1614452D03*
X155180Y1619872D03*
X156070Y1695702D03*
X145745Y1712362D03*
X161310Y1708022D03*
X148145Y1701862D03*
X155145Y1713517D03*
X163760Y19538D03*
X174533D03*
X170828Y26474D03*
X167428D03*
X164830Y344542D03*
X161670D03*
X173275Y393497D03*
X164000Y415362D03*
X163926Y425383D03*
X164000Y420362D03*
X172507Y417205D03*
X163926Y430883D03*
Y443319D03*
Y439397D03*
Y435383D03*
X178546Y453806D03*
X172632Y454095D03*
X165176Y500782D03*
X176393Y575189D03*
X173793D03*
X176393Y572689D03*
X173793D03*
X171293D03*
Y575189D03*
X173793Y577790D03*
X171293D03*
X176393D03*
X176651Y596883D03*
Y594163D03*
X173878Y597027D03*
Y594307D03*
X176651Y599603D03*
X173878Y599747D03*
X161126Y721660D03*
X161078Y706835D03*
X163626Y721660D03*
X163578Y706835D03*
X170877Y1333783D03*
Y1336383D03*
X176077Y1333783D03*
X173477D03*
X176077Y1336383D03*
X173477D03*
X170907Y1339233D03*
X176107D03*
X173507D03*
X170877Y1341883D03*
X176077D03*
X173477D03*
Y1349383D03*
Y1346883D03*
Y1344383D03*
X176077D03*
Y1346883D03*
Y1349383D03*
X170877D03*
Y1346883D03*
Y1344383D03*
X176358Y1403669D03*
X176258Y1400669D03*
X173892Y1402749D03*
Y1405649D03*
X170922Y1399255D03*
X166262D03*
X173252Y1400005D03*
X168592D03*
X160490Y1421454D03*
X164000Y1408862D03*
X162257Y1406594D03*
X160530Y1432124D03*
Y1424124D03*
Y1429124D03*
Y1426624D03*
Y1435124D03*
Y1437754D03*
X165500Y1440362D03*
X173727Y1452134D03*
Y1448734D03*
X170570Y1509250D03*
X164710Y1518014D03*
X168110D03*
X173331Y1579399D03*
X167266Y1569968D03*
X170666D03*
X172099Y1588141D03*
X164920Y1712017D03*
X163060Y1717017D03*
X178226Y1726517D03*
X172962Y1721234D03*
X169777Y1726517D03*
X178142Y1720652D03*
X177933Y19538D03*
X186120Y24162D03*
X188620D03*
X190880Y383012D03*
Y387162D03*
Y391082D03*
X178375Y396571D03*
X181845Y401071D03*
X187371Y425383D03*
X187532Y421387D03*
X187371Y430883D03*
Y443383D03*
X180740Y437562D03*
X184550Y435712D03*
X187371Y440742D03*
X194440Y433895D03*
Y439565D03*
X187371Y447172D03*
X177871D03*
X181994Y453932D03*
X180640Y447172D03*
X185211Y453942D03*
X185191Y502439D03*
X186793Y575189D03*
X184193D03*
X186793Y572689D03*
X184193D03*
X181593Y575189D03*
X178993D03*
X181593Y572689D03*
X178993D03*
X189293Y575189D03*
X186793Y577790D03*
X184193D03*
X189293D03*
X181593D03*
X178993D03*
X181651Y596883D03*
X179151D03*
X186796Y594195D03*
Y596915D03*
X184151Y596883D03*
X179151Y594163D03*
X181651D03*
X184151D03*
X181651Y599603D03*
X179151D03*
X186796Y599635D03*
X184151Y599603D03*
X186720Y737862D03*
X180720D03*
X183720D03*
Y734862D03*
X180720D03*
X186720D03*
X185835Y757057D03*
X188978Y756855D03*
X191602Y756839D03*
X189377Y1333783D03*
X191977D03*
X189377Y1336383D03*
X191977D03*
X191947Y1339263D03*
X189347D03*
X189377Y1349383D03*
X191977D03*
X189377Y1346883D03*
X191977D03*
Y1344383D03*
X189377D03*
X191977Y1341883D03*
X189377D03*
X187711Y1395170D03*
Y1397670D03*
X190827Y1403451D03*
X180977Y1396173D03*
X178458Y1399269D03*
Y1402169D03*
Y1405069D03*
X188211Y1406691D03*
X186165Y1422589D03*
X183135Y1419784D03*
X180510Y1420258D03*
X177510D03*
X186135Y1419784D03*
X183165Y1422589D03*
X177510Y1423278D03*
X180510D03*
X183075Y1430424D03*
Y1425424D03*
Y1427924D03*
X186075Y1430424D03*
Y1425424D03*
Y1427924D03*
X183075Y1432924D03*
X186075D03*
X192600Y1557360D03*
X185895Y1557875D03*
X189600Y1566300D03*
X187400Y1568132D03*
X187542Y1729092D03*
X193293Y1722197D03*
X188794Y1725092D03*
X207894Y19538D03*
X204494D03*
X200789Y26474D03*
X197389D03*
X195050Y412055D03*
X199149Y425755D03*
Y420255D03*
Y414755D03*
X204699Y423242D03*
Y428742D03*
X195050Y417465D03*
X199149Y436755D03*
Y442255D03*
Y431255D03*
Y453255D03*
Y447755D03*
X197650Y455712D03*
X199149Y468255D03*
X208200Y493510D03*
X202338Y568746D03*
X201392Y574271D03*
X198336D03*
X204610Y571097D03*
X199164Y582481D03*
X200654Y578271D03*
X201622Y581009D03*
X208056Y591665D03*
X208806Y589335D03*
X208056Y587005D03*
X208806Y584675D03*
X202262Y592305D03*
X205162D03*
X202338Y602746D03*
X201392Y608271D03*
X198336D03*
X203892Y594471D03*
X202492Y596571D03*
X208292D03*
X206892Y594371D03*
X205392Y596571D03*
X204610Y605097D03*
X199164Y616481D03*
X200654Y612271D03*
X201622Y615009D03*
X208806Y618675D03*
X208056Y621005D03*
X208806Y623335D03*
X202338Y636746D03*
X208056Y625665D03*
X203892Y628471D03*
X202492Y630571D03*
X202262Y626305D03*
X208292Y630571D03*
X206892Y628371D03*
X205162Y626305D03*
X205392Y630571D03*
X204610Y639097D03*
X201392Y642271D03*
X199164Y650481D03*
X200654Y646271D03*
X201622Y649009D03*
X198336Y642271D03*
X208056Y655005D03*
X208806Y657335D03*
Y652675D03*
X207620Y671262D03*
X198420Y672662D03*
X198495Y669487D03*
X208056Y659665D03*
X205392Y664571D03*
X205162Y660305D03*
X206892Y662371D03*
X202262Y660305D03*
X202492Y664571D03*
X203892Y662471D03*
X208292Y664571D03*
X196049Y678195D03*
X194196Y687061D03*
X200018Y677492D03*
X193332Y678195D03*
X207129Y690027D03*
X203199Y690006D03*
X197086Y686326D03*
X203179Y693626D03*
X207140Y693636D03*
X195735Y696469D03*
X198235Y698969D03*
Y696469D03*
X200735Y698969D03*
Y696469D03*
X207140Y738462D03*
X205220Y736562D03*
X201220Y736662D03*
X203660Y731802D03*
X195602Y756839D03*
X203602Y756855D03*
X208977Y1336383D03*
Y1333783D03*
X194577D03*
Y1336383D03*
X209007Y1339263D03*
X194547D03*
X208977Y1341883D03*
X194577Y1349383D03*
Y1346883D03*
Y1344383D03*
X208977D03*
Y1346883D03*
Y1349383D03*
X194577Y1341883D03*
X206735Y1400005D03*
X209065Y1399255D03*
X204405D03*
X198001Y1409361D03*
X193941Y1407029D03*
X200797Y1409605D03*
X200492Y1406686D03*
X193941Y1409750D03*
X195966Y1542863D03*
X203120Y1624782D03*
X208115Y1624217D03*
X195590Y1714517D03*
X196010Y1709017D03*
X208295Y1703362D03*
X199050Y1726431D03*
X204600Y1733022D03*
X222067Y19538D03*
X218667D03*
X214962Y26474D03*
X211562D03*
X225407Y321831D03*
X209530Y426192D03*
X217770Y428262D03*
X224210Y431501D03*
X224305Y422977D03*
X219995Y426267D03*
X224210Y436619D03*
X218140Y440735D03*
X218010Y432735D03*
X223664Y443125D03*
X220000Y448735D03*
X212891Y566632D03*
X210391Y567981D03*
X212891Y601981D03*
X210391D03*
Y635981D03*
X212891D03*
X210320Y671262D03*
X224900Y713293D03*
X209720Y731862D03*
X220033Y756844D03*
X211602Y756855D03*
X216842Y756865D03*
X214177Y1336383D03*
X211577D03*
X214177Y1333783D03*
X211577D03*
X214207Y1339263D03*
X211607D03*
X214177Y1341883D03*
X211577D03*
X214177Y1349383D03*
Y1346883D03*
Y1344383D03*
X211577D03*
Y1346883D03*
Y1349383D03*
X211395Y1400005D03*
X214201Y1404169D03*
X212035Y1402899D03*
X214101Y1401169D03*
X216554Y1399264D03*
Y1402164D03*
Y1405064D03*
X212035Y1405799D03*
X219587Y1435402D03*
X217469Y1454725D03*
X219587Y1443402D03*
Y1439402D03*
X220869Y1454725D03*
X209820Y1631142D03*
X210593Y1714017D03*
X212120Y1703062D03*
X214120Y1713462D03*
X233339Y17662D03*
X235701Y21582D03*
X241310Y20322D03*
X229135Y26474D03*
X225735D03*
X238063Y26232D03*
X235701Y39570D03*
X229131Y50646D03*
X225731D03*
X239820Y54362D03*
X239720Y71862D03*
X239010Y78542D03*
X238297Y129703D03*
X234902Y174047D03*
X226800Y359464D03*
X230359Y461683D03*
X227430Y719772D03*
X238940Y716652D03*
X230864Y1254295D03*
X246510Y20362D03*
X242220Y39362D03*
X246220D03*
X250220D03*
X254050Y39422D03*
X246360Y26852D03*
X248820Y48962D03*
X252320D03*
X255820D03*
X257520Y51562D03*
X254020D03*
X250520D03*
X249885Y69623D03*
X245220Y67862D03*
X248097Y92143D03*
X247897Y100543D03*
X244822Y115543D03*
Y111543D03*
X253910Y115722D03*
X253878Y111771D03*
X243892Y140912D03*
X259933Y141122D03*
X257256Y156727D03*
X245490Y159702D03*
X252000Y395400D03*
X255810Y405582D03*
X252500Y415862D03*
X258066Y426735D03*
X256695Y461117D03*
X257750Y450842D03*
X254713Y518465D03*
X245700Y513262D03*
X250100Y521783D03*
X256885Y574805D03*
X254385D03*
X256855Y571995D03*
X251885Y574805D03*
X249800Y563262D03*
X254355Y589235D03*
X256855D03*
X251855D03*
X256855Y605995D03*
X251885Y608805D03*
X257643Y594220D03*
X255043D03*
Y596820D03*
X257643D03*
X256885Y608805D03*
X254385D03*
X256855Y603495D03*
X251855Y623265D03*
X254355D03*
X256855D03*
Y639995D03*
Y637495D03*
X257643Y628220D03*
X255043D03*
Y630820D03*
X257643D03*
X256885Y642805D03*
X254385D03*
X251855Y657265D03*
X251885Y642805D03*
X254355Y657265D03*
X256855D03*
X257643Y662220D03*
X255043D03*
Y664820D03*
X257643D03*
X253819Y675567D03*
X253849Y678077D03*
X256419Y675567D03*
X256449Y678077D03*
X251219Y675567D03*
X251249Y678077D03*
X248649D03*
X248989Y698827D03*
X249019Y693767D03*
X251589Y698827D03*
X251649Y696277D03*
X254189Y698827D03*
X251619Y693767D03*
X256849Y696277D03*
X256789Y698827D03*
X256819Y693767D03*
X254249Y696277D03*
X254219Y693767D03*
X248300Y703862D03*
X242460Y716652D03*
X253057Y755345D03*
X245487Y755435D03*
X259510Y757822D03*
X251187Y1255025D03*
X263240Y38122D03*
X266990Y41832D03*
X275120Y28562D03*
X275900Y48872D03*
X259320Y48962D03*
X261020Y51562D03*
X263520D03*
X261820Y48962D03*
X264740Y49182D03*
X266497Y69536D03*
Y72036D03*
X264720Y56362D03*
Y60362D03*
Y64362D03*
X266597Y77526D03*
Y80026D03*
X263320Y87662D03*
X261420Y100662D03*
X264920D03*
X268420D03*
X262920Y97962D03*
X266420D03*
X269920D03*
X273620Y96662D03*
X263550Y120922D03*
X269191Y121092D03*
X275797Y120245D03*
X265910Y125492D03*
X266975Y140107D03*
X260600Y151062D03*
X272800Y140162D03*
X264578Y151203D03*
X260100Y159562D03*
X265500Y227862D03*
X263000D03*
X260500Y227362D03*
Y224862D03*
X270240Y245332D03*
X271821Y251962D03*
X267759D03*
X259224Y419532D03*
X263430Y422235D03*
X259869Y431039D03*
X262963Y443735D03*
X272500Y447735D03*
X263040Y448752D03*
X272500Y452862D03*
X264055Y574505D03*
X264025Y571995D03*
X261555Y574505D03*
X261525Y571995D03*
X264055Y566935D03*
X263995Y569485D03*
X261495D03*
X261555Y566935D03*
X266555Y574505D03*
X266525Y571995D03*
X266495Y569485D03*
X266555Y566935D03*
X269055Y574505D03*
X269025Y571995D03*
X268995Y569485D03*
X269055Y566935D03*
X261465Y592115D03*
X261525Y589565D03*
X264025D03*
X263965Y592115D03*
X266525Y589565D03*
X266465Y592115D03*
X269025Y589565D03*
X268965Y592115D03*
X264025Y605995D03*
X261525D03*
X264055Y608505D03*
X261555D03*
X261435Y597175D03*
X261495Y594625D03*
X263995D03*
X263935Y597175D03*
X266525Y605995D03*
X266555Y608505D03*
X266435Y597175D03*
X266495Y594625D03*
X261525Y603495D03*
X264025D03*
X266525D03*
X269025Y605995D03*
X269055Y608505D03*
X268935Y597175D03*
X268995Y594625D03*
X269025Y603495D03*
X261495Y621055D03*
X263995D03*
X261525Y623565D03*
X264025D03*
X263995Y611055D03*
X261495D03*
X266495Y621055D03*
X266525Y623565D03*
X266495Y611055D03*
X268995Y621055D03*
X269025Y623565D03*
X268995Y611055D03*
X261525Y639995D03*
X264025D03*
X261525Y637495D03*
X266525Y639995D03*
X269025D03*
X264025Y637495D03*
X266525D03*
X269025D03*
X263965Y626115D03*
X261465D03*
X266465D03*
X268965D03*
X261495Y655055D03*
X263995D03*
X261525Y657565D03*
X264025D03*
X263995Y645055D03*
X264055Y642505D03*
X261495Y645055D03*
X261555Y642505D03*
X266495Y655055D03*
X266525Y657565D03*
X266495Y645055D03*
X266555Y642505D03*
X268995Y655055D03*
X269025Y657565D03*
X268995Y645055D03*
X269055Y642505D03*
X261465Y660115D03*
X263965D03*
X266465D03*
X268965D03*
X259049Y678077D03*
X259019Y675567D03*
X259419Y693767D03*
X259389Y698827D03*
X259449Y696277D03*
X269600Y715792D03*
X274247Y727165D03*
X268331Y738029D03*
X273046Y735662D03*
X270100Y727262D03*
X264000Y726262D03*
X266700Y730962D03*
X271570Y746422D03*
X265997Y747535D03*
X272208Y768516D03*
X271057Y765525D03*
Y762425D03*
X287000Y20862D03*
X284233Y26474D03*
X280833D03*
X290799Y28362D03*
X284230Y50646D03*
X280830D03*
X289400Y54222D03*
X285357Y105003D03*
X288557D03*
X280857Y107303D03*
X285857Y115603D03*
X282857D03*
X280857Y109903D03*
X275797Y129592D03*
X287000Y139862D03*
X283053Y139728D03*
X276825Y140462D03*
X290685Y165447D03*
X286481Y251962D03*
X281077D03*
X276491D03*
X289274Y290662D03*
X284515D03*
X276500Y444862D03*
X274850Y442562D03*
X279500Y455362D03*
X277578Y509039D03*
X284482Y566022D03*
X286582Y637809D03*
Y634283D03*
X284287Y716015D03*
X277046Y725709D03*
Y735442D03*
X284358Y732562D03*
X283350Y728483D03*
X289137Y735275D03*
X279507Y727025D03*
X285046Y737964D03*
X281046Y737938D03*
X275210Y738102D03*
X287607Y754962D03*
X277046Y746702D03*
X281046D03*
X285046D03*
X299500Y22862D03*
X295520Y12762D03*
X302610Y26362D03*
X292060Y24472D03*
X295520Y26362D03*
X300248Y28362D03*
X304927Y24654D03*
X304972Y28362D03*
X302720Y38182D03*
X292590Y53982D03*
X293161Y50522D03*
X306570Y50222D03*
X290720Y40017D03*
X294720D03*
X295524Y52092D03*
X301310Y52482D03*
X298550Y51602D03*
X303715Y50857D03*
X292942Y71499D03*
X305747Y64013D03*
Y61113D03*
X305247Y71567D03*
X301600Y82457D03*
X302310Y75673D03*
X295357Y88903D03*
X307820Y95724D03*
X301183Y107103D03*
Y110003D03*
Y112803D03*
X296478Y149203D03*
X296800Y139762D03*
X306000Y165662D03*
X295685Y165447D03*
X296478Y158703D03*
X306730Y173842D03*
X304651Y251962D03*
X291759D03*
X306736Y290662D03*
X302765D03*
X298184D03*
X293763D03*
X298587Y508074D03*
X300520Y552262D03*
X307987Y577658D03*
X293805Y569397D03*
Y565997D03*
X298000Y587890D03*
X308417Y585158D03*
X308447Y592255D03*
X306144Y602225D03*
X305612Y622530D03*
Y625030D03*
Y627530D03*
X296405Y630732D03*
Y634132D03*
X295962Y679374D03*
X294679Y688446D03*
Y685046D03*
X291600Y705162D03*
X298273Y715400D03*
X297087Y721249D03*
X304602Y727968D03*
X293027Y755985D03*
X303647Y1307981D03*
X303723Y1353316D03*
Y1355853D03*
X304051Y1365453D03*
X306667Y1361597D03*
X302805Y1379941D03*
Y1376541D03*
X296170Y1622852D03*
X310400Y50362D03*
X314657Y71803D03*
Y68903D03*
X323040Y73122D03*
X323117Y81168D03*
Y76938D03*
X322875Y84318D03*
X316364Y89212D03*
X310459Y75892D03*
X320430Y78002D03*
X313357Y89503D03*
X313457Y96803D03*
X311057Y107103D03*
Y110003D03*
Y112803D03*
X308175Y144202D03*
X308500Y165662D03*
X311200Y165562D03*
X309230Y173842D03*
X309756Y177449D03*
Y181449D03*
X310970Y195362D03*
X308790Y197622D03*
X320270Y200462D03*
X319370Y214492D03*
X316370D03*
X319370Y217492D03*
X316370D03*
X323314Y210645D03*
X306910Y228162D03*
X309910D03*
X306910Y225162D03*
X309910D03*
X322658Y229254D03*
X319718Y223750D03*
X317981Y237724D03*
X320940Y238372D03*
X317129Y251962D03*
X316463Y290662D03*
X316444Y559125D03*
X317860Y572322D03*
X319520Y577658D03*
X312007Y588675D03*
X319520Y582658D03*
X316127Y592785D03*
X318560Y587632D03*
X321276Y599298D03*
X317386Y623207D03*
X308605Y629525D03*
Y627025D03*
X319557Y736225D03*
X317967Y746985D03*
Y771875D03*
X320578Y1290197D03*
X323028Y1297967D03*
X320428D03*
Y1295467D03*
X323028D03*
Y1292967D03*
X320428D03*
X320245Y1357401D03*
X313841Y1365553D03*
X309841Y1364815D03*
X318051Y1367043D03*
X316579Y1364585D03*
X309841Y1367871D03*
X322575Y1358151D03*
X332500Y150738D03*
X326216Y138787D03*
X326900Y162287D03*
X323420Y207549D03*
X326168Y207580D03*
X334485Y216809D03*
X337000Y216862D03*
X335575Y214170D03*
X328588Y209677D03*
X334500Y219362D03*
X337000D03*
X328939Y229139D03*
X335385Y235309D03*
X335412Y222176D03*
X329648Y252202D03*
X341295Y290239D03*
X329002Y290662D03*
X330674Y365702D03*
X328167Y379073D03*
X336270Y402992D03*
X329050Y607402D03*
X331339Y709313D03*
X328120Y710862D03*
X335677Y715215D03*
X327107Y732665D03*
X335467Y725335D03*
X338097Y736235D03*
X335126Y728323D03*
X327096Y736005D03*
X336446Y746486D03*
X338667Y772452D03*
X341527Y778362D03*
X339148Y1269717D03*
X339088Y1272287D03*
X339028Y1274887D03*
X325688Y1290167D03*
X325718Y1287587D03*
X328078Y1288747D03*
X323178Y1290197D03*
X323208Y1287617D03*
X328168Y1280967D03*
X325748Y1284987D03*
X328108Y1286147D03*
X328138Y1283567D03*
X328018Y1291317D03*
X339035Y1280218D03*
X339040Y1277594D03*
X328065Y1299248D03*
X325538Y1297937D03*
Y1292937D03*
Y1295437D03*
X328058Y1293917D03*
X328070Y1296624D03*
X335679Y1330518D03*
X334973Y1333353D03*
X338795Y1338799D03*
X336179Y1342753D03*
X324905Y1357401D03*
X327235Y1358151D03*
X332475Y1357945D03*
X327875Y1363945D03*
Y1361045D03*
X330041Y1362315D03*
X329941Y1359315D03*
X332475Y1363345D03*
Y1360445D03*
X340440Y120552D03*
X343450Y131167D03*
X342700Y139662D03*
X355189Y144267D03*
X351100Y150412D03*
X348100Y185162D03*
X345600Y188162D03*
X356295Y219362D03*
X353145D03*
X342000Y252612D03*
X354672Y252693D03*
X354145Y290591D03*
X345411Y364702D03*
Y376923D03*
X343354Y391643D03*
X347340Y407462D03*
X348880Y703442D03*
X354100Y720743D03*
X352879Y728657D03*
X348037Y728735D03*
X348730Y735098D03*
Y731698D03*
X344264Y1272455D03*
X341754Y1272485D03*
X344252Y1269948D03*
X341742Y1269978D03*
X344258Y1267117D03*
X341748Y1267147D03*
X341754Y1274985D03*
X344264Y1274955D03*
X355036Y1272433D03*
Y1269933D03*
X355378Y1262027D03*
X355318Y1264597D03*
X355258Y1267197D03*
X355036Y1274933D03*
X341605Y1280248D03*
X344115Y1280218D03*
X344264Y1277455D03*
X341754Y1277485D03*
X355048Y1277440D03*
X355025Y1280248D03*
X352373Y1334603D03*
X354703Y1335353D03*
X345969Y1342755D03*
X341969Y1342017D03*
X350179Y1344245D03*
X348707Y1341787D03*
X341969Y1345073D03*
X354850Y1371908D03*
X351850D03*
X349260Y1373418D03*
X351850Y1375408D03*
X354850D03*
X351850Y1378408D03*
X354850D03*
X351850Y1381408D03*
X354850D03*
X349260Y1376918D03*
Y1379918D03*
X349636Y1399601D03*
X352713Y1399336D03*
X355513Y1402306D03*
X352513D03*
X349513D03*
X355325Y1405386D03*
X349463Y1405286D03*
X352463D03*
X355325Y1408386D03*
X346426Y1414401D03*
X352401Y1414432D03*
X355325Y1414386D03*
Y1417386D03*
X352401Y1411432D03*
X355325Y1411386D03*
X352401Y1408432D03*
X349123Y1411376D03*
X349323Y1408406D03*
X349073Y1414356D03*
X346256Y1417301D03*
X352231Y1417332D03*
X348903Y1417256D03*
X363625Y127662D03*
X361800Y122522D03*
X366060Y133912D03*
X363525Y158702D03*
X361190Y210762D03*
X357303Y213159D03*
X371551Y224862D03*
X367306Y252811D03*
X366498Y290264D03*
X357660Y318850D03*
X364014Y366391D03*
Y378649D03*
X364179Y392037D03*
X370200Y409582D03*
X373720Y431362D03*
X365720Y440562D03*
X365771Y449480D03*
X359669Y686744D03*
X359639Y690114D03*
X360470Y705965D03*
X363101Y697348D03*
Y693948D03*
X360990Y726862D03*
X358902Y736225D03*
X355946Y728800D03*
X359790Y729835D03*
X358902Y739755D03*
Y743035D03*
Y754945D03*
Y746405D03*
Y773352D03*
X371578Y1248967D03*
X371458Y1254137D03*
X371330Y1256687D03*
X371518Y1251537D03*
X371278Y1259257D03*
X360198Y1269777D03*
X357546Y1272403D03*
Y1269903D03*
X360138Y1272347D03*
X357828Y1264567D03*
X357888Y1261997D03*
X360378Y1264627D03*
X360438Y1262057D03*
X357768Y1267167D03*
X360318Y1267227D03*
X357546Y1274903D03*
X360128Y1274957D03*
X371218Y1261857D03*
X371225Y1267188D03*
X371230Y1264564D03*
X357558Y1277410D03*
X357535Y1280218D03*
X360120Y1277654D03*
X367694Y1317092D03*
X367807Y1319592D03*
X368391Y1328161D03*
X370923Y1325373D03*
X357033Y1334603D03*
X359363Y1335353D03*
X362147Y1336553D03*
X360003Y1338247D03*
X364269Y1338017D03*
X364073Y1334903D03*
X360003Y1341147D03*
X362147Y1339653D03*
X364347Y1340853D03*
X364647Y1371990D03*
X361647D03*
X358647D03*
X367647D03*
X370552Y1372073D03*
X364647Y1375490D03*
X361647D03*
X358647D03*
Y1378490D03*
X370552Y1375573D03*
X367647Y1375490D03*
X355713Y1399336D03*
X361703Y1399386D03*
X364703D03*
X367703D03*
X370703D03*
X358703Y1402386D03*
X361703D03*
X364703D03*
X367703D03*
X370703D03*
X358713Y1399336D03*
X358573Y1405336D03*
X361573D03*
X364573D03*
X367573D03*
X370573D03*
X358703Y1414606D03*
X361703D03*
X364703D03*
X361703Y1417386D03*
X358703D03*
X364703D03*
X367703D03*
Y1414606D03*
X358217Y1411405D03*
X370517Y1414615D03*
X370717Y1417405D03*
X357917Y1408205D03*
X367948Y1531529D03*
X371850Y1534062D03*
X368600Y1543200D03*
X367140Y1645390D03*
X366700Y1649000D03*
X370500Y1654362D03*
X370635Y1675820D03*
X369300Y1680400D03*
Y1682900D03*
X380930Y122022D03*
X383160Y124322D03*
X383060Y128491D03*
X372530Y122972D03*
X373200Y126052D03*
X379295Y131002D03*
X379860Y252162D03*
X379112Y290386D03*
X385720Y320902D03*
X376500Y366391D03*
Y378649D03*
X377136Y390307D03*
X390220Y392062D03*
X383060Y403542D03*
X379220Y436362D03*
X376220D03*
X382220D03*
X389920Y461362D03*
X379220Y470962D03*
X387500Y495362D03*
X389020Y522862D03*
X371970Y683892D03*
X381010Y734732D03*
X376638Y1248997D03*
X374088Y1248937D03*
X374028Y1251507D03*
X373823Y1256896D03*
X376333Y1256866D03*
X376518Y1254167D03*
X376578Y1251567D03*
X373968Y1254107D03*
X373835Y1259403D03*
X376345Y1259373D03*
X387478Y1248967D03*
X387358Y1254137D03*
X387117Y1256851D03*
X387418Y1251537D03*
X387117Y1259351D03*
X373835Y1261903D03*
Y1264403D03*
X376345Y1261873D03*
Y1264373D03*
X376285Y1267218D03*
X373735Y1267158D03*
X387117Y1261851D03*
X387129Y1264358D03*
X387125Y1267188D03*
X384501Y1321177D03*
X386831Y1321927D03*
X378097Y1329329D03*
X374097Y1328591D03*
X382307Y1330819D03*
X380835Y1328361D03*
X374097Y1331647D03*
X373552Y1372073D03*
X377025Y1371990D03*
X380025D03*
X373532Y1378598D03*
X373552Y1375573D03*
X380025Y1378490D03*
X377025D03*
X380025Y1375490D03*
X377025D03*
Y1381490D03*
X380025D03*
X376825Y1399386D03*
X379825D03*
X373703D03*
X379825Y1402386D03*
X376825D03*
X373703D03*
X376825Y1405386D03*
X379825D03*
X373573Y1405336D03*
X374027Y1411365D03*
X373703Y1414606D03*
X376825Y1414386D03*
X379825D03*
X376825Y1417386D03*
Y1411386D03*
X379825D03*
X373703Y1417386D03*
X376825Y1408386D03*
X379825D03*
X374307Y1408135D03*
X382489Y1428478D03*
X385667Y1433425D03*
X386827Y1429525D03*
X377830Y1534342D03*
X374900Y1534102D03*
X381120D03*
X377720Y1539862D03*
X374720D03*
X374800Y1546400D03*
X385100Y1539700D03*
X381800Y1539600D03*
X381000Y1546500D03*
X384000D03*
X378000Y1546400D03*
X387930Y1585155D03*
X384600Y1595100D03*
X382220Y1591870D03*
X374391Y1648476D03*
X385123Y1639732D03*
X378547D03*
X380170Y1660002D03*
X372640Y1662112D03*
X380077Y1654049D03*
X372009Y1682584D03*
X375430Y1676462D03*
X376610Y1688252D03*
X396380Y62742D03*
X402100Y62632D03*
X399240Y62722D03*
X404910Y62562D03*
X388735Y117322D03*
X395980Y148272D03*
X388965Y215067D03*
X388720Y218362D03*
X394720Y206362D03*
X402700Y234167D03*
X392616Y252162D03*
X396294Y281585D03*
X392083Y290954D03*
X404215Y291140D03*
X398720Y321202D03*
X398661Y323761D03*
X390876Y365640D03*
X390843Y378439D03*
X403875Y365640D03*
X404120Y378439D03*
X404291Y391433D03*
X391149Y404304D03*
X403720Y405552D03*
X388720Y430862D03*
X403220Y436362D03*
X395520Y448362D03*
X400080Y472652D03*
X402500Y495362D03*
X394500Y522862D03*
X400589Y575236D03*
X398796Y1161570D03*
Y1153070D03*
Y1170070D03*
X403738Y1249027D03*
X403618Y1254197D03*
X403498Y1256747D03*
X403678Y1251597D03*
X392538Y1248997D03*
X389928Y1251507D03*
X389988Y1248937D03*
X389868Y1254107D03*
X392298Y1256717D03*
X392418Y1254167D03*
X389627Y1256821D03*
X392478Y1251567D03*
X392238Y1259287D03*
X389627Y1259321D03*
X403438Y1259317D03*
X392220Y1264594D03*
X392228Y1261897D03*
X389627Y1261821D03*
X389639Y1264328D03*
X389635Y1267158D03*
X392185Y1267218D03*
X403385Y1267248D03*
X403378Y1261917D03*
X403390Y1264624D03*
X399935Y1317092D03*
Y1319592D03*
X389161Y1321177D03*
X391491Y1321927D03*
X392131Y1324821D03*
X396397Y1324591D03*
X394197Y1323091D03*
X396397Y1321691D03*
X400073Y1327653D03*
X403051Y1325373D03*
X394297Y1326091D03*
X392131Y1327721D03*
X396397Y1327491D03*
X400888Y1395508D03*
X392947Y1397827D03*
X390934Y1404085D03*
X401079Y1399208D03*
X400924Y1408227D03*
X400926Y1404707D03*
X392517Y1419015D03*
X400991Y1417264D03*
X390934Y1407605D03*
X390914Y1412991D03*
X403125Y1425008D03*
X390687Y1431713D03*
X390777Y1435152D03*
X394067Y1435323D03*
X401244Y1440773D03*
X396822Y1439340D03*
X396946Y1537632D03*
X396768Y1541810D03*
X404920Y1539362D03*
X396946Y1556810D03*
X391330Y1585155D03*
X404030Y1595390D03*
Y1591990D03*
X394360Y1616380D03*
X392550Y1618650D03*
X397406Y1633142D03*
X402590Y1618952D03*
X401740Y1648082D03*
X404240D03*
X404320Y1645452D03*
X401820D03*
X391563Y1640244D03*
X397406Y1636542D03*
X397400Y1641000D03*
X390180Y1668212D03*
X396824Y1673662D03*
X407970Y59612D03*
X407790Y62652D03*
X415800Y62665D03*
Y67465D03*
X419901Y117491D03*
X408284Y163662D03*
X420865Y215067D03*
X410996Y218834D03*
X420752Y239562D03*
X405139Y239908D03*
X417765Y252162D03*
X404985D03*
X417218Y291274D03*
X419920Y338162D03*
X416220Y364062D03*
X418704Y379201D03*
X416762Y367353D03*
X418540Y392163D03*
X416514Y407028D03*
X412720Y439362D03*
X417880Y461942D03*
X418520Y473562D03*
X419460Y1161570D03*
Y1153370D03*
Y1169597D03*
X406248Y1248997D03*
X408798Y1249057D03*
X408511Y1256866D03*
X406001Y1256896D03*
X406128Y1254167D03*
X408678Y1254227D03*
X406188Y1251567D03*
X419638Y1248967D03*
X419295Y1256851D03*
X419518Y1254137D03*
X419578Y1251537D03*
X419295Y1259351D03*
X408738Y1251627D03*
X408523Y1259373D03*
X406013Y1259403D03*
X419295Y1261851D03*
X419307Y1264358D03*
X419285Y1267188D03*
X408523Y1264373D03*
X406013Y1264403D03*
Y1261903D03*
X408523Y1261873D03*
X405895Y1267218D03*
X408445Y1267278D03*
X416629Y1321177D03*
X418959Y1321927D03*
X410225Y1329329D03*
X406225Y1328591D03*
X414435Y1330819D03*
X412963Y1328361D03*
X406225Y1331647D03*
X418320Y1383862D03*
X422320D03*
X414333Y1385292D03*
X410933Y1384648D03*
X414909Y1395658D03*
X408915Y1402606D03*
X411150Y1408163D03*
X410912Y1418177D03*
X408968Y1410427D03*
X411162Y1414126D03*
X416926Y1426471D03*
X412416Y1431645D03*
X419861Y1429718D03*
X419302Y1434700D03*
X422708Y1437560D03*
X410074Y1424993D03*
X416999Y1441908D03*
X413599D03*
X407625Y1552572D03*
X419820Y1555862D03*
X409140Y1566892D03*
X405000Y1566670D03*
X412600Y1601000D03*
X408600Y1607400D03*
X419780Y1602802D03*
X414406Y1624992D03*
Y1628392D03*
X405990Y1618952D03*
X416020Y1620862D03*
X412456Y1649838D03*
X417960Y1650072D03*
X410700Y1655310D03*
X409857Y1682767D03*
X421320Y1671699D03*
X410249Y1673082D03*
X427120Y59862D03*
X428500Y65016D03*
Y70016D03*
X435340Y122196D03*
X428889Y121515D03*
X428883Y131015D03*
X429780Y149373D03*
Y153477D03*
Y157466D03*
Y161466D03*
X433695Y209862D03*
X421200Y232562D03*
X423145Y227862D03*
X426490Y244262D03*
X429702Y290763D03*
X425720Y319492D03*
X432380Y346522D03*
X422420Y338162D03*
X431781Y379201D03*
X434006Y365203D03*
X433596Y391163D03*
X431920Y405288D03*
X428720Y439362D03*
X437720Y435362D03*
X431570Y435512D03*
X437520Y476337D03*
X431220Y496362D03*
X434343Y504233D03*
Y509733D03*
Y498733D03*
X431220Y507143D03*
Y512623D03*
Y501643D03*
X434343Y515233D03*
Y526233D03*
Y520733D03*
X431220Y518133D03*
Y523362D03*
X434620Y535762D03*
X434343Y542733D03*
X434320Y540153D03*
X434343Y547769D03*
Y552769D03*
X421960Y1161570D03*
Y1153370D03*
Y1169597D03*
X422148Y1248937D03*
X424698Y1248997D03*
X422088Y1251507D03*
X421805Y1256821D03*
X422028Y1254107D03*
X424458Y1256717D03*
X424578Y1254167D03*
X424638Y1251567D03*
X421805Y1259321D03*
X424398Y1259287D03*
X436068Y1248967D03*
X435828Y1256687D03*
X435948Y1254137D03*
X436008Y1251537D03*
X435768Y1259257D03*
X421805Y1261821D03*
X421817Y1264328D03*
X421795Y1267158D03*
X424345Y1267218D03*
X424380Y1264594D03*
X424388Y1261897D03*
X435715Y1267188D03*
X435720Y1264564D03*
X435708Y1261857D03*
X432063Y1317092D03*
Y1319592D03*
X421289Y1321177D03*
X423619Y1321927D03*
X428525Y1321691D03*
X426325Y1323091D03*
X424259Y1324821D03*
X428525Y1324591D03*
X432628Y1327845D03*
X435179Y1325373D03*
X424259Y1327721D03*
X426425Y1326091D03*
X428525Y1327491D03*
X426320Y1383862D03*
X430320D03*
X439030Y1383692D03*
X436780Y1387387D03*
X436467Y1391687D03*
X438458Y1402169D03*
X438645Y1426890D03*
X437299Y1436774D03*
X433539Y1430613D03*
X425030Y1434292D03*
X433897Y1434670D03*
X427546Y1443411D03*
X433954Y1439029D03*
X424146Y1443411D03*
X435396Y1551810D03*
X424820Y1552605D03*
X431620Y1541362D03*
X434430Y1567562D03*
X424570Y1579466D03*
X433350Y1579509D03*
X424800Y1616600D03*
X432200Y1607060D03*
X423180Y1602802D03*
X432500Y1613822D03*
X430015Y1626608D03*
X433670Y1639562D03*
X426728Y1636495D03*
X451418Y78782D03*
X446640Y104552D03*
X446746Y152662D03*
X453028Y154864D03*
X452500Y213362D03*
Y222362D03*
X452071Y254862D03*
X442265Y290939D03*
X439120Y314562D03*
X442220Y323362D03*
X448220Y323582D03*
Y319862D03*
X446000Y339362D03*
X455000Y340362D03*
X450500Y358862D03*
X443770Y371042D03*
X451062Y397262D03*
X447490Y409052D03*
X443300Y410962D03*
X447750Y414112D03*
X453020Y414262D03*
X449420Y424162D03*
X451520Y475837D03*
X442520Y476337D03*
X453680Y515072D03*
X451320Y533562D03*
X448276Y1161570D03*
X445776D03*
X443276D03*
X445776Y1153370D03*
X448276D03*
X443276D03*
X448276Y1170069D03*
X445776D03*
X443276D03*
X441128Y1248997D03*
X438578Y1248937D03*
X438518Y1251507D03*
X440858Y1256866D03*
X438348Y1256896D03*
X441008Y1254167D03*
X438458Y1254107D03*
X441068Y1251567D03*
X440870Y1259373D03*
X438360Y1259403D03*
X451642Y1256851D03*
X451878Y1254107D03*
X451642Y1259351D03*
X451938Y1251507D03*
X451998Y1248937D03*
X438360Y1261903D03*
X440870Y1261873D03*
Y1264373D03*
X438360Y1264403D03*
X438225Y1267158D03*
X440775Y1267218D03*
X451642Y1261851D03*
X451654Y1264358D03*
X451645Y1267158D03*
X448757Y1321177D03*
X451087Y1321927D03*
X442353Y1329329D03*
X438353Y1328591D03*
X446563Y1330819D03*
X445091Y1328361D03*
X438353Y1331647D03*
X443842Y1389106D03*
X448020Y1391862D03*
X443424Y1397869D03*
X439391Y1398266D03*
X441369Y1394260D03*
X451048Y1404914D03*
X447110Y1403812D03*
X448114Y1396812D03*
X445339Y1415731D03*
X446230Y1407722D03*
X445230Y1411719D03*
X445723Y1419730D03*
X443850Y1423404D03*
X451080Y1433740D03*
X440164Y1433982D03*
X445294Y1430415D03*
X443715Y1436052D03*
X452520Y1564862D03*
X448328Y1582476D03*
X446020Y1570412D03*
X452020Y1580412D03*
X448740Y1574862D03*
X444458Y1602654D03*
X437383Y1602629D03*
X454661Y1609235D03*
X442974Y1615615D03*
X448181Y1614401D03*
X443800Y1610712D03*
X449940Y1647412D03*
X447090Y1647472D03*
X444940Y1641842D03*
X438340Y1652266D03*
X441740D03*
X462620Y120948D03*
X462320Y115948D03*
X453346Y149864D03*
X461900Y215244D03*
X466300Y217803D03*
X461900Y222921D03*
X466300Y225480D03*
X468323Y254562D03*
X465236Y296973D03*
X461736Y301098D03*
Y306098D03*
X463198Y311587D03*
X465000Y340362D03*
X456660Y359172D03*
X460800Y358962D03*
X467211Y371902D03*
X459220Y393762D03*
X463500Y383562D03*
X455720Y404762D03*
X458600Y414262D03*
X465421Y428078D03*
X456520Y476337D03*
X461520D03*
X453727Y518036D03*
X457456Y522516D03*
X470880Y572692D03*
X467130Y600122D03*
X456818Y1256687D03*
X454388Y1254077D03*
X454152Y1256821D03*
X456998Y1251537D03*
X456758Y1259257D03*
X454152Y1259321D03*
X468258Y1249107D03*
X468018Y1256827D03*
X468138Y1254277D03*
X468198Y1251677D03*
X467958Y1259397D03*
X457058Y1248967D03*
X454508Y1248907D03*
X454448Y1251477D03*
X456938Y1254137D03*
X456705Y1267188D03*
X454155Y1267128D03*
X456748Y1261867D03*
X456740Y1264564D03*
X454152Y1261821D03*
X454164Y1264328D03*
X467905Y1267328D03*
X467910Y1264704D03*
X467898Y1261997D03*
X464191Y1317092D03*
Y1319592D03*
X453417Y1321177D03*
X455747Y1321927D03*
X458453Y1323091D03*
X460653Y1321691D03*
Y1324591D03*
X456387Y1324821D03*
X464191Y1327793D03*
X467307Y1325373D03*
X458553Y1326091D03*
X460653Y1327491D03*
X456387Y1327721D03*
X459550Y1401348D03*
X465947Y1398355D03*
X459321Y1393009D03*
Y1396409D03*
X458441Y1414893D03*
X468880Y1418400D03*
X456619Y1431189D03*
X463140Y1451562D03*
X463207Y1547543D03*
X453595Y1551470D03*
X459520Y1546962D03*
X466905Y1567847D03*
X467400Y1556700D03*
X460020Y1580412D03*
X457220Y1584020D03*
X466520Y1574862D03*
X457220Y1603562D03*
X460200Y1589900D03*
X456510Y1614472D03*
X469488Y1607362D03*
X460910Y1629172D03*
Y1625772D03*
X455681Y1622492D03*
X458978Y1634481D03*
X463344Y1637622D03*
X469580Y1640272D03*
X468040Y1651657D03*
X466460Y1672332D03*
X466180Y1678392D03*
X481880Y147069D03*
X481246Y161364D03*
X476220Y158772D03*
X470900Y234787D03*
X486800Y259162D03*
X478500Y258862D03*
X474736Y302098D03*
X478995Y293787D03*
X479736Y303598D03*
Y308598D03*
X486720Y360862D03*
X482720D03*
X475508Y359266D03*
X476585Y370727D03*
X472720Y391362D03*
X485020Y414162D03*
X471920Y416687D03*
X474169Y476196D03*
X479169D03*
X474044Y503725D03*
X478510Y602942D03*
X472960Y602152D03*
X482780Y607012D03*
X473698Y1161570D03*
X471198D03*
X473698Y1153370D03*
X471198D03*
X473698Y1170070D03*
X471198D03*
X473318Y1249137D03*
X470768Y1249077D03*
X473035Y1256866D03*
X470525Y1256896D03*
X473198Y1254307D03*
X470648Y1254247D03*
X473258Y1251707D03*
X470708Y1251647D03*
X473047Y1259373D03*
X470537Y1259403D03*
X484098Y1248997D03*
X483819Y1256851D03*
X483978Y1254167D03*
X484038Y1251567D03*
X483819Y1259351D03*
X472965Y1267358D03*
X470415Y1267298D03*
X470537Y1261903D03*
X473047Y1261873D03*
Y1264373D03*
X470537Y1264403D03*
X483819Y1261851D03*
X483831Y1264358D03*
X483745Y1267218D03*
X480885Y1321177D03*
X485545D03*
X483215Y1321927D03*
X474481Y1329329D03*
X470481Y1328591D03*
X478691Y1330819D03*
X477219Y1328361D03*
X470481Y1331647D03*
X483560Y1401712D03*
X474983Y1400385D03*
X485141Y1405430D03*
X481997Y1409955D03*
X470987Y1409965D03*
X484921Y1413246D03*
X470890Y1435838D03*
X478449Y1448158D03*
X482633Y1449091D03*
Y1446091D03*
X470111Y1548269D03*
X483348Y1548062D03*
X475110Y1548112D03*
X477968Y1548122D03*
X480848Y1548120D03*
X486210Y1547960D03*
X482400Y1558320D03*
X472220Y1626732D03*
X472210Y1622735D03*
X477905Y1663242D03*
Y1659242D03*
X475150Y1654302D03*
X477835Y1677462D03*
X488748Y72264D03*
X499580Y78442D03*
X489730Y76132D03*
X498330Y96112D03*
X498730Y128592D03*
X498700Y212685D03*
Y220362D03*
X503100Y215244D03*
X500925Y231262D03*
X503100Y222921D03*
X496028Y258590D03*
X499096Y252462D03*
X489091Y293787D03*
X498636Y296273D03*
X495136Y300398D03*
Y305398D03*
X486861D03*
X495036Y310398D03*
X486710Y313582D03*
X492150Y336810D03*
X498720Y360862D03*
X490720D03*
Y368862D03*
X489520Y411862D03*
X494020Y414262D03*
X492970Y409252D03*
X502070Y427937D03*
X488169Y475696D03*
X493169Y476196D03*
X498169D03*
X486500Y556212D03*
X491043Y550447D03*
X486608Y1248967D03*
X489158Y1249027D03*
X486329Y1256821D03*
X486488Y1254137D03*
X488918Y1256747D03*
X489038Y1254197D03*
X486548Y1251537D03*
X489098Y1251597D03*
X486329Y1259321D03*
X488858Y1259317D03*
X500228Y1259237D03*
X486329Y1261821D03*
X486341Y1264328D03*
X488840Y1264624D03*
X488848Y1261927D03*
X488805Y1267248D03*
X486255Y1267188D03*
X500138Y1269637D03*
X500150Y1272344D03*
X500198Y1267037D03*
Y1264467D03*
X500168Y1261807D03*
X500150Y1275224D03*
Y1278104D03*
X487875Y1321927D03*
X492878Y1322618D03*
X490678Y1324018D03*
X496319Y1330493D03*
Y1333043D03*
X499435Y1338799D03*
X488539Y1325772D03*
X492878Y1325518D03*
X488539Y1328672D03*
X490778Y1327018D03*
X492878Y1328418D03*
X496319Y1341264D03*
X491089Y1446091D03*
Y1449091D03*
X499489D03*
Y1446091D03*
X489230Y1643592D03*
X516236Y92948D03*
X513586Y92799D03*
X510600Y92782D03*
X517290Y104252D03*
X513700Y117862D03*
X510900Y111962D03*
X503270Y128592D03*
X507320D03*
X515690Y147852D03*
X519010Y147912D03*
X518186Y139821D03*
X519236Y202404D03*
X518670Y219192D03*
X512500Y209862D03*
Y223362D03*
X508500Y232862D03*
X508000Y241862D03*
X508502Y298813D03*
X503040Y287928D03*
X508500Y303362D03*
X508136Y309398D03*
X502239Y315404D03*
X507160Y332452D03*
X510720Y360862D03*
X514720D03*
X502720D03*
X506720Y368862D03*
X509720Y390362D03*
X513720D03*
X505720Y398362D03*
X502260Y397742D03*
X511320Y437962D03*
X513444Y457522D03*
X516970Y592942D03*
X504135Y615612D03*
X505398Y1259377D03*
X502858Y1259257D03*
X502718Y1271417D03*
X505218Y1271447D03*
X505290Y1267254D03*
X505338Y1261947D03*
X505278Y1264547D03*
X502750Y1267134D03*
X502798Y1261827D03*
X502738Y1264427D03*
X502718Y1274114D03*
X505218Y1274144D03*
X515898Y1271447D03*
X515950Y1274144D03*
X505220Y1280054D03*
X502718Y1276994D03*
X505218Y1277024D03*
X502680Y1280054D03*
X515960D03*
X515950Y1277024D03*
X513013Y1334603D03*
X517673D03*
X515343Y1335353D03*
X506609Y1342755D03*
X502609Y1342017D03*
X510819Y1344245D03*
X509347Y1341787D03*
X502609Y1345073D03*
X509246Y1420002D03*
X505777Y1425579D03*
X507964Y1448979D03*
Y1445979D03*
X529720Y30792D03*
Y43054D03*
X534720Y42922D03*
X533915Y59822D03*
X523978Y59074D03*
X529078Y59282D03*
X527520Y69633D03*
X528590Y72922D03*
X518450Y101602D03*
X527310Y98147D03*
Y94747D03*
X527160Y129243D03*
X523220Y170362D03*
X534765Y161067D03*
X526920Y161362D03*
X529507Y202448D03*
X522337Y202404D03*
X531298Y284280D03*
X536420Y309422D03*
X523682Y307541D03*
Y304541D03*
X526980Y322582D03*
X521820Y336762D03*
X531720Y360862D03*
X527720D03*
X523670Y368892D03*
X525720Y390362D03*
X529720D03*
X521720Y398362D03*
X532650Y446396D03*
Y442376D03*
X521885Y452442D03*
X532650Y450330D03*
Y454270D03*
X533410Y475932D03*
X525820Y473662D03*
X524425Y489112D03*
Y495112D03*
X519520Y484027D03*
X522805Y482155D03*
X531258Y505473D03*
X521561Y505969D03*
Y500469D03*
Y511469D03*
X524220Y505862D03*
Y500362D03*
Y511362D03*
X521561Y516969D03*
Y522469D03*
X536000Y520362D03*
X524220Y516862D03*
X524720Y525293D03*
Y519743D03*
X521561Y527969D03*
Y539819D03*
X524920D03*
X524820Y545319D03*
X523699Y571545D03*
X528500Y566722D03*
X523890Y592387D03*
X531472Y579750D03*
X521118Y1273097D03*
X518488Y1271477D03*
X521058Y1275667D03*
X518490Y1274144D03*
X521058Y1278277D03*
X521020Y1280974D03*
X518500Y1280054D03*
X518490Y1277024D03*
X530398Y1288557D03*
X530548Y1283377D03*
X530428Y1285947D03*
X530410Y1291254D03*
X532558Y1289967D03*
X532618Y1287367D03*
X532678Y1284797D03*
X530450Y1297014D03*
Y1294134D03*
X532570Y1295554D03*
Y1298434D03*
Y1292674D03*
X525008Y1336287D03*
X520643Y1338247D03*
X522809Y1339517D03*
X522783Y1334882D03*
X520643Y1341147D03*
X520003Y1335353D03*
X528447Y1353316D03*
Y1355816D03*
X524892Y1341462D03*
X522818Y1342930D03*
X528929Y1364212D03*
X531563Y1361597D03*
X539720Y30792D03*
X534720D03*
X542050Y47452D03*
X539720Y42862D03*
X550971Y42902D03*
X544720Y42892D03*
X548609Y48082D03*
X537315Y59822D03*
X541002Y71436D03*
X544402D03*
X548070Y79372D03*
X542460Y99172D03*
X539475Y118772D03*
X547395Y147302D03*
X543083Y146338D03*
X540460Y200392D03*
X544390Y236512D03*
X550390Y231742D03*
X548390Y236512D03*
X546390Y231742D03*
X542050Y231722D03*
X539639Y271972D03*
X539830Y274912D03*
X537720Y278212D03*
X547420Y306862D03*
X544920D03*
X549220Y339687D03*
X535720Y360862D03*
X546758Y360502D03*
X547810Y414472D03*
X549670Y419892D03*
X542870Y438320D03*
X548464Y456534D03*
X548780Y475932D03*
X548550Y480382D03*
X546210Y519642D03*
X541820Y575130D03*
X541722Y568054D03*
X537730Y577440D03*
X547020Y590332D03*
X550320Y583362D03*
X536626Y590500D03*
X537560Y598102D03*
X537648Y1290037D03*
X535058Y1290007D03*
X535148Y1287397D03*
X543660Y1302934D03*
X541100D03*
X538560D03*
X535110Y1292704D03*
Y1295584D03*
Y1298464D03*
X537650Y1292704D03*
X540210D03*
X537650Y1298464D03*
Y1295584D03*
X540210Y1298464D03*
Y1295584D03*
X536020Y1302904D03*
X545141Y1357401D03*
X549801D03*
X538737Y1365553D03*
X534737Y1364815D03*
X542947Y1367043D03*
X541475Y1364585D03*
X534737Y1367871D03*
X547471Y1358151D03*
X563482Y40826D03*
X554720Y32862D03*
X565184Y47982D03*
X558058Y46352D03*
X554983Y45312D03*
X553650Y48842D03*
X551470Y79372D03*
X567865Y92656D03*
X559000Y102862D03*
X561000Y98862D03*
X552395Y134340D03*
X566500Y125097D03*
X551231Y122671D03*
X564890Y142173D03*
X555220Y164787D03*
X555545Y156462D03*
X555195Y184862D03*
Y171862D03*
X554872Y196635D03*
X559400Y201162D03*
X557248Y198909D03*
X564600Y202662D03*
X552489Y212022D03*
X553402Y231292D03*
X552089Y253202D03*
Y257202D03*
X562461Y272161D03*
X561324Y301149D03*
X566730Y300992D03*
X555520Y309827D03*
X563790Y331846D03*
X561290D03*
X558790D03*
X562200Y419412D03*
X559300Y414112D03*
X559730Y434772D03*
X557829Y454479D03*
X558220Y459362D03*
X563281Y543113D03*
X563700Y538477D03*
X560640Y540613D03*
X566140Y554972D03*
Y551472D03*
X559927Y548457D03*
X556820Y570462D03*
X557430Y583572D03*
X566510Y1352217D03*
X554837Y1359315D03*
X557037Y1363715D03*
Y1357915D03*
Y1360815D03*
X554937Y1362315D03*
X552771Y1361045D03*
Y1363945D03*
X552131Y1358151D03*
X555057Y1449395D03*
X572500Y32862D03*
X568500D03*
X581500Y41862D03*
X573190Y42912D03*
X567507Y45869D03*
X575330Y47672D03*
X570208Y47982D03*
X579930Y72052D03*
X577300Y66682D03*
X577880Y75442D03*
X570150Y102862D03*
X579080Y119402D03*
X573360Y140532D03*
X573115Y161232D03*
X569470Y171702D03*
X581120Y155062D03*
X568245Y167112D03*
X579481Y198378D03*
X579170Y190092D03*
X579481Y194378D03*
Y206378D03*
X578450Y218562D03*
X579245Y221362D03*
X567730Y225362D03*
X578390D03*
X567730Y221362D03*
X581755Y236978D03*
X575359Y265132D03*
X582510Y296657D03*
X577676Y300268D03*
X577480Y303822D03*
X582510Y304052D03*
Y311571D03*
X570440Y331930D03*
X567630Y331958D03*
X574800Y322462D03*
X571830Y348772D03*
X572360Y351962D03*
X571720Y381862D03*
X575050Y383602D03*
X577720Y381862D03*
X574491Y376549D03*
X580370Y383670D03*
X581090Y426970D03*
X571930Y421232D03*
X571110Y442656D03*
X569490Y437600D03*
X571110Y446706D03*
X567320Y454962D03*
Y459962D03*
Y457462D03*
X577220Y449462D03*
X578920Y466462D03*
X583045Y488212D03*
X583220Y493212D03*
X568840Y501046D03*
X584173Y498422D03*
X568520Y504162D03*
Y506662D03*
X577470Y505592D03*
X578925Y516846D03*
X571627Y548124D03*
X569050Y578292D03*
X572057Y577242D03*
X571555Y1352487D03*
X570645Y1361358D03*
X576220Y1423862D03*
X571620Y1424492D03*
X584950Y54842D03*
X586260Y52222D03*
X599800Y43152D03*
X597955Y48047D03*
X593369Y45682D03*
X586600Y60602D03*
X590680Y83591D03*
X592307Y94262D03*
X597287D03*
X594720Y97220D03*
X588245Y132142D03*
X598410Y124102D03*
X598390Y126802D03*
X589690Y161732D03*
X592220Y173862D03*
X596795Y179287D03*
X590281Y180698D03*
X599720Y184887D03*
X593220D03*
X584795Y233362D03*
X591310Y219582D03*
X592220Y249362D03*
X595415Y246515D03*
X591727Y285862D03*
X593763Y293999D03*
X588850Y291622D03*
X599620Y314762D03*
X595520Y314862D03*
X583820Y314662D03*
X590820Y330962D03*
X590720Y327862D03*
Y324582D03*
X590470Y319192D03*
X593120Y342782D03*
X583685Y363271D03*
X586185D03*
X586070Y352302D03*
X591839Y426112D03*
X595380Y416660D03*
X591720Y433937D03*
X595520Y439762D03*
X597220Y458688D03*
X599080Y448062D03*
X584100Y477952D03*
X592520Y467662D03*
X590210Y484132D03*
X599645Y479862D03*
X598661Y486922D03*
X587100Y493842D03*
X592400Y479162D03*
X591070Y504900D03*
X594090Y501957D03*
X587100Y496342D03*
X591425Y522337D03*
X591500Y516862D03*
X596880Y534812D03*
X592340Y744624D03*
X598693Y742072D03*
X611810Y34400D03*
X612822Y43232D03*
X606880Y44682D03*
X614400Y46012D03*
X603063Y48023D03*
X606020Y84562D03*
X615220Y76862D03*
X615170Y73812D03*
X601220Y73862D03*
Y76862D03*
X603720Y98362D03*
X608620Y94162D03*
X617585Y97257D03*
X613020Y94162D03*
X617409D03*
X603880Y93902D03*
X600220Y96862D03*
X614384Y119342D03*
X606040Y153432D03*
X606190Y144002D03*
X602580Y151052D03*
X603019Y146399D03*
X615573Y179484D03*
X615572Y176442D03*
X611381Y200378D03*
Y209878D03*
X614200Y265792D03*
X605350Y293092D03*
X605870Y298172D03*
X605560Y303372D03*
X607590Y314732D03*
X609040Y317282D03*
X615635Y317637D03*
X614130Y328762D03*
X605305Y331162D03*
X615180Y336812D03*
X605898Y372984D03*
X609690Y402812D03*
X605220Y416362D03*
X610720Y436362D03*
X600800Y430900D03*
X614220Y436362D03*
X610720Y442862D03*
X614220D03*
Y447862D03*
X602910Y461862D03*
X610720Y457862D03*
X614220D03*
X610720Y452862D03*
X604360Y452120D03*
X614220Y467862D03*
Y472862D03*
Y477862D03*
X605469Y467562D03*
X610720Y462862D03*
X614220D03*
X601220Y486922D03*
X600645Y504362D03*
X606200Y510862D03*
X611870Y512560D03*
X606220Y517762D03*
X607328Y537481D03*
X610797Y537528D03*
X607720Y550862D03*
X610720D03*
X613220Y654662D03*
X603276Y741375D03*
X600460Y744912D03*
X613047Y741492D03*
X602768Y758385D03*
X616675Y31777D03*
X624633Y49193D03*
X629820Y42562D03*
Y45062D03*
X619562Y49193D03*
X624140Y46672D03*
X622271Y44782D03*
X629000Y67362D03*
X628590Y58622D03*
X622271Y57952D03*
X623300Y95762D03*
X620540Y100112D03*
X632300Y104472D03*
X626699Y119182D03*
X630951D03*
X631290Y153702D03*
X615970Y161522D03*
X628195Y175914D03*
X628194Y172872D03*
X628730Y216472D03*
X631730D03*
X628730Y220472D03*
Y224472D03*
X631730Y220472D03*
Y224472D03*
X622730Y230362D03*
X630795Y236862D03*
X618470Y265732D03*
X629564Y253127D03*
X621060Y271066D03*
X633150Y301457D03*
X627950Y298897D03*
X627600Y309134D03*
X632143Y306575D03*
X630220Y314362D03*
X623365Y316742D03*
X631146Y317768D03*
X619474Y331162D03*
X619100Y374638D03*
X621720Y373362D03*
X622490Y402162D03*
X628500Y402362D03*
X624220Y411362D03*
X629220D03*
X623220Y426362D03*
X625500Y421362D03*
X629220D03*
Y426362D03*
X628900Y431050D03*
X625620Y447862D03*
X625900Y431050D03*
X625620Y442862D03*
X629220D03*
X622220D03*
X617220Y436362D03*
X622220Y452862D03*
Y447862D03*
X629220Y457862D03*
X626400Y462812D03*
X625620Y457862D03*
X622220D03*
X629220Y452862D03*
X625620D03*
X629220Y447862D03*
X626390Y467882D03*
X626210Y478002D03*
X626310Y472902D03*
X629220Y462862D03*
X622220D03*
X622520Y467862D03*
X629220Y487310D03*
X622860D03*
X626720Y482880D03*
X623670Y507862D03*
X629480Y508862D03*
X633000Y508700D03*
X629920Y516652D03*
X623000Y546900D03*
X629220Y643462D03*
X626720D03*
X617252Y739354D03*
X623497Y748235D03*
X626017Y745083D03*
X620870Y762072D03*
X617940Y763552D03*
X630417Y757135D03*
X628970Y1670880D03*
X637220Y31462D03*
X643880Y42142D03*
X647447Y46322D03*
X641200Y46762D03*
X638500Y57362D03*
X635000D03*
X637000Y68142D03*
X634500Y73422D03*
X645330Y77132D03*
Y72972D03*
X640220Y85542D03*
X634690D03*
X647220Y96929D03*
X639901Y103462D03*
X640000Y108542D03*
X639970Y113892D03*
X640130Y166362D03*
X643170Y171362D03*
X649870Y181942D03*
X645263Y235689D03*
X640295Y234237D03*
X645109Y249202D03*
Y260202D03*
X643800Y294327D03*
Y298297D03*
Y306547D03*
Y302247D03*
X645990Y314482D03*
X643800Y310962D03*
X633350Y314362D03*
X647100Y357372D03*
X636075Y389862D03*
X649075Y389937D03*
X632620Y389862D03*
X645925Y389937D03*
X638700Y400962D03*
X647700Y399162D03*
X643500Y400962D03*
X643940Y411482D03*
X637220Y411362D03*
X644220Y426362D03*
X640720Y418862D03*
X644220Y421362D03*
X637220Y416362D03*
Y426362D03*
X637195Y421362D03*
X647420Y434162D03*
X640720Y431362D03*
X644000Y438862D03*
X644220Y431362D03*
X638250Y439250D03*
X637220Y431362D03*
X644220Y452862D03*
X640820Y457902D03*
X637220Y452862D03*
X640720D03*
X640920Y447862D03*
X644220D03*
X637195Y457862D03*
X637220Y467862D03*
Y472862D03*
Y477862D03*
X644220D03*
Y462862D03*
X641235Y477377D03*
X640798Y472934D03*
X637220Y462862D03*
X640820Y467862D03*
X640620Y483422D03*
X642580Y508172D03*
X645220Y504362D03*
X646815Y517974D03*
X648296Y528255D03*
X637020Y522362D03*
X642630Y517870D03*
X640130D03*
X633147Y758595D03*
X647725Y1643719D03*
X643725Y1643467D03*
X648225Y1658482D03*
X642725Y1658562D03*
X635410Y1664220D03*
X637540Y1669480D03*
X636702Y1677610D03*
X645725Y1691182D03*
X640725Y1691452D03*
X650725Y1690682D03*
X646225Y1708169D03*
X642225Y1708457D03*
X648220Y1716912D03*
X636160Y1710662D03*
X639745Y1722362D03*
Y1718362D03*
X648220Y1722921D03*
X651943Y33535D03*
X663543Y43328D03*
X656950Y59012D03*
X651680Y73812D03*
X656500Y69662D03*
X661587D03*
X661600Y75562D03*
X657165Y79131D03*
X656426Y75431D03*
X652320Y123362D03*
X662498Y124960D03*
X650790Y149871D03*
Y140699D03*
X662880Y149912D03*
Y146912D03*
X651730Y177212D03*
X662560Y214152D03*
X662780Y210362D03*
Y205362D03*
Y207862D03*
X659880Y210762D03*
Y205762D03*
Y208262D03*
X650705Y270947D03*
X662891Y357442D03*
X662680Y354362D03*
X651520Y378662D03*
X658720Y399862D03*
X652000Y402362D03*
X653100Y407862D03*
X655820Y452662D03*
X655800Y461432D03*
X652195Y457862D03*
X655820Y467662D03*
X663000Y489500D03*
X663014Y493860D03*
X655220Y486862D03*
X661865Y505334D03*
X663720Y523806D03*
X665990Y517131D03*
X661220Y526862D03*
X650794Y515039D03*
X652577Y1000775D03*
X653690Y1392362D03*
X653761Y1396300D03*
X663187Y1395170D03*
Y1397720D03*
X666303Y1403476D03*
X663687Y1407279D03*
X654540Y1427605D03*
Y1424205D03*
X661100Y1451012D03*
X662660Y1548120D03*
X663410Y1553982D03*
X664590Y1631620D03*
X663097Y1642667D03*
X651725Y1643397D03*
X656725Y1660769D03*
X663118Y1655557D03*
X663043Y1651557D03*
X663145Y1672862D03*
Y1668862D03*
X653420Y1698662D03*
X663645Y1722862D03*
X680200Y39062D03*
X677560Y40572D03*
X672250Y40812D03*
X666943Y43328D03*
X682290Y46822D03*
X670612Y47264D03*
X674012D03*
X674035Y74522D03*
X678050Y58157D03*
X673987Y87662D03*
X677820Y89462D03*
X680578Y75992D03*
X674540Y80652D03*
X670800Y85932D03*
X667940Y80142D03*
X671320Y91192D03*
X677790Y104880D03*
X673720Y110362D03*
X674145Y113487D03*
X677978Y119668D03*
Y115668D03*
X675560Y117120D03*
X668300Y132400D03*
X665650Y147692D03*
X673713Y237725D03*
X674731Y359924D03*
X680600Y364282D03*
X683100Y369550D03*
X673220Y388362D03*
X675295Y399862D03*
X670720D03*
X668695Y408362D03*
Y404262D03*
X665870Y433942D03*
X675220Y508862D03*
X680220Y495887D03*
X670220Y503837D03*
X680220Y508862D03*
X675220Y521862D03*
X670720D03*
Y516862D03*
X680220Y530362D03*
X673340Y530922D03*
X673617Y744735D03*
X669700Y746626D03*
X677887Y742121D03*
X669778Y759929D03*
X670037Y1336396D03*
X664987D03*
X667487D03*
X664987Y1338896D03*
X667487D03*
X670037D03*
Y1333896D03*
X664987D03*
X667487D03*
X664987Y1348896D03*
X667487D03*
X664987Y1346396D03*
X667487D03*
X664987Y1343896D03*
Y1341396D03*
X667487D03*
Y1343896D03*
X670037Y1341396D03*
Y1343896D03*
Y1346396D03*
Y1348896D03*
X679881Y1399280D03*
X673477Y1409386D03*
X669477Y1406694D03*
X677619Y1408887D03*
X675876Y1406619D03*
X669477Y1409415D03*
X674149Y1434149D03*
X671149D03*
X668649D03*
X674149Y1426149D03*
Y1431149D03*
Y1428649D03*
X671149Y1426149D03*
X668649D03*
X671149Y1431149D03*
X668649Y1428649D03*
Y1431149D03*
X671149Y1428649D03*
X677319Y1428359D03*
Y1433359D03*
Y1430859D03*
X682160Y1548040D03*
X665410Y1548180D03*
X679207Y1560482D03*
X678877Y1566798D03*
X678621Y1571072D03*
X678610Y1582154D03*
X666560Y1581000D03*
X678619Y1579070D03*
X666600Y1584900D03*
X678900Y1595400D03*
X678771Y1585945D03*
X666700Y1595500D03*
X678900Y1589800D03*
X666700Y1591900D03*
X678900Y1592600D03*
X666700Y1588500D03*
X679640Y1617520D03*
Y1614000D03*
X679270Y1604040D03*
X675710Y1620320D03*
X673420Y1650057D03*
X671290Y1646320D03*
X668695Y1662235D03*
X671610Y1673792D03*
X671620Y1668303D03*
X677940Y1670110D03*
X678490Y1695660D03*
X674195Y1712362D03*
X675120Y1716242D03*
X674195Y1728362D03*
X672270Y1721612D03*
X687120Y39632D03*
X692289Y40633D03*
X689940Y38952D03*
X696800Y42108D03*
X696838Y47940D03*
X683440Y42832D03*
X687344Y46940D03*
X692389Y46439D03*
X694751Y70212D03*
X690027Y70142D03*
X685780Y70022D03*
X699475Y69982D03*
X685968Y58157D03*
X694400D03*
X681980D03*
X690510Y59132D03*
X696700Y72462D03*
X692389Y72692D03*
X687664Y73202D03*
X696370Y78512D03*
X696727Y81552D03*
Y84052D03*
X681053Y104668D03*
X695720Y102162D03*
X694220Y104862D03*
X688019Y109845D03*
X687030Y113090D03*
X687034Y115896D03*
X697615Y123697D03*
X687238Y171071D03*
X685600Y364282D03*
X690600D03*
X695600D03*
X683500Y381200D03*
X685210Y388852D03*
X694920Y388797D03*
X687500Y399402D03*
X692330Y388751D03*
X685220Y391652D03*
X692402Y391250D03*
X695220Y399862D03*
X685270Y408362D03*
Y404262D03*
X692400Y404682D03*
X683320Y490662D03*
X685220Y495887D03*
X690580Y482992D03*
X694510Y482942D03*
X686120Y481862D03*
X695220Y495887D03*
X690220D03*
X695220Y508862D03*
X685220D03*
X690220Y506362D03*
X685220Y503837D03*
X690220Y508882D03*
X690330Y503530D03*
X695257Y503847D03*
X695220Y516852D03*
X685220D03*
X690220Y519662D03*
X695220D03*
X689720Y530862D03*
X695220Y530662D03*
X683457Y745175D03*
X696810Y1300162D03*
X692280Y1302532D03*
X684555Y1338896D03*
X689605Y1336396D03*
Y1338896D03*
X687105Y1336396D03*
X684555D03*
X687105Y1338896D03*
X689605Y1333896D03*
X687105D03*
X684555D03*
X689605Y1348896D03*
X687105D03*
X689605Y1346396D03*
X687105D03*
X684555Y1341396D03*
Y1343896D03*
Y1346396D03*
Y1348896D03*
X689605Y1341396D03*
Y1343896D03*
X687105Y1341396D03*
Y1343896D03*
X684541Y1399280D03*
X682211Y1400030D03*
X686871D03*
X691777Y1405594D03*
Y1399794D03*
X689577Y1401194D03*
X687511Y1402924D03*
X691777Y1402694D03*
X689677Y1404194D03*
X687511Y1405824D03*
X694596Y1396198D03*
X694129Y1420283D03*
X696754Y1419809D03*
X691129Y1420283D03*
X681899Y1434049D03*
Y1426049D03*
Y1431049D03*
Y1428549D03*
X694129Y1423303D03*
X691129D03*
X696694Y1427949D03*
Y1425449D03*
Y1430449D03*
X696784Y1422614D03*
X683930Y1552562D03*
Y1555062D03*
Y1557562D03*
X692100Y1567190D03*
X692026Y1580490D03*
X697197Y1640667D03*
X697122Y1636667D03*
X689200Y1648843D03*
X686220Y1640667D03*
X697595Y1666862D03*
X687045Y1673362D03*
X706370Y46782D03*
X701838Y42202D03*
Y47940D03*
X703900Y72112D03*
X701400D03*
X713000Y69662D03*
X697720Y58162D03*
X710200Y69662D03*
X706867Y58197D03*
X703100Y58157D03*
X712500Y79862D03*
X710486Y77695D03*
X700500Y74862D03*
X698710Y86035D03*
X705390Y85792D03*
X703000Y84862D03*
X706720Y100462D03*
X699220Y102162D03*
X702720D03*
X701220Y104862D03*
X697720D03*
X712733Y117488D03*
Y114588D03*
X712290Y106722D03*
X712340Y128093D03*
X700600Y125309D03*
X707008Y125804D03*
X705800Y167788D03*
Y171188D03*
X704770Y182999D03*
Y179599D03*
Y194810D03*
Y191410D03*
Y218432D03*
Y206621D03*
Y215032D03*
Y203221D03*
X700600Y364282D03*
X705600D03*
X710600D03*
X709000Y354000D03*
X715600Y363900D03*
X705700Y361400D03*
X709400Y378200D03*
X713220Y378362D03*
X711200Y396500D03*
X707220Y399362D03*
X709160Y386730D03*
X713220Y388362D03*
X707400Y396200D03*
X713220Y399862D03*
X705195Y408362D03*
Y404262D03*
X705780Y411022D03*
X712770Y406822D03*
X705720Y488862D03*
X703220Y490362D03*
X705720Y484862D03*
X711220Y503842D03*
X705220D03*
Y508862D03*
X711220Y508882D03*
X710720Y521362D03*
X705220D03*
X701757Y521324D03*
X705220Y530362D03*
X710940Y591172D03*
X698602Y580536D03*
X705240Y594020D03*
X702740D03*
X712060Y638542D03*
X708680Y638812D03*
X708310Y646032D03*
X704320Y645262D03*
X704000Y740862D03*
X700500Y745862D03*
X703545Y745907D03*
X711720Y1286162D03*
X707720Y1290162D03*
X705720Y1286662D03*
X704795Y1294559D03*
X707320Y1301162D03*
X708137Y1336396D03*
Y1338896D03*
X703087Y1336396D03*
X705587D03*
Y1338896D03*
X703087D03*
X708137Y1333896D03*
X705587D03*
X703087D03*
Y1346396D03*
X705587D03*
X703087Y1348896D03*
X705587D03*
X708137Y1341396D03*
Y1343896D03*
X705587Y1341396D03*
X703087D03*
Y1343896D03*
X705587D03*
X708137Y1348896D03*
Y1346396D03*
X701330Y1395195D03*
Y1397695D03*
X704446Y1403476D03*
X701830Y1407326D03*
X711620Y1409386D03*
X707620Y1406694D03*
Y1409660D03*
X699754Y1419809D03*
X699694Y1427949D03*
Y1425449D03*
Y1430449D03*
X699784Y1422614D03*
X712222Y1570703D03*
X702112Y1571683D03*
Y1575683D03*
Y1579683D03*
X711102Y1575683D03*
X714162Y1574333D03*
X713052Y1579683D03*
X712582Y1584843D03*
X704497Y1598927D03*
X702112Y1587683D03*
Y1591683D03*
X713102Y1601307D03*
X715775Y1599024D03*
X714380Y1589960D03*
X702112Y1595683D03*
X712512Y1596338D03*
X711350Y1590720D03*
X711780Y1614590D03*
X704370Y1604580D03*
X706103Y1617107D03*
X708857Y1613462D03*
X710570Y1629890D03*
X708830Y1623115D03*
X705516Y1620296D03*
X710540Y1636070D03*
X708999Y1646762D03*
X703719Y1646768D03*
X697595Y1662862D03*
X700460Y1660918D03*
X709678Y1658485D03*
X697730Y1677460D03*
X704759Y1677001D03*
X724620Y40062D03*
X728720Y43562D03*
X719820Y45862D03*
X717320Y44062D03*
X729293Y58062D03*
X724644Y58362D03*
X719949Y58862D03*
X715990Y69662D03*
X725740Y69580D03*
X721990Y69762D03*
X718900Y69662D03*
X727700Y60562D03*
X728591Y71960D03*
X722415Y77862D03*
X718425Y77882D03*
X728090Y75132D03*
X719100Y85262D03*
X727518Y90984D03*
X715933Y117488D03*
Y114588D03*
X729933Y108388D03*
X728733Y132088D03*
Y129288D03*
X720433Y135088D03*
X717433D03*
X728733Y126388D03*
X719933Y124488D03*
X723133D03*
X715940Y157362D03*
X718213Y159241D03*
X720633Y160788D03*
X716698Y185687D03*
Y173687D03*
Y177087D03*
Y197187D03*
Y200587D03*
Y189087D03*
Y209021D03*
Y212421D03*
X717020Y220862D03*
X719720Y220142D03*
X722500Y365500D03*
X724897Y353887D03*
X721989Y351234D03*
X727000Y365500D03*
X731400D03*
X722500Y374100D03*
X727000D03*
X731400Y375000D03*
X718720Y381892D03*
X728220Y388362D03*
X723195Y408362D03*
Y404262D03*
X725220Y399862D03*
X723220Y508882D03*
X717220D03*
X729220D03*
Y503842D03*
X723220D03*
X717220D03*
X714000Y496132D03*
X723120Y525362D03*
X728220Y521362D03*
X717220D03*
X717296Y525407D03*
X723220Y516852D03*
X729220D03*
X717220D03*
X729212Y531700D03*
X729328Y583076D03*
X729295Y586113D03*
X725207Y579371D03*
X722707D03*
X715860Y585540D03*
X714320Y597462D03*
X723450Y597072D03*
X720240Y598292D03*
X715420Y639162D03*
X719190Y646642D03*
X717720Y643262D03*
X715220D03*
X723340Y642922D03*
X714087Y745865D03*
X720697Y765862D03*
X723460Y1245632D03*
X714720Y1286162D03*
X723054Y1333896D03*
X725604D03*
X728104D03*
X725604Y1338896D03*
X723054Y1336396D03*
X725604D03*
X728104Y1338896D03*
Y1336396D03*
X723054Y1338896D03*
X725604Y1346396D03*
X728104D03*
X725604Y1348896D03*
X728104D03*
X725604Y1343896D03*
Y1341396D03*
X728104Y1343896D03*
Y1341396D03*
X723054Y1348896D03*
Y1346396D03*
Y1343896D03*
Y1341396D03*
X725654Y1405824D03*
Y1402924D03*
X727720Y1401194D03*
X727820Y1404194D03*
X718024Y1399280D03*
X722684D03*
X720354Y1400030D03*
X725014D03*
X715762Y1408887D03*
X714019Y1406619D03*
X717300Y1547370D03*
X715792Y1567461D03*
X720370Y1566910D03*
X723520Y1561604D03*
X724712Y1566820D03*
X716612Y1584635D03*
X717152Y1570093D03*
X728977Y1574453D03*
X717402Y1574433D03*
X724465Y1580092D03*
X722465Y1582092D03*
X726465D03*
X723942Y1574123D03*
X724465Y1590950D03*
X722465Y1588950D03*
X726465D03*
X729052Y1602518D03*
X726092Y1598483D03*
X720987Y1599568D03*
X723542Y1612702D03*
X721488Y1610945D03*
X725910Y1611900D03*
X716688Y1610055D03*
X719168Y1612016D03*
X718195Y1647300D03*
X714203Y1642926D03*
X729150Y1641690D03*
X726810Y1652430D03*
X714071Y1663842D03*
X722630Y1655740D03*
X724500Y1680400D03*
X718758Y1673800D03*
X745900Y40362D03*
X733314Y40862D03*
X740100Y41162D03*
X746100Y46262D03*
X736620Y45262D03*
X745474Y57932D03*
X733642Y58062D03*
X741377Y57932D03*
X737595D03*
X732793Y71436D03*
X736193D03*
X742620Y71762D03*
X735880Y60662D03*
X740819Y82362D03*
X736720Y101662D03*
X745035Y94632D03*
X735770Y94988D03*
X739823Y91052D03*
X741308Y108742D03*
X738600Y136600D03*
X736060Y145532D03*
X740220Y145362D03*
X745725Y167537D03*
X732720Y231362D03*
X734220Y238362D03*
X744247Y312598D03*
X741800Y363200D03*
X742090Y356082D03*
X735600Y351400D03*
X735800Y365500D03*
X732700Y351500D03*
X740200Y375100D03*
X736220Y380787D03*
X742720Y380262D03*
X735800Y375000D03*
X738220Y388362D03*
X742160Y396452D03*
X738220Y383862D03*
X745720Y399862D03*
X735220Y410842D03*
X735745Y408362D03*
Y404262D03*
X733720Y399862D03*
X743980Y443482D03*
X740740Y473822D03*
X741420Y494162D03*
X747600Y506592D03*
X735220Y508862D03*
X745220Y503842D03*
X735220D03*
X735430Y516862D03*
X745220Y522362D03*
Y516852D03*
X730220Y523362D03*
X740840Y521982D03*
X735173Y521362D03*
X736480Y531722D03*
X738980D03*
X733922Y531712D03*
X733117Y580071D03*
Y582571D03*
X733134Y585672D03*
X736710Y603842D03*
Y607242D03*
X735620Y613862D03*
X730690Y655532D03*
X744538Y746524D03*
X737609Y744282D03*
X730889Y746834D03*
X740820Y741762D03*
X729920Y1405594D03*
X732226Y1396212D03*
X729920Y1399794D03*
Y1402694D03*
X733336Y1568341D03*
Y1565341D03*
Y1559341D03*
Y1562341D03*
X730336Y1559341D03*
Y1562341D03*
X745336D03*
Y1559341D03*
Y1565341D03*
Y1568341D03*
X742336Y1562341D03*
Y1559341D03*
Y1565341D03*
Y1568341D03*
X739336Y1562341D03*
Y1559341D03*
Y1565341D03*
Y1568341D03*
X736336D03*
Y1565341D03*
Y1559341D03*
Y1562341D03*
X733336Y1574341D03*
Y1571341D03*
X745336Y1574341D03*
Y1571341D03*
X742336Y1574341D03*
Y1571341D03*
X739336Y1574341D03*
Y1571341D03*
X736336D03*
Y1574341D03*
X735300Y1648760D03*
X737080Y1655820D03*
X735080Y1662980D03*
X740840Y1655590D03*
X732705Y1669450D03*
X754620Y51602D03*
X758620D03*
X749477Y57932D03*
X755700Y59942D03*
Y62442D03*
X758200Y59942D03*
Y62442D03*
X760700Y59942D03*
Y62442D03*
X747487Y71429D03*
X757693Y100653D03*
Y96423D03*
X750700Y106642D03*
X754800Y97082D03*
X750033Y92888D03*
Y89988D03*
X757340Y92562D03*
X748033Y116288D03*
X747230Y108572D03*
X760390Y111810D03*
X751220Y137864D03*
X747200Y251500D03*
X757150Y280592D03*
X758720Y283262D03*
X759920Y280562D03*
X758412Y298790D03*
X755305Y298847D03*
X748820Y284562D03*
X758390Y295450D03*
X748498Y309640D03*
X759637Y311585D03*
X757936Y303908D03*
X760670Y317432D03*
X747554Y384962D03*
X757430Y408212D03*
X760469Y442647D03*
X750290Y462162D03*
X757365Y459862D03*
X752500Y495762D03*
X757238Y483862D03*
X756642Y496522D03*
Y501744D03*
X751220Y522362D03*
Y516852D03*
X759790Y525522D03*
X755940Y516862D03*
X756650Y526072D03*
X761710Y517651D03*
X757020Y530462D03*
X759820D03*
X754220D03*
X762345Y1284542D03*
Y1287542D03*
Y1290542D03*
X762205Y1293272D03*
X757720Y1375462D03*
Y1384062D03*
X758020Y1397862D03*
X758420Y1406862D03*
X758120Y1414762D03*
X755420Y1426262D03*
Y1422862D03*
X748336Y1562341D03*
Y1559341D03*
Y1565341D03*
Y1568341D03*
X751336D03*
Y1565341D03*
Y1559341D03*
Y1562341D03*
X748336Y1574341D03*
Y1571341D03*
X760112Y1579183D03*
X749612Y1579023D03*
X749652Y1586407D03*
X760152Y1583183D03*
X749612Y1583023D03*
X760112Y1592183D03*
Y1587183D03*
X749662Y1590733D03*
X749612Y1594683D03*
X758360Y1589661D03*
X761716Y1661194D03*
X751620Y1674312D03*
X759859Y1686090D03*
X759359Y1729520D03*
X752875Y1726670D03*
X774059Y68912D03*
X773420Y143462D03*
X772328Y153728D03*
X771426Y158026D03*
X766320Y264892D03*
X763320D03*
X771630Y258102D03*
X762420Y280562D03*
X777420Y277962D03*
X769789Y296231D03*
X777467Y296315D03*
X769860Y302462D03*
X771377Y314139D03*
X771490Y354942D03*
X768490D03*
X777420Y354962D03*
X774490Y354942D03*
X765000Y354862D03*
X771960Y375162D03*
X767960Y369662D03*
X776000D03*
X764000D03*
X766195Y393212D03*
X773245Y398212D03*
X766195Y403212D03*
Y413212D03*
X773245Y403212D03*
Y408212D03*
X768910Y403260D03*
X771050Y416940D03*
X766195Y423212D03*
Y428212D03*
X768701Y418662D03*
X774982Y446908D03*
X772365Y454862D03*
X768720Y459862D03*
X765315Y454862D03*
Y459862D03*
X772365D03*
X765360Y475412D03*
X765335Y469552D03*
X772364Y475062D03*
X772365Y469862D03*
X765315Y479862D03*
X772365Y488862D03*
X776170Y493422D03*
X766510Y493452D03*
X765386Y483572D03*
X773530Y507062D03*
X765810Y506342D03*
X769745Y502600D03*
X775378Y502502D03*
X765521Y525364D03*
X769220Y530362D03*
X765720D03*
X777020D03*
X772020Y746562D03*
X774384Y744088D03*
X762562Y746444D03*
X769921Y742095D03*
X767421D03*
X764921D03*
X769337Y760775D03*
X762617Y758885D03*
X765345Y1284542D03*
X768335Y1284612D03*
X765345Y1287542D03*
Y1290542D03*
X768335Y1287612D03*
Y1290612D03*
X765205Y1293272D03*
X768195Y1293342D03*
X778005Y1294092D03*
X768520Y1384062D03*
Y1375462D03*
X768620Y1397262D03*
X775375Y1403561D03*
X767820Y1414762D03*
X763152Y1581893D03*
Y1577893D03*
Y1573793D03*
X773952Y1580493D03*
X768714Y1571203D03*
X769452Y1584393D03*
X770252Y1587268D03*
X763152Y1590893D03*
Y1594893D03*
X774052Y1590293D03*
X776922Y1590444D03*
X764920Y1695347D03*
X766880Y1689020D03*
X766603Y1721797D03*
X785180Y120947D03*
X792680D03*
X790180D03*
X787680D03*
X783940Y118637D03*
X786440D03*
X788940D03*
X781440D03*
X782553Y150031D03*
Y152531D03*
X779893Y147521D03*
Y150021D03*
X780820Y278262D03*
X785135Y274822D03*
X785200Y271400D03*
X794057Y301569D03*
X794220Y296062D03*
X785220Y284762D03*
X792943Y312642D03*
X784415Y313734D03*
X793896Y309026D03*
X793820Y304962D03*
X779120Y303410D03*
Y308755D03*
X785000Y355000D03*
X779920Y354962D03*
X782420D03*
X790120Y354862D03*
X792620D03*
X787600Y354900D03*
X795520Y393462D03*
X791075Y388000D03*
X781195Y393212D03*
X781320Y398212D03*
X787720Y408362D03*
X781195Y413212D03*
Y423212D03*
X785560Y417902D03*
X788120Y422942D03*
X791040Y422892D03*
X793660Y422842D03*
X785720Y427862D03*
X789230Y414942D03*
X780020Y441437D03*
Y445287D03*
X784730Y432682D03*
X787320Y444862D03*
Y439862D03*
X791582Y435352D03*
X781205Y454402D03*
X780315Y459862D03*
X787320Y454862D03*
Y449862D03*
Y459862D03*
X787360Y469862D03*
X786220Y464862D03*
X796315Y469290D03*
X780315Y464862D03*
X783340Y474802D03*
X782690Y488862D03*
X793220Y493362D03*
X781170Y493422D03*
X785800Y482762D03*
X793875Y483262D03*
X778670Y493422D03*
X783600Y502462D03*
X783450Y522462D03*
X783400Y511902D03*
X789720Y589862D03*
X785220Y581362D03*
X789720Y587362D03*
X791720Y593862D03*
X793720Y595862D03*
X791969Y618384D03*
X794720Y617862D03*
X783507Y761875D03*
X794157Y761295D03*
X782515Y766702D03*
X791140Y761693D03*
X792045Y1284542D03*
Y1290542D03*
Y1287542D03*
X791905Y1293272D03*
X791260Y1388662D03*
X790380Y1432132D03*
X784352Y1568293D03*
Y1565293D03*
Y1559293D03*
Y1562293D03*
X781352Y1568293D03*
Y1565293D03*
Y1559293D03*
Y1562293D03*
X793352D03*
Y1559293D03*
Y1565293D03*
Y1568293D03*
X790352Y1562293D03*
Y1559293D03*
Y1565293D03*
Y1568293D03*
X787352D03*
Y1565293D03*
Y1559293D03*
Y1562293D03*
X784352Y1574293D03*
Y1571293D03*
X781352Y1574293D03*
Y1571293D03*
X793352Y1574293D03*
Y1571293D03*
X790352Y1574293D03*
Y1571293D03*
X787352D03*
Y1574293D03*
X808800Y267900D03*
X810920Y280062D03*
X798204Y279146D03*
X797924Y298358D03*
X806450Y310362D03*
X803620Y302962D03*
X805870Y304812D03*
X799720Y300462D03*
X795920Y312662D03*
X803280Y354982D03*
X800646Y354921D03*
X795220Y354862D03*
X806000Y360600D03*
X798400D03*
X805910Y355012D03*
X797900Y354800D03*
X795520Y398212D03*
X800352Y408389D03*
X803120Y428762D03*
X797720Y428412D03*
X798370Y439932D03*
X802010Y439940D03*
X802790Y433832D03*
X795320Y439862D03*
X805720Y432902D03*
X801750Y444330D03*
X795320Y444862D03*
X810860Y454862D03*
X802810D03*
X795320D03*
Y449862D03*
X802810Y464862D03*
Y449862D03*
X810860Y459862D03*
X802810D03*
X795320D03*
X810860Y449862D03*
X798990Y474862D03*
X802865D03*
X795320Y464862D03*
X810815Y474862D03*
X810860Y464862D03*
X810815Y469862D03*
X807220Y493362D03*
X801940Y485932D03*
X804510Y486122D03*
X809510D03*
X799230Y485922D03*
X812510Y486422D03*
X802790Y495652D03*
X805470Y510522D03*
X807640Y506672D03*
X808100Y509900D03*
X797420Y512503D03*
X805445Y587582D03*
X810720Y586862D03*
X811143Y605265D03*
X807945Y594362D03*
X803220D03*
X797200Y599883D03*
X795720Y614862D03*
X796702Y761195D03*
X810850Y770272D03*
X799577Y760985D03*
X807000Y757562D03*
X798035Y1284612D03*
X795045Y1284542D03*
X798035Y1290612D03*
Y1287612D03*
X795045Y1290542D03*
Y1287542D03*
X797895Y1293342D03*
X794905Y1293272D03*
X806323Y1343076D03*
X812130Y1343022D03*
X809210Y1343062D03*
X804100Y1435010D03*
X800000Y1431100D03*
X799352Y1562293D03*
Y1559293D03*
Y1565293D03*
Y1568293D03*
X796352Y1562293D03*
Y1559293D03*
Y1565293D03*
Y1568293D03*
X799352Y1574293D03*
Y1571293D03*
X796352Y1574293D03*
Y1571293D03*
X804652Y1581793D03*
Y1573793D03*
X812652Y1577793D03*
X801652Y1584539D03*
X812698Y1587047D03*
X804652Y1597793D03*
Y1585993D03*
X799152Y1586507D03*
X804652Y1589793D03*
Y1609793D03*
X827114Y115223D03*
X823114D03*
X814570Y145952D03*
X814531Y139851D03*
X820900Y147112D03*
X815060Y280072D03*
X813490Y273862D03*
X816220Y277162D03*
X813293Y287062D03*
X826300Y311962D03*
X823800D03*
X818000Y378800D03*
X813210Y374292D03*
X815710D03*
X825003Y389012D03*
Y397276D03*
X819220Y397664D03*
X824980Y413260D03*
X819220Y412264D03*
X823600Y421194D03*
X815310Y440100D03*
X816810Y464862D03*
X825100Y468900D03*
X824860Y464862D03*
X816400Y472900D03*
X820720Y493862D03*
X822415Y479600D03*
X821720Y511082D03*
X814305Y499503D03*
X819320Y502347D03*
X821720Y527082D03*
X815650Y516807D03*
X821720Y515082D03*
Y523082D03*
X820220Y586862D03*
X814220Y582530D03*
X823720Y594862D03*
X820470Y595112D03*
X815120Y593582D03*
X820613Y744641D03*
X823589Y746924D03*
X822374Y757039D03*
X814770Y763874D03*
X815789Y1008845D03*
X826090Y1334362D03*
Y1339362D03*
Y1329362D03*
Y1344362D03*
X820920Y1344342D03*
X818420D03*
X823352Y1565293D03*
Y1562293D03*
Y1559293D03*
Y1568293D03*
X826352Y1565293D03*
Y1562293D03*
Y1559293D03*
Y1568293D03*
X823352Y1571293D03*
Y1574293D03*
X826352Y1571293D03*
Y1574293D03*
X815652Y1582570D03*
Y1573793D03*
X813352Y1590893D03*
X812652Y1593793D03*
X815551D03*
X818652Y1590444D03*
X812652Y1605793D03*
Y1601793D03*
X836779Y68008D03*
X828600Y61752D03*
X839898Y87248D03*
X841584Y94181D03*
X837250Y93221D03*
X839360Y114862D03*
X835114Y115223D03*
X845220Y135862D03*
Y129362D03*
X829114Y147123D03*
X828145Y160362D03*
X838220Y163862D03*
X835220D03*
X837320Y175112D03*
X842720Y181360D03*
X837160Y218212D03*
Y213207D03*
X844526Y204968D03*
X838820Y206872D03*
X837500Y229642D03*
X840063Y285022D03*
X839450Y272662D03*
X835400Y268800D03*
X829620Y280345D03*
X829820Y275045D03*
X840850Y278948D03*
X829720Y292762D03*
X839860Y294702D03*
X827620Y302962D03*
X830417Y311865D03*
X836300Y418800D03*
X832400Y427100D03*
X840400Y418900D03*
X831720Y457700D03*
X839640Y449612D03*
X832700Y446800D03*
X830600Y449200D03*
X838220Y459562D03*
X841200Y456500D03*
X832720Y494862D03*
X829720D03*
X838645Y492862D03*
X830870Y480010D03*
X832590Y512888D03*
X829745Y502082D03*
X832370Y525849D03*
X843287Y527817D03*
X841461Y525849D03*
X840990Y529786D03*
X828009Y587913D03*
X831705Y593877D03*
X829230Y582772D03*
X831530Y651932D03*
X830587Y741205D03*
X833120Y743392D03*
X838587Y766825D03*
X841827Y766795D03*
X837127Y758976D03*
X829420Y758422D03*
X841997Y773085D03*
X838020Y1232432D03*
X832090Y1326862D03*
Y1331862D03*
Y1336862D03*
Y1341862D03*
X829352Y1565293D03*
Y1562293D03*
Y1559293D03*
Y1568293D03*
X832352D03*
Y1565293D03*
Y1559293D03*
Y1562293D03*
X835352Y1568293D03*
Y1565293D03*
Y1559293D03*
Y1562293D03*
X838352Y1568293D03*
Y1565293D03*
Y1559293D03*
Y1562293D03*
X841352Y1568293D03*
Y1565293D03*
Y1559293D03*
Y1562293D03*
X829352Y1574293D03*
Y1571293D03*
X832352D03*
Y1574293D03*
X835352Y1571293D03*
Y1574293D03*
X838352Y1571293D03*
Y1574293D03*
X841352Y1571293D03*
Y1574293D03*
X843652Y1584539D03*
X841152Y1586507D03*
X858629Y60293D03*
X850015Y87341D03*
X843855Y87711D03*
X847472Y94754D03*
X847660Y113962D03*
X853100Y113762D03*
X854100Y132972D03*
X854220Y135862D03*
Y129362D03*
X854200Y138562D03*
X848745Y160187D03*
X848709Y156752D03*
X848360Y182872D03*
X845720Y181362D03*
X855858Y212425D03*
X855933Y215375D03*
X860050Y215310D03*
X847580Y232222D03*
X853828Y269043D03*
X850133Y271049D03*
X861865Y273730D03*
X850093Y286625D03*
X855480Y299692D03*
X856243Y286447D03*
X859920Y308852D03*
X859740Y399081D03*
X846040Y399210D03*
X846490Y422131D03*
X850610Y444352D03*
X851606Y447927D03*
X844210Y455902D03*
X846700Y476900D03*
X855200D03*
X857620Y492862D03*
X858600Y511130D03*
X848620Y509752D03*
X853070Y515447D03*
X857195Y522162D03*
X859888Y593970D03*
X859054Y583752D03*
X845523Y582126D03*
X856520Y751262D03*
X859450Y750462D03*
X844957Y763065D03*
X854620Y1242125D03*
X854237Y1250358D03*
X846652Y1581793D03*
Y1573793D03*
X854652Y1577793D03*
X857652Y1582570D03*
Y1573793D03*
X854777Y1586968D03*
X846652Y1597793D03*
X855352Y1590893D03*
X854652Y1593793D03*
X846652Y1585993D03*
X857551Y1593793D03*
X846652Y1589793D03*
X854652Y1605793D03*
Y1601793D03*
X846652Y1609793D03*
X862930Y70072D03*
X866330D03*
X862452Y151590D03*
X867620Y154362D03*
X871145Y163862D03*
X871580Y183370D03*
X875169Y185113D03*
X864859Y187110D03*
X873200Y194262D03*
X871890Y196740D03*
X877971Y196652D03*
X867528Y231788D03*
X875543Y266447D03*
X867700Y268262D03*
X875543Y269347D03*
X863747Y280870D03*
X867237Y273325D03*
X868552Y285537D03*
X874243Y287047D03*
X877322Y296051D03*
X872320Y304936D03*
X869820D03*
X867320D03*
X864820D03*
X860531Y375826D03*
X870700Y386476D03*
Y398620D03*
Y402581D03*
X868113Y409372D03*
X870513Y414276D03*
X862320Y431462D03*
X863415Y445829D03*
X860574Y445404D03*
X861080Y459742D03*
X870360Y493042D03*
X862620Y507162D03*
X868110Y499142D03*
X865290Y499032D03*
X865810Y521862D03*
X866820Y736562D03*
X863925Y737697D03*
X864680Y751582D03*
X874155Y756993D03*
X864700Y778300D03*
X868352Y1568293D03*
Y1565293D03*
Y1559293D03*
Y1562293D03*
X865352Y1568293D03*
Y1565293D03*
Y1559293D03*
Y1562293D03*
X874352D03*
Y1559293D03*
Y1565293D03*
Y1568293D03*
X871352D03*
Y1565293D03*
Y1559293D03*
Y1562293D03*
X868352Y1574293D03*
Y1571293D03*
X865352Y1574293D03*
Y1571293D03*
X874352Y1574293D03*
Y1571293D03*
X871352D03*
Y1574293D03*
X860652Y1590444D03*
X878327Y183169D03*
X876695Y171362D03*
Y176862D03*
X887520Y171362D03*
Y176862D03*
X877724Y200837D03*
X878220Y187449D03*
X888929Y209223D03*
X891620Y209662D03*
X888929Y206723D03*
X891620Y207162D03*
X884003Y278712D03*
X883870Y275802D03*
X883909Y281862D03*
X879587Y270004D03*
X883870Y272652D03*
X887338Y296760D03*
X882520Y327562D03*
X885020D03*
X887520D03*
X890422Y333879D03*
X893440Y336232D03*
X890820Y389362D03*
X890920Y386352D03*
X889453Y458926D03*
X887590Y471552D03*
X889439Y489599D03*
Y492999D03*
X881680Y504742D03*
Y508142D03*
X884512Y523800D03*
X882410Y526132D03*
X888130Y532612D03*
X891530D03*
X887810Y582442D03*
X889000Y737562D03*
X885310Y736442D03*
X886720Y741902D03*
X878192Y879910D03*
X884747Y871745D03*
X879100Y912608D03*
X884619Y916477D03*
X892317Y915872D03*
X880102Y923235D03*
X891560Y1435510D03*
X883352Y1562293D03*
Y1559293D03*
Y1565293D03*
Y1568293D03*
X880352Y1562293D03*
Y1559293D03*
Y1565293D03*
Y1568293D03*
X877352Y1562293D03*
Y1559293D03*
Y1565293D03*
Y1568293D03*
X883352Y1574293D03*
Y1571293D03*
X880352Y1574293D03*
Y1571293D03*
X877352Y1574293D03*
Y1571293D03*
X888652Y1581793D03*
Y1573793D03*
X885652Y1584539D03*
X888652Y1597793D03*
Y1585993D03*
X883152Y1586507D03*
X888652Y1589793D03*
Y1609793D03*
X908620Y188899D03*
X896620Y209662D03*
X894120D03*
Y207162D03*
X896620D03*
X906120Y261252D03*
X894770Y283062D03*
X896540Y341132D03*
X902260Y473153D03*
Y475653D03*
X903124Y470797D03*
X900020Y470672D03*
X896060Y481222D03*
Y484622D03*
X907678Y488177D03*
X895340Y497882D03*
Y501282D03*
X901829Y512730D03*
Y516130D03*
X893450Y516862D03*
X901230Y531612D03*
X904630D03*
X894897Y871745D03*
X894965Y917422D03*
X899830Y971484D03*
Y974884D03*
X907770Y1045242D03*
X894830Y1435970D03*
X907352Y1568293D03*
Y1565293D03*
Y1559293D03*
Y1562293D03*
Y1574293D03*
Y1571293D03*
X896652Y1577793D03*
X899652Y1582570D03*
Y1573793D03*
X896672Y1587073D03*
X897352Y1590893D03*
X896652Y1593793D03*
X899551D03*
X902652Y1590444D03*
X896652Y1605793D03*
Y1601793D03*
X922726Y176302D03*
X922100Y181791D03*
X917386Y184114D03*
X924920Y196199D03*
X923836Y193563D03*
X923897Y445545D03*
X927034Y445594D03*
X912984Y458135D03*
X909584D03*
X924447Y463012D03*
X921047D03*
X909190Y473392D03*
X912288Y472430D03*
X918532Y492445D03*
X927154Y492103D03*
X924623Y492097D03*
X918078Y495177D03*
X921189Y492086D03*
X918212Y497677D03*
X918131Y503330D03*
X921060Y506086D03*
X923783Y506076D03*
X918212Y500777D03*
X909984Y496330D03*
X926173Y512391D03*
X913394Y521662D03*
X916794D03*
X909600Y521162D03*
X922879Y531976D03*
Y528576D03*
X918420Y804062D03*
X909720Y798861D03*
Y794862D03*
X913720Y799362D03*
X914152Y803294D03*
X921757Y962082D03*
X916974Y962108D03*
X923930Y976652D03*
X917980Y974952D03*
X924440Y996852D03*
X914838Y985989D03*
X918720Y1009937D03*
X910352Y1568293D03*
Y1565293D03*
Y1559293D03*
Y1562293D03*
X922352D03*
Y1559293D03*
Y1565293D03*
Y1568293D03*
X919352Y1562293D03*
Y1559293D03*
Y1565293D03*
Y1568293D03*
X916352Y1562293D03*
Y1559293D03*
Y1565293D03*
Y1568293D03*
X913352D03*
Y1565293D03*
Y1559293D03*
Y1562293D03*
X910352Y1574293D03*
Y1571293D03*
X922352Y1574293D03*
Y1571293D03*
X919352Y1574293D03*
Y1571293D03*
X916352Y1574293D03*
Y1571293D03*
X913352D03*
Y1574293D03*
X919488Y1660733D03*
X918020Y1672860D03*
X914500Y1671400D03*
X938160Y173389D03*
X935550Y173329D03*
X940720Y173389D03*
X938160Y176389D03*
X935550Y176329D03*
X940720Y176389D03*
X940424Y184190D03*
X936424D03*
X935770Y191419D03*
X939270D03*
X940410Y188852D03*
X930472Y246093D03*
X938603Y240063D03*
X933122Y246115D03*
X933686Y242922D03*
X935454Y241154D03*
X933217Y380693D03*
Y384693D03*
X941059Y427911D03*
Y424511D03*
X937447Y457862D03*
X934047D03*
X928394Y472201D03*
Y474701D03*
X932373Y495175D03*
X932089Y492691D03*
X929654Y492103D03*
X932218Y499314D03*
X939872Y495813D03*
X932089Y505986D03*
X932289Y502986D03*
X926637Y506069D03*
X929281Y506086D03*
X931720Y524862D03*
X940550Y517400D03*
X940140Y514925D03*
X933773Y530479D03*
X930731D03*
X941050Y532252D03*
Y528852D03*
X938742Y803831D03*
X931573Y816109D03*
X927470Y815112D03*
X935052Y812630D03*
X934260Y808312D03*
X938371Y809311D03*
X930786Y811785D03*
X925220Y817862D03*
X928237Y824844D03*
X926469Y826612D03*
X926823Y962082D03*
X940170Y962842D03*
X939740Y987762D03*
X936998Y985750D03*
X932310Y996812D03*
X927220Y1012362D03*
X931220D03*
X925352Y1562293D03*
Y1559293D03*
Y1565293D03*
Y1568293D03*
Y1574293D03*
Y1571293D03*
X938652Y1581393D03*
X928152Y1584539D03*
X938652Y1593393D03*
Y1585393D03*
X925152Y1586507D03*
X938652Y1589393D03*
X933979Y1661327D03*
X929979Y1661352D03*
X942100Y1671100D03*
X945720Y173389D03*
X943220D03*
X945720Y176389D03*
X943220D03*
X948400Y176499D03*
X949120Y184912D03*
X944250Y194489D03*
Y197889D03*
X957020Y193299D03*
X949550Y192819D03*
X957020Y264862D03*
X953046Y390103D03*
X951181Y391916D03*
X950660Y399472D03*
X956487Y394831D03*
X949920Y404602D03*
X944032Y437631D03*
Y434231D03*
X945447Y463012D03*
X942047D03*
X946727Y507952D03*
Y504552D03*
X954420Y511252D03*
Y500552D03*
Y497152D03*
Y514652D03*
X954390Y527596D03*
X945524Y515483D03*
X944261Y517871D03*
X941740Y512922D03*
X942610Y515350D03*
X945100Y534464D03*
X955123Y533642D03*
X948415Y534313D03*
X956518Y531567D03*
X957220Y582862D03*
X953594Y787477D03*
X954447Y791735D03*
X951043Y796140D03*
X950190Y791382D03*
X944272Y803410D03*
X943366Y798707D03*
X946786Y795287D03*
X947921Y799761D03*
X944170Y962842D03*
X949560Y981392D03*
X951560Y997422D03*
X956980Y1536260D03*
X953980D03*
X950980D03*
X947980D03*
X944980D03*
Y1551260D03*
X947980D03*
X950980D03*
X953980D03*
X956980D03*
X944980Y1548260D03*
X947980D03*
X950980D03*
X953980D03*
X956980D03*
X944980Y1545260D03*
X947980D03*
X950980D03*
X953980D03*
X956980D03*
X944980Y1542260D03*
X947980D03*
X950980D03*
X953980D03*
X956980D03*
Y1539260D03*
X953980D03*
X950980D03*
X947980D03*
X944980D03*
Y1554260D03*
X947980D03*
X950980D03*
X953980D03*
X956980D03*
X956800Y1663725D03*
X956600Y1666875D03*
X962604Y165313D03*
X962458Y162398D03*
X965150Y193412D03*
X966720Y198099D03*
X970720D03*
X961120Y193299D03*
X968384Y242051D03*
X965884D03*
X960020Y264862D03*
X963020D03*
X962570Y282812D03*
X962882Y314512D03*
X967239Y320073D03*
X963854Y320113D03*
X963300Y347962D03*
X962623Y350642D03*
X970730Y377872D03*
X972220Y386251D03*
Y390239D03*
X975670Y392063D03*
X963856Y398302D03*
X965890Y405967D03*
X963720Y439862D03*
X961320Y476242D03*
X968286Y483941D03*
Y480541D03*
X964347Y509462D03*
X970788Y501230D03*
X964347Y501262D03*
X969351Y512416D03*
X957790Y527596D03*
X963930Y533362D03*
X967330D03*
X959351Y533566D03*
X960920Y644762D03*
Y649762D03*
Y654762D03*
X963720Y647262D03*
Y657262D03*
Y652262D03*
X960820Y665062D03*
X960920Y659762D03*
X963720Y662262D03*
X967750Y1376460D03*
X969000Y1536262D03*
X971700D03*
X969000Y1548262D03*
X971700D03*
X969000Y1545262D03*
X971700D03*
X969000Y1551262D03*
X971700D03*
Y1542262D03*
X969000D03*
X971700Y1539262D03*
X969000D03*
X965904Y1554364D03*
X960904D03*
X969000Y1554262D03*
X971700D03*
X965086Y1603984D03*
X962086D03*
X990501Y152397D03*
X986369Y155358D03*
X975690Y157220D03*
X983811Y156694D03*
X985499Y168753D03*
X985431Y181058D03*
X990115Y173039D03*
X987320Y194599D03*
Y198099D03*
Y201599D03*
X977220Y201399D03*
X986020Y191099D03*
X981795Y216623D03*
X978012Y276436D03*
X975512Y282096D03*
X978012D03*
X975512Y279266D03*
X978012D03*
X981470Y268532D03*
X979940Y292262D03*
Y289762D03*
X975512Y294996D03*
X978012D03*
X979940Y284762D03*
Y287262D03*
X988818Y346372D03*
X978000Y362462D03*
X988723Y369650D03*
X991934Y368443D03*
X988908Y373392D03*
X986400Y383123D03*
X983770Y373962D03*
X979766Y377507D03*
X977949Y384205D03*
X980916Y384286D03*
X980856Y392502D03*
X986955Y391939D03*
X983629Y397628D03*
X979559Y399362D03*
X983970Y392562D03*
X991369Y408252D03*
X979240Y425212D03*
X984254Y418379D03*
X987440Y431193D03*
X980720Y512362D03*
X986400Y503200D03*
X986273Y532996D03*
X980535Y532643D03*
X986418Y530019D03*
X975900Y1265062D03*
X987920Y1290662D03*
X985320Y1288762D03*
X992306Y1295049D03*
X979373Y1342724D03*
X974700Y1536262D03*
X980400D03*
X977700D03*
X974700Y1548262D03*
Y1545262D03*
Y1551262D03*
X980400Y1548262D03*
X977700D03*
X980400Y1545262D03*
X977700D03*
X980400Y1551262D03*
X977700D03*
Y1542262D03*
X980400D03*
X974700D03*
X977700Y1539262D03*
X980400D03*
X974700D03*
X984270Y1554364D03*
X974700Y1554262D03*
X980400D03*
X977700D03*
X989270Y1554364D03*
X995000Y150883D03*
X1001500D03*
X995180Y153689D03*
X1006220Y160799D03*
X1002720D03*
X1001101Y165510D03*
X999220Y185299D03*
X1002720D03*
X1006220D03*
X996415Y172579D03*
X1002920Y174799D03*
X990220Y195699D03*
Y199199D03*
X1008120Y198293D03*
X990195Y216823D03*
X990220Y202699D03*
X1000610Y211039D03*
X1005640Y210969D03*
X1001195Y219898D03*
X1005120Y230399D03*
X994743Y289843D03*
X1006232Y343983D03*
X1001440Y359702D03*
X994689Y379348D03*
X1006201Y370004D03*
X999440Y371782D03*
X996922Y367764D03*
X994322Y404090D03*
X1005123Y414662D03*
X997617Y412383D03*
X997394Y415578D03*
X993012Y421570D03*
X997225Y419162D03*
X990840Y431193D03*
X1005720Y498862D03*
X1003220Y512862D03*
X1005520Y510932D03*
X991237Y533043D03*
X1008560Y589682D03*
X1005960Y594682D03*
X1005373Y748826D03*
X995120Y773122D03*
X994942Y777055D03*
X996320Y1280683D03*
Y1284062D03*
X997920Y1278762D03*
X994574Y1297318D03*
X995066Y1536262D03*
X992466D03*
X1001066D03*
X1003766D03*
X998066D03*
X995066Y1551262D03*
X992466D03*
X995066Y1545262D03*
X992466D03*
X995066Y1548262D03*
X992466D03*
X1001066Y1551262D03*
X1003766D03*
X1001066Y1545262D03*
X1003766D03*
X1001066Y1548262D03*
X1003766D03*
X998066Y1551262D03*
Y1545262D03*
Y1548262D03*
Y1542262D03*
X1003766D03*
X1001066D03*
X992466D03*
X995066D03*
X998066Y1539262D03*
X1003766D03*
X1001066D03*
X992466D03*
X995066D03*
X1007636Y1554364D03*
X995066Y1554262D03*
X992466D03*
X1001066D03*
X1003766D03*
X998066D03*
X996698Y1604000D03*
X993698D03*
X1008129Y150948D03*
X1009720Y160799D03*
X1013220D03*
X1012791Y157596D03*
X1012000Y185299D03*
X1014900D03*
X1017800D03*
X1017200Y175699D03*
X1014300D03*
X1019900Y175799D03*
X1020645Y190499D03*
X1011320Y202169D03*
X1019355Y218423D03*
X1019802Y214099D03*
X1010005Y208424D03*
X1011720Y229699D03*
X1019355Y222423D03*
X1019530Y226423D03*
X1007820Y229999D03*
X1021118Y294290D03*
X1020720Y310937D03*
X1015520Y302862D03*
X1009800Y343800D03*
X1021695Y364518D03*
X1006710Y372931D03*
X1015096Y373758D03*
X1017163Y367963D03*
X1009883Y367955D03*
X1010420Y416062D03*
X1015420Y410862D03*
X1009009Y419948D03*
X1021239Y416974D03*
X1016261Y432888D03*
X1012861D03*
X1024200Y510362D03*
X1018092Y520212D03*
X1020392Y521826D03*
X1016360Y594682D03*
X1016220Y590862D03*
X1019000Y601042D03*
X1021654Y606302D03*
X1011160Y594682D03*
X1007873Y748826D03*
X1007600Y1298250D03*
X1007610Y1295040D03*
X1021612Y1536262D03*
X1016012D03*
X1018612D03*
Y1551262D03*
X1016012D03*
X1018612Y1545262D03*
X1016012D03*
X1018612Y1548262D03*
X1016012D03*
X1021612Y1551262D03*
Y1545262D03*
Y1548262D03*
X1018612Y1542262D03*
X1016012D03*
X1021612D03*
Y1539262D03*
X1016012D03*
X1018612D03*
Y1554262D03*
X1016012D03*
X1021612D03*
X1012636Y1554364D03*
X1026620Y125662D03*
X1034229Y128953D03*
X1032894Y155185D03*
X1022800Y175799D03*
X1037618Y261200D03*
X1031702Y264130D03*
X1025862Y291727D03*
X1032317Y291284D03*
X1036278Y303993D03*
Y307393D03*
X1033285Y353627D03*
X1029395Y375844D03*
X1025004Y374662D03*
X1031950Y383771D03*
Y387171D03*
X1031153Y390152D03*
X1026820Y394362D03*
X1038320Y407062D03*
Y404462D03*
X1026548Y400571D03*
X1035920Y420062D03*
Y417462D03*
X1026370Y503562D03*
X1032155Y509737D03*
X1025530Y519627D03*
X1033040Y519852D03*
X1038130Y518417D03*
X1040720Y591862D03*
X1024154Y601152D03*
X1029630Y601252D03*
X1026654Y596152D03*
X1035760Y592952D03*
X1033260Y601272D03*
X1038260D03*
X1033817Y735612D03*
X1036954Y734669D03*
X1030660Y735082D03*
X1027212Y1536262D03*
X1024612D03*
Y1551262D03*
X1027212D03*
X1024612Y1545262D03*
X1027212D03*
X1024612Y1548262D03*
X1027212D03*
X1024612Y1542262D03*
X1027212D03*
Y1539262D03*
X1024612D03*
X1031002Y1554364D03*
X1024612Y1554262D03*
X1027212D03*
X1036002Y1554364D03*
X1028298Y1604000D03*
X1025298D03*
X1040970Y128332D03*
X1043720Y363462D03*
X1054820Y370162D03*
X1044120Y366362D03*
X1040120Y393962D03*
X1042720D03*
X1041420Y443962D03*
X1043920D03*
X1050470Y447062D03*
X1041444Y506504D03*
X1053690Y520760D03*
X1045720Y591672D03*
X1043260Y601272D03*
X1045760Y596272D03*
X1048260Y601272D03*
X1051680Y614772D03*
X1053745Y742341D03*
X1053354Y1286714D03*
Y1291714D03*
X1039510Y1296655D03*
X1049510D03*
X1044510D03*
X1039510Y1293155D03*
X1049510D03*
X1044510D03*
X1053354Y1296714D03*
X1041798Y1536262D03*
X1047798D03*
X1050498D03*
X1044798D03*
X1039298D03*
X1041798Y1551262D03*
X1039298D03*
X1041798Y1545262D03*
X1039298D03*
X1041798Y1548262D03*
X1039298D03*
X1047798Y1551262D03*
X1050498D03*
X1047798Y1545262D03*
X1050498D03*
X1047798Y1548262D03*
X1050498D03*
X1044798Y1551262D03*
Y1545262D03*
Y1548262D03*
X1039298Y1542262D03*
X1044798D03*
X1050498D03*
X1047798D03*
X1041798D03*
X1044798Y1539262D03*
X1050498D03*
X1047798D03*
X1039298D03*
X1041798D03*
X1054368Y1554364D03*
X1041798Y1554262D03*
X1039298D03*
X1047798D03*
X1050498D03*
X1044798D03*
X1056898Y1604000D03*
X1067220Y145362D03*
Y142862D03*
Y148362D03*
X1059943Y435314D03*
X1062120Y477462D03*
X1056190Y520760D03*
X1058220Y585862D03*
X1061470D03*
X1056220Y605052D03*
X1055205Y744853D03*
X1063354Y1286714D03*
X1058354D03*
X1063354Y1291714D03*
X1058354D03*
X1063354Y1296714D03*
X1058290Y1296302D03*
X1071179Y1294669D03*
X1066462Y1520088D03*
X1065164Y1536262D03*
X1062464D03*
X1071164D03*
X1068164D03*
X1065164Y1551262D03*
X1062464D03*
X1065164Y1545262D03*
X1062464D03*
X1065164Y1548262D03*
X1062464D03*
X1071164Y1551262D03*
Y1545262D03*
Y1548262D03*
X1068164Y1551262D03*
Y1545262D03*
Y1548262D03*
Y1542262D03*
X1071164D03*
X1062464D03*
X1065164D03*
X1068164Y1539262D03*
X1071164D03*
X1062464D03*
X1065164D03*
Y1554262D03*
X1062464D03*
X1071164D03*
X1068164D03*
X1059368Y1554364D03*
X1059898Y1604000D03*
X1071920Y53862D03*
X1079114Y75775D03*
X1080168Y90721D03*
X1081282Y180937D03*
X1086756Y187540D03*
X1077973Y246362D03*
X1083973D03*
X1080973D03*
X1077883Y260842D03*
X1076823Y265438D03*
X1083823D03*
X1083883Y260842D03*
X1080883D03*
X1080323Y265438D03*
X1082853Y269492D03*
X1079853D03*
X1075400Y273762D03*
X1078400D03*
X1081400D03*
X1084400D03*
X1087400D03*
X1076018Y289400D03*
X1079018D03*
X1082018D03*
X1085018D03*
X1084130Y298342D03*
X1086630D03*
X1076353Y363966D03*
X1078853D03*
X1087330Y369061D03*
Y374131D03*
Y379251D03*
X1075462Y386723D03*
X1078151Y413911D03*
X1078120Y411262D03*
X1084245Y435437D03*
X1078545Y435637D03*
X1081045D03*
X1087280Y435437D03*
X1076598Y477087D03*
X1081930Y477132D03*
X1079320Y473892D03*
X1076820D03*
X1073589Y506461D03*
X1082220Y522362D03*
X1085720Y522422D03*
X1073250Y582332D03*
X1084637Y744635D03*
X1083714Y1285144D03*
Y1288144D03*
Y1291144D03*
X1077634Y1294869D03*
X1074387Y1294652D03*
X1074010Y1510650D03*
X1073864Y1536262D03*
X1085830D03*
X1073864Y1551262D03*
Y1545262D03*
Y1548262D03*
X1085830Y1551262D03*
Y1545262D03*
Y1548262D03*
Y1542262D03*
X1073864D03*
X1085830Y1539262D03*
X1073864D03*
X1077734Y1554364D03*
X1073864Y1554262D03*
X1085830D03*
X1082734Y1554364D03*
X1084000Y1647110D03*
X1094644Y67992D03*
X1090279Y126524D03*
X1105580Y132822D03*
X1100630Y130376D03*
X1099030Y245140D03*
X1088018Y289400D03*
X1089130Y298342D03*
X1091630D03*
X1094130D03*
X1089660Y408560D03*
X1095820Y420762D03*
X1090245Y435437D03*
X1093497Y744655D03*
X1089714Y1285144D03*
X1105480Y1517982D03*
X1088530Y1536262D03*
X1091530D03*
X1088530Y1551262D03*
Y1545262D03*
Y1548262D03*
X1094530Y1551262D03*
X1097230D03*
X1094530Y1545262D03*
X1097230D03*
X1094530Y1548262D03*
X1097230D03*
X1091530Y1551262D03*
Y1545262D03*
Y1548262D03*
Y1542262D03*
X1097230D03*
X1094530D03*
X1088530D03*
X1091530Y1539262D03*
X1094530D03*
X1088530D03*
X1101600Y1554364D03*
X1104750Y1549346D03*
X1088530Y1554262D03*
X1094530D03*
X1097230D03*
X1091530D03*
X1095436Y1603944D03*
X1092436D03*
X1088790Y1641830D03*
X1094225Y1671710D03*
X1091880Y1673720D03*
X1110977Y55505D03*
X1110754Y60028D03*
X1113594Y69862D03*
X1109020Y80592D03*
X1118309Y111687D03*
X1115860Y113883D03*
X1118486Y208942D03*
X1111918Y234718D03*
X1109088Y234668D03*
X1111918Y237718D03*
Y240718D03*
X1109088Y237668D03*
Y240668D03*
X1120190Y255652D03*
X1117820Y456132D03*
X1113207Y744455D03*
X1115853Y1426342D03*
Y1435532D03*
X1114400Y1518237D03*
X1110725Y1518046D03*
X1113725Y1530935D03*
X1115802Y1615010D03*
X1117407Y1628495D03*
X1113990Y1631370D03*
X1113325Y1627975D03*
X1117182Y1625460D03*
X1106480Y1641275D03*
X1113110Y1666460D03*
X1108320Y1680200D03*
X1112130Y1711600D03*
X1112252Y1706170D03*
X1112200Y1709000D03*
X1114150Y1715726D03*
X1110663Y1719189D03*
X1119200Y1730300D03*
Y1727200D03*
X1114300Y1722700D03*
X1119300Y1724100D03*
X1132547Y64864D03*
X1129997Y69864D03*
X1122278Y107549D03*
X1120420Y109829D03*
X1124858Y197309D03*
X1128485Y198159D03*
X1133041Y194137D03*
X1124360Y259712D03*
X1125409Y305797D03*
X1122059Y305673D03*
X1124985Y302578D03*
X1127402Y456174D03*
X1136051Y503324D03*
X1124120Y643762D03*
X1136720Y641362D03*
X1133720Y642862D03*
X1129420Y644062D03*
X1122980Y741312D03*
X1127972Y747250D03*
X1135750Y1255672D03*
X1127179Y1372700D03*
X1124679D03*
Y1370200D03*
X1127179D03*
X1129729Y1372700D03*
Y1370200D03*
Y1375200D03*
X1127179D03*
X1124679D03*
X1129729Y1377700D03*
Y1380200D03*
Y1385200D03*
Y1382700D03*
X1127179D03*
X1124679D03*
X1127179Y1380200D03*
Y1377700D03*
X1124679D03*
Y1380200D03*
Y1385200D03*
X1127179D03*
X1122879Y1431474D03*
Y1434024D03*
X1125995Y1439780D03*
X1123379Y1443583D03*
X1133169Y1445690D03*
X1129169Y1442998D03*
X1135568Y1442923D03*
X1129169Y1445719D03*
X1130841Y1462953D03*
X1128341Y1465453D03*
Y1462953D03*
X1130841Y1465453D03*
X1133841Y1462953D03*
Y1465453D03*
X1128341Y1468453D03*
X1130841D03*
X1133841D03*
X1128341Y1460453D03*
X1130841D03*
X1133841D03*
Y1471453D03*
X1130841D03*
X1128341D03*
X1132187Y1582738D03*
X1135187D03*
X1132187Y1590738D03*
X1135187D03*
X1124862Y1615010D03*
X1140242Y101135D03*
X1152720Y180862D03*
X1148795Y213731D03*
X1141957Y227277D03*
X1144457D03*
X1139457D03*
X1146670Y230110D03*
X1147700Y362731D03*
X1137315Y379592D03*
X1147700Y368041D03*
X1138551Y503324D03*
X1144720Y501362D03*
Y498662D03*
X1142967Y592097D03*
X1138500Y586362D03*
X1142127Y586452D03*
X1140697Y608762D03*
X1150140Y610362D03*
X1144810Y613762D03*
X1142674Y1287608D03*
X1144247Y1372700D03*
Y1370200D03*
X1146797Y1372700D03*
X1149297D03*
X1146797Y1370200D03*
X1149297D03*
X1144247Y1375200D03*
X1146797D03*
X1149297D03*
X1144247Y1377700D03*
Y1380200D03*
Y1385200D03*
Y1382700D03*
X1146797D03*
X1149297D03*
X1146797Y1380200D03*
Y1377700D03*
X1149297Y1380200D03*
Y1377700D03*
Y1385200D03*
X1146797D03*
X1146563Y1436334D03*
X1141903D03*
X1144233Y1435584D03*
X1139573D03*
X1149469Y1437098D03*
X1151669Y1435698D03*
Y1438598D03*
X1137311Y1445191D03*
X1147203Y1441968D03*
X1149569Y1440098D03*
X1151669Y1441498D03*
X1147203Y1439068D03*
X1141591Y1462853D03*
Y1465353D03*
Y1468353D03*
Y1471353D03*
Y1460353D03*
X1150821Y1459607D03*
Y1456587D03*
X1138430Y1524150D03*
X1151497Y1524187D03*
X1153465Y1550301D03*
X1149528D03*
X1145410Y1540640D03*
X1143060Y1538380D03*
X1141654Y1550301D03*
X1137717Y1558020D03*
X1141690Y1552920D03*
X1152187Y1574738D03*
X1142187D03*
X1145187D03*
X1142187Y1582738D03*
X1145187D03*
X1152187D03*
X1141525Y1597630D03*
X1152187Y1590738D03*
X1142187D03*
X1145187D03*
X1140750Y1604330D03*
X1150380Y1602590D03*
X1146960Y1618960D03*
X1152257Y1628910D03*
X1155703Y73679D03*
X1165440Y176450D03*
X1168710Y176590D03*
X1159460Y194090D03*
X1160630Y213870D03*
X1159753Y361281D03*
X1159460Y366025D03*
X1156790Y363231D03*
X1161690Y374110D03*
X1164320Y451062D03*
X1156100Y456342D03*
X1167190Y526922D03*
X1158300Y585862D03*
X1170740Y602132D03*
X1155962Y746193D03*
X1156609Y1286685D03*
X1165279Y1372700D03*
X1162779D03*
X1167829D03*
X1162779Y1370200D03*
X1165279D03*
X1167829D03*
X1162779Y1375200D03*
X1165279D03*
X1167829D03*
Y1377700D03*
Y1380200D03*
Y1385200D03*
Y1382700D03*
X1165279D03*
X1162779D03*
X1165279Y1380200D03*
X1162779D03*
Y1377700D03*
X1165279D03*
X1162779Y1385200D03*
X1165279D03*
X1161022Y1431499D03*
Y1433999D03*
X1164138Y1439780D03*
X1154288Y1432502D03*
X1161522Y1443630D03*
X1167312Y1442998D03*
Y1445964D03*
X1159386Y1464253D03*
Y1466753D03*
X1156386Y1464253D03*
Y1466753D03*
X1159386Y1469253D03*
X1156386D03*
X1153821Y1459607D03*
Y1456587D03*
X1159386Y1461753D03*
X1159476Y1458918D03*
X1156386Y1461753D03*
X1156476Y1458918D03*
X1159446Y1456113D03*
X1156446D03*
X1167245Y1524187D03*
X1159371D03*
X1163308D03*
X1155433D03*
X1165276Y1550301D03*
X1169213D03*
X1157402D03*
X1161339D03*
X1161595Y1574738D03*
X1164595D03*
X1155187D03*
X1161595Y1582738D03*
X1164595D03*
X1155187D03*
X1163079Y1601479D03*
X1161595Y1590738D03*
X1164595D03*
X1155187D03*
X1169460Y1606630D03*
Y1616630D03*
Y1611630D03*
X1158030Y1619250D03*
X1164830Y1628830D03*
X1163970Y1620600D03*
X1169325Y1642600D03*
X1158325D03*
X1162383Y1652505D03*
X1164830Y1654632D03*
X1159930D03*
X1161076Y1680624D03*
X1157700Y1681100D03*
X1174120Y57111D03*
X1175926Y69151D03*
X1180676Y106858D03*
X1187413Y143132D03*
X1181420Y157962D03*
X1181700Y186962D03*
X1173314Y176452D03*
X1170595Y170056D03*
X1181476Y172247D03*
X1184510Y188962D03*
X1173100Y186962D03*
X1172925Y202174D03*
X1181369Y199234D03*
X1183460Y205342D03*
X1181470Y208802D03*
X1172835Y218174D03*
X1181500Y211962D03*
Y218462D03*
Y215962D03*
Y222162D03*
X1186653Y302242D03*
X1181450Y306052D03*
X1174120Y355362D03*
X1169690Y526922D03*
X1172310Y584562D03*
X1181300Y584762D03*
X1177570Y602052D03*
X1175217Y595762D03*
X1173020Y745972D03*
X1175573Y1286765D03*
X1172573D03*
X1182747Y1372700D03*
X1185297D03*
X1182747Y1370200D03*
X1185297D03*
X1182747Y1375200D03*
X1185297D03*
X1182747Y1380200D03*
Y1377700D03*
Y1385200D03*
Y1382700D03*
X1185297D03*
Y1377700D03*
Y1380200D03*
Y1385200D03*
X1184706Y1436334D03*
X1180046D03*
X1182376Y1435584D03*
X1177716D03*
X1171342Y1445650D03*
X1175454Y1445191D03*
X1173711Y1442923D03*
X1171182Y1524187D03*
X1184330Y1573260D03*
X1184290Y1570080D03*
X1171595Y1574738D03*
X1174595D03*
X1171595Y1582738D03*
X1174595D03*
X1183410Y1594450D03*
X1183440Y1591640D03*
X1171595Y1590738D03*
X1174595D03*
X1178140Y1601100D03*
X1184200Y1599900D03*
X1183320Y1597080D03*
X1169968Y1602370D03*
X1174550Y1615630D03*
X1178250Y1609100D03*
X1184200Y1602700D03*
X1185030Y1624660D03*
X1180325Y1642600D03*
X1173383Y1652505D03*
X1184383D03*
X1181930Y1654632D03*
X1175830D03*
X1170930D03*
X1183076Y1680624D03*
X1172076D03*
X1194478Y56986D03*
X1197520Y56962D03*
X1201158Y57130D03*
X1189393Y60183D03*
X1188700Y100700D03*
X1185400Y104000D03*
X1193532Y132644D03*
X1194800Y143112D03*
X1197414Y161592D03*
X1191020Y170862D03*
X1185420Y153762D03*
X1200720Y184862D03*
X1188300Y189062D03*
X1200720Y187862D03*
X1200963Y212648D03*
X1200830Y206002D03*
X1186340Y204492D03*
X1187300Y217862D03*
X1188500Y205772D03*
X1188600Y225962D03*
X1187013Y238972D03*
X1194840Y236592D03*
X1199720Y252362D03*
X1196720D03*
X1188810Y296088D03*
X1186280Y298972D03*
X1193198Y586172D03*
X1195698D03*
X1198198D03*
X1200698D03*
X1185687Y744475D03*
X1187797Y1372700D03*
Y1370200D03*
Y1375200D03*
Y1382700D03*
Y1377700D03*
Y1380200D03*
Y1385200D03*
X1187412Y1437498D03*
X1189612Y1436098D03*
X1191918Y1432516D03*
X1185346Y1442128D03*
X1187512Y1440498D03*
X1189612Y1441898D03*
X1185346Y1439228D03*
X1189612Y1438998D03*
X1187720Y1517688D03*
X1187830Y1522188D03*
X1198546Y1520188D03*
X1187830Y1526688D03*
X1198546Y1524688D03*
X1187720Y1536362D03*
X1198485Y1534313D03*
X1198436Y1529362D03*
X1187720Y1531862D03*
Y1553692D03*
X1198497Y1539667D03*
X1187720Y1548772D03*
X1198436Y1546492D03*
X1187720Y1544292D03*
X1198436Y1551192D03*
Y1556192D03*
Y1561062D03*
X1187720Y1558682D03*
Y1563182D03*
X1194510Y1563076D03*
X1187600Y1622064D03*
X1201600Y1633790D03*
X1199400Y1627800D03*
X1190895Y1642910D03*
X1186000Y1640000D03*
X1197400Y1654942D03*
X1192500D03*
X1186830Y1654632D03*
X1193646Y1680934D03*
X1201106Y1677873D03*
X1190735Y1688390D03*
X1194793Y1698295D03*
X1201505Y1688435D03*
X1192340Y1700422D03*
X1197240D03*
X1193174Y1726414D03*
X1216176Y56742D03*
X1202860Y120392D03*
X1215763Y114363D03*
X1215800Y111300D03*
X1201700Y110000D03*
X1202920Y117162D03*
X1210910Y129502D03*
X1206114Y132962D03*
X1206434Y129492D03*
X1206694Y139512D03*
X1214415Y153962D03*
X1206664Y158952D03*
X1214091Y164962D03*
X1214534Y157462D03*
X1214054Y186092D03*
X1214693Y174962D03*
X1214134Y180972D03*
X1213720Y200309D03*
Y189362D03*
X1204220D03*
X1213720Y195362D03*
X1215720Y204862D03*
X1203200Y202514D03*
X1219060Y213312D03*
X1206660Y224742D03*
X1213540Y224792D03*
X1207220Y243998D03*
X1210900Y265300D03*
X1204475Y350684D03*
X1205165Y380962D03*
X1218870Y418082D03*
X1214000Y599262D03*
X1208980Y598462D03*
X1207100Y600882D03*
X1211277Y744265D03*
X1206757Y744455D03*
X1210288Y754081D03*
X1202300Y753962D03*
X1207607Y754095D03*
X1215896Y756942D03*
X1206432Y758995D03*
X1202307Y757082D03*
X1205820Y1652910D03*
X1210830Y1676500D03*
X1217210Y1684520D03*
X1212305Y1688700D03*
X1216363Y1698605D03*
X1205563Y1698340D03*
X1207180Y1685680D03*
X1208010Y1700467D03*
X1213910Y1700732D03*
X1203110Y1700467D03*
X1203939Y1726459D03*
X1214834Y1726724D03*
X1228425Y91500D03*
X1222100Y91600D03*
X1225100Y91500D03*
X1225700Y108962D03*
X1232182Y110659D03*
X1224614Y116962D03*
X1219534Y116492D03*
X1223500Y111162D03*
X1226400Y125200D03*
X1226093Y134262D03*
X1229500Y125100D03*
X1223100Y130700D03*
X1234093Y144962D03*
X1226093Y140962D03*
X1222593D03*
X1222920Y144909D03*
Y148909D03*
X1222593Y168962D03*
X1222890Y157002D03*
X1226093Y156962D03*
X1222594Y154242D03*
X1226093Y168162D03*
X1225874Y163462D03*
X1222720Y163362D03*
X1226093Y177962D03*
X1222724Y176102D03*
X1226093Y172962D03*
X1223134Y190802D03*
X1225574Y188662D03*
X1228520Y202162D03*
X1229720Y197302D03*
X1226093Y193462D03*
X1225320Y200162D03*
X1233282Y201875D03*
X1223180Y210552D03*
X1233780Y214572D03*
X1231720Y217862D03*
Y209862D03*
X1219220Y243862D03*
Y247148D03*
X1230720Y380362D03*
X1221220D03*
X1232720Y377862D03*
X1224300Y380400D03*
X1223650Y520672D03*
X1230650D03*
X1227150D03*
X1219060Y757272D03*
X1223327Y757615D03*
X1228320Y758598D03*
X1218810Y1700732D03*
X1236620Y58862D03*
X1241010Y110782D03*
X1250010Y117121D03*
X1244200Y112862D03*
X1249362Y111600D03*
X1241035Y114399D03*
X1234746Y136040D03*
X1240728Y136198D03*
X1240904Y151592D03*
X1238604Y150062D03*
X1241100Y145842D03*
X1244120Y167462D03*
X1246272Y164889D03*
X1243100Y160181D03*
X1243184Y182422D03*
X1239874Y182322D03*
X1236410Y201462D03*
X1236220Y189362D03*
X1236593Y197462D03*
X1236584Y205762D03*
X1245486Y203000D03*
X1245593Y211762D03*
X1236620Y221562D03*
X1244720Y230362D03*
X1245514Y224302D03*
X1245593Y219662D03*
X1239045Y224062D03*
X1246878Y248615D03*
X1240500Y248332D03*
Y244332D03*
X1236720Y257362D03*
X1243589Y379595D03*
X1236720Y377862D03*
X1234720Y380362D03*
X1248150Y520672D03*
X1244650D03*
X1241150D03*
X1237650D03*
X1234150D03*
X1242260Y757602D03*
X1261227Y52061D03*
X1258727D03*
X1263454Y83060D03*
X1266464Y83090D03*
X1264098Y88787D03*
X1262320Y96012D03*
X1258539Y100900D03*
X1252520Y92022D03*
X1258539Y109263D03*
X1260641Y114399D03*
X1264220Y110462D03*
X1250424Y108943D03*
X1257581Y114579D03*
X1256093Y149462D03*
X1264663Y158946D03*
X1254994Y157382D03*
X1265010Y162222D03*
X1261899Y174648D03*
X1253624Y201362D03*
X1267315Y220701D03*
X1264874Y217462D03*
X1256504D03*
X1255613Y209568D03*
X1265207Y208442D03*
X1259703Y209808D03*
X1253440Y230552D03*
X1253860Y235622D03*
X1256070Y229512D03*
X1264584Y226592D03*
X1256593Y221462D03*
Y233972D03*
Y225972D03*
X1253950Y246692D03*
X1266715Y244692D03*
X1254370Y241302D03*
X1265065Y249982D03*
X1256494Y243177D03*
X1256574Y238662D03*
X1266518Y237042D03*
X1256584Y248002D03*
X1256454Y252122D03*
X1264854Y253996D03*
Y256496D03*
X1258883Y280558D03*
X1258250Y292986D03*
X1263150Y294726D03*
X1255150Y306211D03*
X1256220Y434362D03*
X1261220Y454362D03*
X1253220Y451362D03*
X1267220D03*
X1260220Y477362D03*
X1255920Y511362D03*
X1251650Y520672D03*
X1255150D03*
X1258667Y751405D03*
X1255520Y747362D03*
X1263486Y739949D03*
X1257672Y1351008D03*
X1276820Y58142D03*
X1282360Y58132D03*
X1279580D03*
X1279390Y87697D03*
X1275820Y87962D03*
X1270329Y101011D03*
X1266722Y101005D03*
X1278456Y96187D03*
X1279415Y90847D03*
X1281704Y95402D03*
X1282824Y108872D03*
X1271284Y108971D03*
X1282764Y135398D03*
X1277820Y140682D03*
X1281093Y144516D03*
X1271954Y159143D03*
X1271593Y165962D03*
X1278093Y184462D03*
X1278993Y193262D03*
X1273093Y200038D03*
X1278183Y201262D03*
X1275493Y193962D03*
X1267289Y192167D03*
X1269904Y192692D03*
X1272893Y191262D03*
X1271315Y220701D03*
X1267773Y208373D03*
X1273093Y213962D03*
X1275727Y209597D03*
X1267618Y225382D03*
X1277661Y225685D03*
X1267593Y229462D03*
X1278783Y221386D03*
X1282176Y221436D03*
X1282654Y226309D03*
X1278320Y239292D03*
X1279493Y248662D03*
X1282645Y255671D03*
Y252271D03*
X1277771Y255173D03*
X1273754Y256504D03*
X1276800Y276562D03*
X1269960Y294536D03*
X1271150Y305792D03*
X1272530Y429362D03*
X1284220D03*
X1280270Y434362D03*
X1272220D03*
X1278380Y463362D03*
X1276220Y477362D03*
X1283220D03*
X1269220D03*
X1274420Y463362D03*
X1275576Y730879D03*
X1266727Y752955D03*
X1279788Y1304042D03*
X1279812Y1353552D03*
X1279334Y1356089D03*
X1275856Y1358098D03*
X1271990Y1358079D03*
X1276891Y1362891D03*
X1282928Y1361833D03*
X1269012Y1371693D03*
Y1368293D03*
X1285201Y58121D03*
X1293454Y81232D03*
X1289210D03*
X1298640Y93062D03*
X1292880Y93162D03*
X1292899Y98519D03*
X1294354Y103166D03*
X1291704Y109427D03*
X1288093Y125962D03*
X1291478Y137745D03*
X1286150Y131092D03*
X1297605Y145824D03*
X1285710Y249182D03*
X1290293Y247562D03*
X1288637Y240448D03*
X1292630Y240462D03*
X1291071Y275543D03*
Y278543D03*
X1290005Y293768D03*
Y290268D03*
X1294500Y299692D03*
X1291100D03*
X1291500Y312862D03*
Y315362D03*
X1291420Y320662D03*
Y318162D03*
X1295540Y440902D03*
X1301310Y440862D03*
X1291220Y463362D03*
X1294440Y477267D03*
X1296630Y463462D03*
X1300220Y477362D03*
X1284220Y463362D03*
X1289936Y732539D03*
X1290520Y746562D03*
X1292572Y785575D03*
X1297298Y790982D03*
X1296719Y1290197D03*
X1299169Y1295467D03*
Y1297967D03*
X1296569D03*
Y1295467D03*
Y1292967D03*
X1299169D03*
X1296581Y1300474D03*
X1299181D03*
X1296576Y1303298D03*
X1299176D03*
X1290102Y1365789D03*
X1286102Y1365051D03*
X1294312Y1367279D03*
X1292840Y1364821D03*
X1286102Y1368107D03*
X1298836Y1358387D03*
X1296506Y1357637D03*
X1301820Y58672D03*
X1311424Y68652D03*
X1308174D03*
X1311960Y58152D03*
X1311260Y83032D03*
X1310857Y78542D03*
X1307120Y78562D03*
X1310906Y97807D03*
X1314406Y97756D03*
X1308274Y104162D03*
X1314059Y93877D03*
X1307244Y118452D03*
X1306836Y108242D03*
X1302080Y117032D03*
X1302060Y113852D03*
X1300990Y121812D03*
X1315156Y130656D03*
X1314920Y135361D03*
X1313117Y250605D03*
X1314685Y248651D03*
X1307431Y256099D03*
X1309283Y254162D03*
X1311275Y252297D03*
X1305552Y257974D03*
X1308736Y284948D03*
X1312136D03*
X1307042Y292636D03*
X1303642D03*
X1307442Y306998D03*
X1304042D03*
X1307677Y322996D03*
X1311077D03*
X1317100Y553900D03*
X1308600Y653500D03*
X1303576Y659671D03*
X1311420Y738262D03*
X1305187Y735630D03*
X1315020Y739862D03*
X1307469Y787772D03*
X1301034Y784165D03*
X1304260Y788265D03*
X1309930Y789852D03*
X1306701Y794779D03*
X1305117Y797125D03*
X1309210Y792802D03*
X1315169Y1274887D03*
X1315289Y1269717D03*
X1315229Y1272287D03*
X1304149Y1291317D03*
X1301889Y1284987D03*
X1301829Y1290167D03*
X1301859Y1287587D03*
X1304299Y1280967D03*
X1304269Y1283567D03*
X1304239Y1286147D03*
X1304209Y1288747D03*
X1315176Y1280218D03*
X1315181Y1277594D03*
X1299319Y1290197D03*
X1299349Y1287617D03*
X1301686Y1303268D03*
X1304196Y1299248D03*
X1304189Y1293917D03*
X1304201Y1296624D03*
X1301679Y1292937D03*
Y1295437D03*
Y1297937D03*
X1301691Y1300444D03*
X1311820Y1330518D03*
Y1333018D03*
X1314936Y1338799D03*
X1312650Y1342572D03*
X1308616Y1363345D03*
Y1360445D03*
X1306082Y1359315D03*
X1306182Y1362315D03*
X1304016Y1363945D03*
Y1361045D03*
X1308616Y1357945D03*
X1303496Y1358387D03*
X1301166Y1357637D03*
X1316459Y58697D03*
X1322248Y68487D03*
X1321279Y58767D03*
X1317831Y68652D03*
X1322415Y75480D03*
X1322906Y94212D03*
X1319968Y98266D03*
X1329891Y99455D03*
X1329646Y104954D03*
X1322906Y109733D03*
X1323912Y245111D03*
X1320387Y258901D03*
X1325769Y259001D03*
X1325414Y293556D03*
X1328814D03*
X1319903Y299176D03*
X1323303D03*
X1319618Y318073D03*
X1325080Y323902D03*
X1316218Y318073D03*
X1328480Y323902D03*
X1330101Y540049D03*
X1328530Y747702D03*
X1325210Y744322D03*
X1331519Y1262027D03*
X1331459Y1264597D03*
X1331399Y1267197D03*
X1317889Y1267147D03*
X1320399Y1267117D03*
X1317883Y1269978D03*
X1317895Y1272485D03*
X1320393Y1269948D03*
X1320405Y1272455D03*
X1331177Y1269933D03*
Y1272433D03*
X1317895Y1274985D03*
X1320405Y1274955D03*
X1331177Y1274933D03*
X1331166Y1280248D03*
X1317746D03*
X1320256Y1280218D03*
X1317895Y1277485D03*
X1320405Y1277455D03*
X1331189Y1277440D03*
X1328514Y1334603D03*
X1330844Y1335353D03*
X1322110Y1342755D03*
X1318110Y1342017D03*
X1326320Y1344245D03*
X1324848Y1341787D03*
X1318110Y1345073D03*
X1331288Y1372440D03*
X1327491Y1372358D03*
X1324491Y1372658D03*
X1327491Y1375858D03*
X1331288Y1375940D03*
X1324491Y1375858D03*
X1327491Y1381478D03*
Y1378478D03*
X1331288Y1378560D03*
X1324491Y1381478D03*
Y1378478D03*
X1331304Y1401986D03*
Y1404986D03*
X1327926D03*
X1322228Y1419890D03*
X1322186Y1411326D03*
Y1414326D03*
Y1417326D03*
X1322270Y1422454D03*
X1325084Y1420066D03*
X1325042Y1408502D03*
Y1411502D03*
Y1417502D03*
Y1414502D03*
X1331344Y1414456D03*
X1330804Y1411536D03*
Y1408536D03*
X1331386Y1420020D03*
X1328008D03*
X1331344Y1417456D03*
X1327966Y1408456D03*
Y1411456D03*
Y1417456D03*
Y1414456D03*
X1331428Y1422584D03*
X1328050D03*
X1322312Y1425018D03*
X1325126Y1422630D03*
X1325168Y1425194D03*
X1328092Y1425148D03*
X1331470D03*
X1333190Y58825D03*
X1347640Y101950D03*
X1345583Y91307D03*
X1336549Y105970D03*
X1344631Y127244D03*
X1332497Y133931D03*
X1343034Y141698D03*
X1336761Y293404D03*
X1340161D03*
X1335145Y332616D03*
X1341431Y322693D03*
X1331745Y332616D03*
X1338031Y322693D03*
X1345424Y328981D03*
X1344720Y423162D03*
X1337220D03*
X1342220D03*
X1339720D03*
X1333143Y540049D03*
X1340420Y538422D03*
Y541822D03*
X1347419Y1259257D03*
X1347379Y1256687D03*
X1336269Y1274957D03*
X1333969Y1264567D03*
X1334029Y1261997D03*
X1333909Y1267167D03*
X1336339Y1269777D03*
X1336279Y1272347D03*
X1347359Y1261857D03*
X1347371Y1264564D03*
X1336519Y1264627D03*
X1336579Y1262057D03*
X1347366Y1267188D03*
X1336459Y1267227D03*
X1333687Y1269903D03*
Y1272403D03*
Y1274903D03*
X1333676Y1280218D03*
X1336261Y1277654D03*
X1333699Y1277410D03*
X1343948Y1317092D03*
Y1319592D03*
X1344532Y1328161D03*
X1347397Y1325320D03*
X1336144Y1341147D03*
X1338288Y1339653D03*
X1340488Y1340853D03*
X1336144Y1338247D03*
X1340214Y1334853D03*
X1340410Y1338017D03*
X1338288Y1336553D03*
X1333174Y1334603D03*
X1335504Y1335353D03*
X1334288Y1372440D03*
X1340288D03*
X1346193Y1372523D03*
X1343193D03*
X1337288Y1372440D03*
Y1375940D03*
X1334288D03*
X1343193Y1376023D03*
X1346193D03*
X1340288Y1375940D03*
X1346304Y1401986D03*
X1343304D03*
X1340304D03*
X1337304D03*
X1334304D03*
Y1404986D03*
X1346304D03*
X1343304D03*
X1340304D03*
X1337304D03*
X1337344Y1414456D03*
X1346344D03*
X1343344D03*
X1340344D03*
X1346534Y1411496D03*
Y1408496D03*
X1334344Y1414456D03*
X1346344Y1417456D03*
X1340344D03*
X1337344D03*
X1334386Y1420020D03*
X1334344Y1417456D03*
X1346386Y1420020D03*
X1343386D03*
X1340386D03*
X1337386D03*
X1343344Y1417456D03*
X1337428Y1422584D03*
X1340428D03*
X1343428D03*
X1334428D03*
X1337328Y1425164D03*
X1340328D03*
X1343328D03*
X1346178Y1425254D03*
X1346278Y1422674D03*
X1334470Y1425148D03*
X1348610Y84712D03*
X1349480Y77072D03*
X1366369Y83820D03*
X1349570Y104147D03*
X1353394Y131812D03*
X1348620Y136162D03*
X1349220Y140362D03*
X1348824Y328981D03*
X1358371Y332275D03*
X1361771D03*
X1355200Y337843D03*
X1351800D03*
X1356220Y581862D03*
X1356047Y680000D03*
X1358907Y681262D03*
X1361727Y680665D03*
X1352474Y1256866D03*
X1349964Y1256896D03*
X1352486Y1259373D03*
X1349976Y1259403D03*
X1363258Y1256851D03*
Y1259351D03*
X1349876Y1267158D03*
X1352426Y1267218D03*
X1363266Y1267188D03*
X1349976Y1261903D03*
X1352486Y1261873D03*
Y1264373D03*
X1349976Y1264403D03*
X1363258Y1261851D03*
X1363270Y1264358D03*
X1360593Y1321872D03*
X1363098Y1320951D03*
X1354238Y1329329D03*
X1350238Y1328591D03*
X1358448Y1330819D03*
X1356976Y1328361D03*
X1350238Y1331647D03*
X1352666Y1378560D03*
X1349666D03*
X1352666Y1381560D03*
X1349666D03*
X1352666Y1375940D03*
X1349666D03*
X1352126Y1401986D03*
X1349426D03*
X1352126Y1404986D03*
X1349426D03*
X1349508Y1420020D03*
X1352166Y1420456D03*
Y1414456D03*
Y1411456D03*
Y1408456D03*
Y1417456D03*
X1349466Y1411456D03*
Y1408456D03*
Y1417456D03*
Y1414456D03*
X1349278Y1422674D03*
X1364860Y1455172D03*
X1362410Y1445272D03*
X1378839Y87626D03*
X1366369Y92450D03*
X1366714Y109506D03*
X1376991Y176430D03*
X1373591D03*
X1375619Y236261D03*
X1375257Y229756D03*
X1373493Y227762D03*
X1370207Y682245D03*
X1374938Y1161569D03*
Y1170069D03*
X1379579Y1259317D03*
X1368379Y1259287D03*
X1379639Y1256747D03*
X1368439Y1256717D03*
X1365768Y1256821D03*
Y1259321D03*
X1365776Y1267158D03*
X1368326Y1267218D03*
X1379519Y1261917D03*
X1379531Y1264624D03*
X1379526Y1267248D03*
X1368361Y1264594D03*
X1368369Y1261897D03*
X1365768Y1261821D03*
X1365780Y1264328D03*
X1376076Y1317092D03*
Y1319592D03*
X1379192Y1325373D03*
X1368272Y1324821D03*
X1372538Y1324591D03*
X1370338Y1323091D03*
X1372538Y1321691D03*
X1365376Y1321938D03*
X1367635Y1320904D03*
X1377214Y1327653D03*
X1368272Y1327721D03*
X1370438Y1326091D03*
X1372538Y1327491D03*
X1377054Y1394028D03*
X1367316Y1399053D03*
Y1403458D03*
X1370577Y1421899D03*
X1367436Y1414778D03*
X1370891Y1410306D03*
X1378417Y1415292D03*
X1367316Y1407458D03*
X1367889Y1419235D03*
X1377075Y1425014D03*
X1365235Y1428637D03*
X1370250Y1433715D03*
X1367620Y1431472D03*
X1367170Y1453142D03*
X1368842Y1449261D03*
X1364800Y1449231D03*
X1368980Y1457122D03*
X1370041Y1460374D03*
X1393250Y93802D03*
X1386684Y145017D03*
X1386404Y149008D03*
X1394182Y171470D03*
X1398182D03*
X1395960Y226422D03*
X1393460D03*
X1386868Y222937D03*
X1384017Y223697D03*
X1386138Y225411D03*
X1384895Y221346D03*
X1381951Y221420D03*
X1381235Y236020D03*
X1390600Y248262D03*
X1392685Y498992D03*
X1387550Y502922D03*
X1387600Y499182D03*
X1391260Y507082D03*
X1396081Y1161569D03*
Y1153369D03*
Y1170069D03*
X1384652Y1256866D03*
X1382142Y1256896D03*
X1384664Y1259373D03*
X1382154Y1259403D03*
X1395436Y1256851D03*
Y1259351D03*
X1384586Y1267278D03*
X1395426Y1267188D03*
X1382036Y1267218D03*
X1382154Y1261903D03*
X1384664Y1261873D03*
Y1264373D03*
X1382154Y1264403D03*
X1395436Y1261851D03*
X1395448Y1264358D03*
X1392770Y1321177D03*
X1395100Y1321927D03*
X1386366Y1329329D03*
X1382366Y1328591D03*
X1390576Y1330819D03*
X1389104Y1328361D03*
X1382366Y1331647D03*
X1396311Y1385712D03*
X1398680Y1380582D03*
X1390474Y1385142D03*
X1387074Y1384272D03*
X1390513Y1395452D03*
X1387066Y1401734D03*
X1387291Y1408163D03*
X1387470Y1418302D03*
X1385109Y1410427D03*
X1390170Y1423942D03*
X1387068Y1413991D03*
X1381066Y1425008D03*
X1393630Y1426562D03*
X1388557Y1431645D03*
X1395907Y1430227D03*
X1395443Y1434700D03*
X1398569Y1437860D03*
X1383429Y1427652D03*
X1392620Y1446708D03*
X1389220D03*
X1382600Y1563480D03*
X1391655Y1570037D03*
X1391055Y1565037D03*
X1384840Y1565640D03*
X1386790Y1563610D03*
X1396600Y1590200D03*
Y1586400D03*
X1393000Y1590300D03*
X1395325Y1606862D03*
X1386200Y1645700D03*
X1386600Y1641400D03*
X1407029Y152732D03*
X1410370Y138742D03*
X1406970D03*
X1407029Y156132D03*
X1401341Y177159D03*
X1404829Y184263D03*
X1404741Y177159D03*
X1408229Y184263D03*
X1407178Y171684D03*
X1403778D03*
X1413900Y225212D03*
X1396900Y228932D03*
X1398831Y1161569D03*
Y1153369D03*
Y1170069D03*
X1411909Y1259257D03*
X1400599Y1256717D03*
X1411969Y1256687D03*
X1397946Y1256821D03*
Y1259321D03*
X1400539Y1259287D03*
X1400521Y1264594D03*
X1400529Y1261897D03*
X1397936Y1267158D03*
X1400486Y1267218D03*
X1411849Y1261857D03*
X1411861Y1264564D03*
X1411856Y1267188D03*
X1397946Y1261821D03*
X1397958Y1264328D03*
X1408204Y1317092D03*
Y1319592D03*
X1411320Y1325373D03*
X1400400Y1324821D03*
X1404666Y1324591D03*
X1402466Y1323091D03*
X1404666Y1321691D03*
X1397430Y1321177D03*
X1399760Y1321927D03*
X1408969Y1327645D03*
X1402566Y1326091D03*
X1400400Y1327721D03*
X1404666Y1327491D03*
X1401655Y1384676D03*
X1406461Y1383862D03*
X1415171Y1383692D03*
X1412961Y1387387D03*
X1412608Y1391687D03*
X1414362Y1402191D03*
X1414786Y1426890D03*
X1413440Y1436774D03*
X1409680Y1430613D03*
X1401371Y1434592D03*
X1410477Y1440117D03*
X1410038Y1434670D03*
X1403687Y1444711D03*
X1400287D03*
X1400220Y1518862D03*
X1409248Y1528862D03*
X1400160Y1543342D03*
X1404433Y1565037D03*
X1400695Y1570037D03*
X1400715Y1565037D03*
X1407440Y1557552D03*
X1404433Y1570037D03*
X1402536Y1576097D03*
X1402680Y1597700D03*
X1401300Y1619917D03*
X1410900Y1624800D03*
X1400000Y1626362D03*
Y1634362D03*
Y1638362D03*
X1410500Y1638862D03*
X1396900Y1642100D03*
X1413950Y184263D03*
X1423110D03*
X1417350D03*
X1426510D03*
X1428336Y232762D03*
X1415340Y231812D03*
X1418630Y220018D03*
X1422030D03*
X1413847Y239528D03*
X1426020Y261501D03*
X1431430Y256383D03*
Y264060D03*
X1426647Y329050D03*
X1417022Y621419D03*
X1424119Y1161520D03*
X1426619D03*
X1424119Y1153369D03*
X1426619D03*
Y1169570D03*
X1424119D03*
X1416999Y1256866D03*
X1414489Y1256896D03*
X1417011Y1259373D03*
X1414501Y1259403D03*
X1427783Y1256851D03*
Y1259351D03*
X1414366Y1267158D03*
X1416916Y1267218D03*
X1427786Y1267158D03*
X1414501Y1261903D03*
X1417011Y1261873D03*
Y1264373D03*
X1414501Y1264403D03*
X1427783Y1261851D03*
X1427795Y1264358D03*
X1424898Y1321177D03*
X1427228Y1321927D03*
X1418494Y1329329D03*
X1414494Y1328591D03*
X1422704Y1330819D03*
X1421232Y1328361D03*
X1414494Y1331647D03*
X1418990Y1387452D03*
X1422594Y1383301D03*
X1419995Y1397492D03*
X1415620Y1396652D03*
X1419055Y1392497D03*
X1426872Y1405811D03*
X1423256Y1403728D03*
X1424255Y1396612D03*
X1421480Y1415731D03*
X1422371Y1407722D03*
X1421371Y1411719D03*
X1421864Y1419730D03*
X1419991Y1423404D03*
X1424930Y1433850D03*
X1416272Y1433949D03*
X1421435Y1430415D03*
X1419746Y1435932D03*
X1414350Y1516435D03*
X1426020Y1521535D03*
X1414590Y1532255D03*
X1414350Y1521335D03*
X1427120Y1537355D03*
X1414590Y1537155D03*
X1414740Y1543475D03*
Y1548375D03*
X1427320Y1548575D03*
X1425620Y1556662D03*
X1416060Y1574922D03*
X1422680Y1582100D03*
X1419450Y1596150D03*
X1423700Y1600400D03*
X1434600Y59262D03*
X1444275Y57262D03*
X1432220Y61862D03*
X1440800Y66862D03*
X1447340Y157402D03*
X1442434Y210757D03*
X1430120Y225182D03*
X1431636Y230448D03*
X1444570Y238372D03*
X1431933Y238125D03*
X1431431Y267378D03*
X1436120Y315772D03*
X1436270Y312592D03*
X1436335Y309407D03*
X1436320Y305862D03*
Y303362D03*
X1436050Y321352D03*
X1436120Y318272D03*
X1436232Y344176D03*
X1433418Y729104D03*
X1444099Y1259397D03*
X1432899Y1259257D03*
X1444159Y1256827D03*
X1432959Y1256687D03*
X1430293Y1256821D03*
Y1259321D03*
X1444051Y1264704D03*
X1444039Y1261997D03*
X1444046Y1267328D03*
X1432889Y1261867D03*
X1432881Y1264564D03*
X1432846Y1267188D03*
X1430296Y1267128D03*
X1430293Y1261821D03*
X1430305Y1264328D03*
X1440332Y1317092D03*
Y1319592D03*
X1443448Y1325373D03*
X1432528Y1324821D03*
X1436794Y1324591D03*
X1434594Y1323091D03*
X1436794Y1321691D03*
X1429558Y1321177D03*
X1431888Y1321927D03*
X1441332Y1327793D03*
X1434694Y1326091D03*
X1432528Y1327721D03*
X1436794Y1327491D03*
X1437443Y1406289D03*
X1444997Y1392885D03*
X1435462Y1393009D03*
Y1396409D03*
X1434312Y1415197D03*
X1443112Y1417929D03*
X1445020Y1412672D03*
X1443676Y1432624D03*
X1433750Y1429208D03*
X1439742Y1436924D03*
X1434720Y1454862D03*
X1440440Y1454892D03*
X1444468Y1570610D03*
X1433720Y1569762D03*
X1440105Y1593352D03*
X1446700Y1598400D03*
X1438300Y1606800D03*
Y1602600D03*
X1430250Y1612812D03*
X1441800Y1628700D03*
Y1624500D03*
X1438547Y1638212D03*
X1443617D03*
X1431575Y1634842D03*
X1442573Y1649862D03*
X1442587Y1659242D03*
X1438320Y1668292D03*
X1438220Y1673955D03*
X1446715Y1679957D03*
X1446000Y67802D03*
X1458720Y145362D03*
X1450270Y143022D03*
X1450720Y153362D03*
X1448820Y148092D03*
X1450720Y169862D03*
Y161862D03*
X1449740Y166912D03*
X1450720Y181862D03*
Y177862D03*
Y173862D03*
X1462561Y205982D03*
X1457361D03*
X1459961Y210432D03*
X1456150Y214382D03*
X1449110Y233742D03*
X1455600Y297200D03*
X1456770Y342942D03*
X1460849Y343327D03*
X1462790Y359042D03*
X1462870Y355012D03*
X1449777Y362021D03*
X1459900Y370823D03*
X1455920Y373941D03*
X1463600Y374462D03*
X1449777Y371039D03*
X1455642Y409646D03*
X1449296Y407347D03*
X1449600Y402322D03*
X1456777Y418596D03*
Y426546D03*
X1456237Y726945D03*
X1457620Y736195D03*
X1460187Y729805D03*
X1455692Y731401D03*
X1457714Y741622D03*
X1447149Y1161569D03*
X1449649D03*
X1447299Y1153369D03*
X1449799D03*
X1447149Y1170069D03*
X1449649D03*
X1449176Y1256866D03*
X1446666Y1256896D03*
X1449188Y1259373D03*
X1446678Y1259403D03*
X1459960Y1259351D03*
Y1256851D03*
X1449106Y1267358D03*
X1459886Y1267218D03*
X1446556Y1267298D03*
X1446678Y1261903D03*
X1449188Y1261873D03*
Y1264373D03*
X1446678Y1264403D03*
X1459960Y1261851D03*
X1459972Y1264358D03*
X1457026Y1321177D03*
X1461686D03*
X1459356Y1321927D03*
X1450622Y1329329D03*
X1446622Y1328591D03*
X1454832Y1330819D03*
X1453360Y1328361D03*
X1446622Y1331647D03*
X1459968Y1402765D03*
X1451176Y1399026D03*
X1451198Y1403047D03*
X1460224Y1407545D03*
X1458138Y1409955D03*
X1461062Y1413246D03*
X1455006Y1447938D03*
X1459111Y1445669D03*
Y1448669D03*
X1457577Y1526689D03*
X1457817Y1542509D03*
X1457967Y1553729D03*
X1458200Y1565037D03*
Y1560037D03*
X1448620Y1556162D03*
X1456030Y1590302D03*
X1456120Y1586262D03*
X1453600Y1595662D03*
X1451500Y1612800D03*
X1454167Y1638302D03*
X1459127D03*
X1448507Y1638212D03*
X1448920Y1675062D03*
X1474142Y61767D03*
X1462000Y153362D03*
X1470220Y169862D03*
X1473090Y204502D03*
X1472335Y209362D03*
X1467761Y205982D03*
X1471308Y230640D03*
X1463833Y230448D03*
X1474660Y252878D03*
X1463808Y244948D03*
X1463833Y235566D03*
X1473820Y265962D03*
X1471510Y252878D03*
X1471690Y259862D03*
X1463950Y258172D03*
X1463330Y264060D03*
X1463510Y273878D03*
X1475452Y289708D03*
X1475352Y306308D03*
X1476826Y312177D03*
X1467700Y370953D03*
X1472758Y370817D03*
X1465836Y408668D03*
X1470942Y409718D03*
X1475250Y401812D03*
X1469777Y418396D03*
X1469951Y429251D03*
X1469720Y434542D03*
X1469760Y452622D03*
X1471460Y633402D03*
X1468060D03*
X1465171Y647132D03*
X1469020Y647102D03*
X1470841Y721493D03*
X1464999Y1259317D03*
X1476369Y1259237D03*
X1465059Y1256747D03*
X1462470Y1259321D03*
Y1256821D03*
X1476291Y1275224D03*
X1464946Y1267248D03*
X1464989Y1261927D03*
X1464981Y1264624D03*
X1476339Y1264467D03*
Y1267037D03*
X1476309Y1261807D03*
X1476279Y1269637D03*
X1476291Y1272344D03*
X1462396Y1267188D03*
X1462470Y1261821D03*
X1462482Y1264328D03*
X1476291Y1278104D03*
X1464016Y1321927D03*
X1466819Y1324018D03*
X1469019Y1322618D03*
X1473956Y1341068D03*
X1472460Y1330493D03*
Y1333043D03*
X1475576Y1338799D03*
X1469019Y1325518D03*
X1464680Y1325772D03*
X1469019Y1328418D03*
X1466919Y1327018D03*
X1464680Y1328672D03*
X1467567Y1445669D03*
Y1448669D03*
X1475967Y1445669D03*
Y1448669D03*
X1478320Y1522962D03*
X1472565Y1623635D03*
X1478061Y1633864D03*
X1463767Y1638302D03*
X1476570Y1661124D03*
X1493120Y240412D03*
X1487958Y236062D03*
X1490060Y255378D03*
X1485320Y260362D03*
X1478745Y281508D03*
X1493289Y280027D03*
X1478526Y289677D03*
X1481445Y289708D03*
X1479745Y312208D03*
X1478426Y306277D03*
X1481345Y306308D03*
X1481484Y361688D03*
X1481766Y372288D03*
X1489443D03*
X1494784Y374188D03*
X1486040Y368392D03*
X1481766Y406238D03*
X1490384Y407292D03*
X1493384Y411313D03*
X1482650Y411190D03*
X1495527Y406215D03*
X1486880Y416863D03*
X1484805Y427577D03*
X1489310Y426822D03*
X1481539Y1259377D03*
X1478999Y1259257D03*
X1481479Y1261947D03*
X1481419Y1264547D03*
X1481431Y1267254D03*
X1478939Y1261827D03*
X1478879Y1264427D03*
X1478891Y1267134D03*
X1481359Y1271447D03*
X1492039D03*
X1481359Y1274144D03*
X1492091D03*
X1478859Y1271417D03*
Y1274114D03*
X1481361Y1280054D03*
X1492101D03*
X1478821D03*
X1481359Y1277024D03*
X1492091D03*
X1478859Y1276994D03*
X1489154Y1334603D03*
X1493814D03*
X1491484Y1335353D03*
X1482750Y1342755D03*
X1478750Y1342017D03*
X1486960Y1344245D03*
X1485488Y1341787D03*
X1478750Y1345073D03*
X1485387Y1420002D03*
X1481918Y1425579D03*
X1484442Y1445557D03*
Y1448557D03*
X1482830Y1525162D03*
X1480800Y1663600D03*
X1510500Y125992D03*
X1508959Y215802D03*
X1503020D03*
X1499922Y211240D03*
X1496720Y225292D03*
X1504484Y234562D03*
X1508410Y230842D03*
X1510017Y225516D03*
X1501840Y225502D03*
X1512420Y239116D03*
X1510810Y249742D03*
X1509040Y243362D03*
X1504890Y249862D03*
X1506600Y239092D03*
X1504650Y254392D03*
X1508049Y280056D03*
X1498984Y282797D03*
X1508558Y291175D03*
X1512244Y311522D03*
X1505922Y304583D03*
X1509539Y308467D03*
X1498184Y361723D03*
Y369798D03*
X1495150Y369842D03*
X1503450Y385843D03*
X1509638Y738627D03*
X1509350Y741315D03*
X1504747Y747293D03*
X1503514Y801361D03*
Y797961D03*
X1497199Y1275667D03*
X1497259Y1273097D03*
X1494629Y1271477D03*
X1494631Y1274144D03*
X1506569Y1285947D03*
X1508819Y1284797D03*
X1506539Y1288557D03*
X1508759Y1287367D03*
X1508699Y1289967D03*
X1494641Y1280054D03*
X1494631Y1277024D03*
X1506551Y1291254D03*
X1497199Y1278277D03*
X1497161Y1280974D03*
X1506689Y1283377D03*
X1506591Y1297014D03*
Y1294134D03*
X1508711Y1295554D03*
Y1298434D03*
Y1292674D03*
X1496784Y1341147D03*
X1498924Y1334882D03*
X1498950Y1339517D03*
X1501149Y1336287D03*
X1496784Y1338247D03*
X1496144Y1335353D03*
X1504588Y1353316D03*
Y1355816D03*
X1501033Y1341462D03*
X1498959Y1342930D03*
X1505570Y1364212D03*
X1507704Y1361597D03*
X1510027Y1425825D03*
X1507617Y1424045D03*
X1522920Y116180D03*
X1513900Y117762D03*
X1518575Y138662D03*
X1521115Y193262D03*
X1524539Y215551D03*
X1522009Y210825D03*
X1518110Y215551D03*
X1526998Y209645D03*
X1527732Y219488D03*
X1514520Y231116D03*
X1526152Y225114D03*
X1514593Y249698D03*
Y235116D03*
X1519758Y265161D03*
X1522786Y262558D03*
X1522258Y265161D03*
X1519833Y277297D03*
X1522258Y288956D03*
X1517669Y291516D03*
X1515940Y795815D03*
Y799215D03*
X1513789Y1290037D03*
X1511289Y1287397D03*
X1511199Y1290007D03*
X1513791Y1292704D03*
X1516351D03*
X1513791Y1298464D03*
Y1295584D03*
X1516351D03*
Y1298464D03*
X1511251Y1292704D03*
Y1298464D03*
Y1295584D03*
X1521282Y1357401D03*
X1525942D03*
X1514878Y1365553D03*
X1510878Y1364815D03*
X1519088Y1367043D03*
X1517616Y1364585D03*
X1510878Y1367871D03*
X1523612Y1358151D03*
X1512177Y1427795D03*
X1516137Y1432135D03*
X1513657Y1429985D03*
X1544010Y27552D03*
X1536310Y47492D03*
X1534060Y100162D03*
X1530660D03*
X1533520Y110662D03*
X1529500Y122122D03*
X1535575Y118862D03*
X1540090Y122782D03*
X1536925Y129937D03*
X1529500Y125862D03*
X1535520Y151562D03*
X1529233Y153162D03*
X1535450Y155262D03*
X1542401Y141561D03*
X1534720Y199803D03*
X1528720Y199862D03*
X1533385Y193108D03*
X1533148Y211614D03*
X1531824Y207677D03*
X1534194Y217519D03*
X1529670Y225522D03*
X1535561Y225393D03*
X1531110Y264862D03*
X1539150Y267132D03*
X1540958Y307756D03*
X1539720Y589862D03*
Y581862D03*
X1540377Y634165D03*
X1541211Y646178D03*
X1533178Y1360815D03*
X1530978Y1359315D03*
X1528912Y1361045D03*
X1531078Y1362315D03*
X1533178Y1363715D03*
X1528912Y1363945D03*
X1533178Y1357915D03*
X1528272Y1358151D03*
X1556413Y19495D03*
X1549308Y26431D03*
X1552708D03*
X1552960Y124359D03*
X1553189Y127781D03*
X1556049Y147711D03*
X1545763Y159305D03*
X1551160Y189342D03*
X1557900Y220362D03*
X1557760Y214792D03*
X1550353Y217352D03*
X1557320Y203297D03*
X1559400Y229832D03*
X1545668Y305266D03*
X1545768Y302766D03*
X1543958Y307556D03*
X1546458Y307856D03*
X1543858Y310056D03*
X1543720Y581862D03*
X1548720D03*
X1552720Y589862D03*
Y581862D03*
X1554753Y628860D03*
X1553312Y636815D03*
X1559354Y655716D03*
Y659116D03*
X1550487Y681565D03*
X1550320Y696562D03*
X1550917Y704332D03*
X1550390Y709885D03*
X1570586Y19495D03*
X1573986D03*
X1559813D03*
X1563481Y26431D03*
X1566881D03*
X1573560Y245078D03*
X1574760Y251032D03*
X1559722Y243110D03*
X1570675Y267857D03*
X1573246Y306650D03*
X1572396Y309450D03*
X1563714Y572792D03*
X1567114D03*
X1559557Y593290D03*
X1564768Y708159D03*
X1562871Y732316D03*
Y735716D03*
X1571577Y747145D03*
X1567547Y755485D03*
X1571920Y762662D03*
X1568490Y758162D03*
X1570374Y760093D03*
X1584759Y19495D03*
X1588159D03*
X1577654Y26431D03*
X1591828D03*
X1581054D03*
X1576589Y300927D03*
X1588314Y592553D03*
X1585714D03*
X1583114D03*
X1590914D03*
X1588254Y595103D03*
X1588284Y597613D03*
X1585654Y595103D03*
X1585684Y597613D03*
X1583084D03*
X1583054Y595103D03*
X1588284Y608655D03*
X1585684D03*
X1583084D03*
X1590854Y595103D03*
X1590884Y597613D03*
Y608655D03*
X1588254Y613715D03*
X1588224Y611205D03*
X1585654Y613715D03*
X1585624Y611205D03*
X1583024D03*
X1583054Y613715D03*
X1590854D03*
X1590824Y611205D03*
X1591368Y628727D03*
X1591428Y626177D03*
X1588928D03*
X1588868Y628727D03*
X1591398Y631237D03*
X1588898D03*
X1591368Y650877D03*
X1591338Y648367D03*
X1591398Y645817D03*
X1588868Y650877D03*
X1588838Y648367D03*
X1588898Y645817D03*
X1591368Y653377D03*
X1588868D03*
X1591448Y657677D03*
X1588948D03*
Y660177D03*
X1591448D03*
X1588968Y665237D03*
X1591468D03*
X1588938Y662727D03*
X1591438D03*
X1588938Y679807D03*
X1588878Y682357D03*
X1588908Y684867D03*
X1591438Y679807D03*
X1591378Y682357D03*
X1591408Y684867D03*
X1591328Y696727D03*
X1591388Y694177D03*
X1588888D03*
X1588828Y696727D03*
X1591358Y699277D03*
X1588858D03*
X1591358Y718837D03*
X1591328Y716327D03*
X1591388Y713777D03*
X1588858Y718837D03*
X1588828Y716327D03*
X1588888Y713777D03*
X1590915Y755793D03*
X1598933Y19495D03*
X1602333D03*
X1595228Y26431D03*
X1603747Y192951D03*
X1603530Y202402D03*
X1603706Y211526D03*
X1603580Y206902D03*
X1604200Y234642D03*
X1604240Y227892D03*
X1603920Y222922D03*
X1604270Y231490D03*
X1604240Y238242D03*
X1602980Y560002D03*
X1593514Y592553D03*
X1601830Y590685D03*
X1604430D03*
X1607200Y583962D03*
X1593484Y597613D03*
X1593454Y595103D03*
X1593484Y608655D03*
X1593424Y611205D03*
X1593454Y613715D03*
X1601830Y615201D03*
X1604430D03*
X1598868Y628727D03*
X1598928Y626177D03*
X1593868Y628727D03*
X1593928Y626177D03*
X1596428D03*
X1596368Y628727D03*
X1598898Y631237D03*
X1593898D03*
X1596398D03*
X1598868Y650877D03*
X1598838Y648367D03*
X1596368Y650877D03*
X1593868D03*
X1596338Y648367D03*
X1593838D03*
X1598898Y645817D03*
X1596398D03*
X1593898D03*
X1598868Y653377D03*
X1596368D03*
X1593868D03*
X1598948Y657677D03*
X1593948D03*
X1596448D03*
Y660177D03*
X1593948D03*
X1598948D03*
X1596468Y665237D03*
X1593968D03*
X1598968D03*
X1596438Y662727D03*
X1593938D03*
X1598938D03*
X1593938Y679807D03*
X1596438D03*
X1593878Y682357D03*
X1596378D03*
X1593908Y684867D03*
X1596408D03*
X1598878Y682357D03*
X1598908Y684867D03*
X1598938Y679807D03*
X1596288Y688902D03*
X1598888D03*
X1598828Y696727D03*
X1593828D03*
X1593888Y694177D03*
X1596388D03*
X1596328Y696727D03*
X1593858Y699277D03*
X1596358D03*
X1598888Y694177D03*
X1596288Y691502D03*
X1598858Y699277D03*
X1598888Y691502D03*
X1598858Y718837D03*
X1598828Y716327D03*
X1596358Y718837D03*
X1593858D03*
X1596328Y716327D03*
X1593828D03*
X1596388Y713777D03*
X1593888D03*
X1598888D03*
X1596250Y721452D03*
X1598850D03*
X1599010Y724002D03*
X1598440Y736692D03*
X1592760Y736652D03*
X1595600D03*
X1606788Y756199D03*
X1602788D03*
X1621920Y25962D03*
X1622220Y49862D03*
X1623881Y129627D03*
X1610788Y756199D03*
X1614788D03*
X1618788D03*
X1615062Y1421241D03*
X1613047Y1415669D03*
X1614927Y1426076D03*
Y1429896D03*
X1624353Y1428766D03*
Y1431316D03*
X1617215Y1440822D03*
X1634799Y19495D03*
X1638199D03*
X1627694Y26431D03*
X1631094D03*
X1633111Y206693D03*
X1632342Y216015D03*
X1635835Y343002D03*
X1636800Y429982D03*
X1639800D03*
X1636800Y426982D03*
X1639800D03*
X1636800Y438982D03*
X1639800D03*
X1636800Y435982D03*
X1639800D03*
X1636800Y432982D03*
X1639800D03*
X1638928Y756199D03*
X1630928D03*
X1634928D03*
X1638277Y1269065D03*
X1640812Y1270020D03*
X1631203Y1367492D03*
X1628653D03*
X1626153D03*
X1628653Y1372492D03*
X1631203D03*
X1626153D03*
X1631203Y1369992D03*
X1628653D03*
X1626153D03*
X1628653Y1379992D03*
Y1382492D03*
Y1377492D03*
Y1374992D03*
X1631203Y1377492D03*
Y1374992D03*
Y1379992D03*
Y1382492D03*
X1626153Y1379992D03*
Y1382492D03*
Y1374992D03*
Y1377492D03*
X1630643Y1440290D03*
X1627469Y1437072D03*
X1624853Y1440875D03*
X1634643Y1442982D03*
X1638785Y1442483D03*
X1637042Y1440215D03*
X1630643Y1443090D03*
X1635315Y1465745D03*
Y1462745D03*
X1632315Y1468745D03*
X1629815D03*
X1632315Y1465745D03*
X1629815D03*
X1632315Y1462745D03*
X1629815D03*
X1635315Y1468745D03*
Y1460245D03*
X1629815D03*
X1632315D03*
X1629815Y1457745D03*
X1632315D03*
X1635315D03*
X1639645Y1473645D03*
X1648972Y19495D03*
X1652372D03*
X1641867Y26431D03*
X1645267D03*
X1650020Y408952D03*
X1647310Y408922D03*
X1650020Y411452D03*
X1647310Y411422D03*
X1654110Y434177D03*
X1657755Y517910D03*
X1651851Y532057D03*
X1651112Y545572D03*
X1645530Y549160D03*
X1653230Y549322D03*
X1642720Y560862D03*
X1656238Y592113D03*
X1649833Y594946D03*
X1653794Y594956D03*
X1653774Y598576D03*
X1649844Y598555D03*
X1656955Y611090D03*
X1645300Y612202D03*
X1653220Y620662D03*
X1645681Y624011D03*
X1648581D03*
X1651481D03*
X1654809Y638101D03*
X1653319Y642311D03*
X1652351Y639573D03*
X1648811Y628277D03*
X1647081Y626211D03*
X1645917Y628917D03*
Y633577D03*
X1645167Y631247D03*
Y635907D03*
X1650081Y626111D03*
X1651711Y628277D03*
X1651635Y651836D03*
X1652581Y646311D03*
X1643582Y652601D03*
X1655637Y646311D03*
X1641082Y652601D03*
X1649363Y649485D03*
X1654809Y672101D03*
X1652351Y673573D03*
X1645681Y658011D03*
X1648581D03*
X1648811Y662277D03*
X1647081Y660211D03*
X1645917Y662917D03*
Y667577D03*
X1645167Y665247D03*
Y669907D03*
X1650081Y660111D03*
X1651481Y658011D03*
X1651711Y662277D03*
X1641082Y686601D03*
X1651635Y685836D03*
X1652581Y680311D03*
X1653319Y676311D03*
X1643582Y686601D03*
X1655113Y680835D03*
X1649363Y683485D03*
X1654809Y706101D03*
X1648811Y696277D03*
X1645167Y703907D03*
X1645917Y701577D03*
X1645167Y699247D03*
X1645917Y696917D03*
X1650081Y694111D03*
X1645681Y692011D03*
X1647081Y694211D03*
X1648581Y692011D03*
X1651711Y696277D03*
X1651481Y692011D03*
X1641082Y720601D03*
X1651635Y719836D03*
X1652581Y714311D03*
X1653319Y710311D03*
X1652351Y707573D03*
X1643582Y720601D03*
X1655637Y714311D03*
X1649363Y717485D03*
X1651509Y756492D03*
X1650771Y1367492D03*
X1648271D03*
X1645721D03*
X1648271Y1372492D03*
X1650771D03*
X1645721D03*
X1650771Y1369992D03*
X1648271D03*
X1645721D03*
X1648271Y1379992D03*
Y1382492D03*
X1650771Y1379992D03*
Y1382492D03*
X1648271Y1377492D03*
Y1374992D03*
X1650771Y1377492D03*
Y1374992D03*
X1645721Y1377492D03*
Y1374992D03*
Y1379992D03*
Y1382492D03*
X1641047Y1432876D03*
X1645707D03*
X1643377Y1433626D03*
X1648037D03*
X1655762Y1429794D03*
X1648677Y1436220D03*
X1653243Y1435690D03*
X1651043Y1434190D03*
X1653243Y1432790D03*
X1651143Y1437190D03*
X1653243Y1438590D03*
X1648677Y1439120D03*
X1655295Y1453879D03*
X1652295D03*
X1643065Y1462645D03*
Y1465645D03*
Y1468645D03*
Y1460145D03*
Y1457645D03*
X1655295Y1456899D03*
X1652295D03*
X1642645Y1473645D03*
X1646958Y1501553D03*
X1671828Y26431D03*
X1668100Y180852D03*
X1667739Y187187D03*
X1666690Y193290D03*
X1674432Y216981D03*
X1672596Y220541D03*
X1668426Y222432D03*
X1664866Y225162D03*
X1660861Y227548D03*
X1664970Y472112D03*
X1662447Y480619D03*
X1665790Y523417D03*
X1662262Y537334D03*
X1659740Y542222D03*
X1661872Y534703D03*
X1660243Y532071D03*
X1668917Y549992D03*
X1666902Y555115D03*
X1663502D03*
X1658738Y592113D03*
X1661238D03*
X1664197Y602191D03*
X1669222Y604490D03*
X1670700Y594562D03*
X1672500Y596462D03*
X1660660Y602273D03*
X1664410Y617953D03*
X1668920Y617637D03*
X1660754Y609837D03*
X1669397Y614064D03*
X1663471Y609837D03*
X1666686Y757162D03*
X1669303Y1372492D03*
X1664253D03*
X1666753D03*
X1669303Y1367492D03*
Y1369992D03*
X1666753Y1367492D03*
X1664253D03*
Y1369992D03*
X1666753D03*
X1669303Y1379992D03*
Y1382492D03*
Y1377492D03*
Y1374992D03*
X1666753Y1379992D03*
X1664253D03*
X1666753Y1382492D03*
X1664253D03*
X1666753Y1377492D03*
X1664253D03*
Y1374992D03*
X1666753D03*
X1662496Y1428791D03*
Y1431291D03*
X1665612Y1437072D03*
X1662996Y1440922D03*
X1672786Y1442982D03*
X1668786Y1440290D03*
Y1443256D03*
X1657920Y1453405D03*
X1660920D03*
X1657860Y1466545D03*
Y1464045D03*
X1657950Y1456210D03*
X1657860Y1459045D03*
Y1461545D03*
X1660950Y1456210D03*
X1660860Y1466545D03*
Y1464045D03*
Y1459045D03*
Y1461545D03*
X1666123Y1493362D03*
Y1501362D03*
Y1533862D03*
Y1520862D03*
Y1545862D03*
X1671673Y1550815D03*
X1666123Y1557557D03*
X1666198Y1561557D03*
X1671660Y1569412D03*
X1666198Y1581321D03*
X1678933Y19495D03*
X1682333D03*
X1686001Y26431D03*
X1689401D03*
X1675228D03*
X1678994Y217231D03*
X1690208Y421855D03*
X1689095Y462640D03*
X1684940Y463030D03*
X1685779Y491230D03*
X1690229Y481845D03*
X1687238Y485496D03*
X1681817Y495290D03*
X1675664Y513802D03*
X1690999Y513107D03*
X1683702Y514687D03*
X1676600Y523902D03*
X1688768Y518107D03*
X1689544Y543874D03*
X1689506Y539882D03*
X1679941Y552222D03*
X1678860Y556752D03*
X1683369Y562698D03*
Y566098D03*
X1676644Y655345D03*
Y652745D03*
X1679244Y655345D03*
X1681864Y655286D03*
X1679244Y652745D03*
X1676624Y642404D03*
X1676644Y644945D03*
Y647545D03*
Y650145D03*
X1679244Y642345D03*
X1681864Y642286D03*
X1679244Y644945D03*
Y647545D03*
X1681864Y644886D03*
Y647486D03*
Y650086D03*
Y652686D03*
X1679244Y650145D03*
X1673860Y726522D03*
X1681810Y752955D03*
X1688912Y1372492D03*
X1686362D03*
Y1367492D03*
Y1369992D03*
X1688912Y1367492D03*
Y1369992D03*
Y1377492D03*
Y1374992D03*
Y1382492D03*
Y1379992D03*
X1686362D03*
Y1382492D03*
Y1374992D03*
Y1377492D03*
X1679190Y1432876D03*
X1683850D03*
X1681520Y1433626D03*
X1686180D03*
X1686820Y1436520D03*
X1688886Y1434790D03*
X1688986Y1437790D03*
X1676928Y1442483D03*
X1675185Y1440215D03*
X1686820Y1439420D03*
X1680720Y1487062D03*
X1679508Y1498303D03*
X1678340Y1500862D03*
X1679508Y1517803D03*
X1677930Y1520362D03*
X1679508Y1538803D03*
X1678340Y1541362D03*
X1678230Y1590542D03*
X1674220Y1585321D03*
X1696506Y19495D03*
X1693106D03*
X1703617Y26459D03*
X1700217D03*
X1703570Y50649D03*
X1700170D03*
X1702490Y204780D03*
X1704223Y209707D03*
Y212207D03*
X1701164Y209758D03*
X1698566Y214904D03*
X1696066D03*
X1693725Y217409D03*
X1698566Y212404D03*
X1696066D03*
X1698725Y217409D03*
X1696225D03*
X1701164Y212258D03*
X1704264Y217458D03*
X1701264D03*
X1704264Y214958D03*
X1701264D03*
X1698566Y209704D03*
X1696066D03*
X1693466Y209504D03*
Y214704D03*
Y212204D03*
X1693725Y219909D03*
X1698725D03*
X1696225D03*
X1704264Y219958D03*
X1701264D03*
X1704185Y222710D03*
X1698220Y369652D03*
X1699809Y403985D03*
X1695579D03*
X1702959Y404243D03*
X1707780Y410738D03*
X1697161Y406602D03*
X1692429Y403985D03*
X1701124Y423802D03*
X1694050Y416643D03*
X1695455Y422287D03*
X1707544Y431745D03*
X1707568Y420370D03*
X1690140Y434160D03*
X1693720Y455862D03*
X1697220D03*
X1702127Y468719D03*
X1693236Y472650D03*
X1691151Y493678D03*
X1689943Y479304D03*
X1701811Y501318D03*
X1701635Y497177D03*
X1699300Y498632D03*
X1697210Y500802D03*
X1694050Y501422D03*
X1693711Y498527D03*
X1691129Y501697D03*
X1707200Y498962D03*
X1699553Y513107D03*
X1707552Y506731D03*
X1707716Y513562D03*
X1702930Y526102D03*
X1699265Y521507D03*
X1690999Y525507D03*
X1701726Y518107D03*
X1699666Y541507D03*
X1699251Y533642D03*
X1691104Y530503D03*
X1691445Y535011D03*
X1704886Y534564D03*
X1689769Y537339D03*
X1699107Y555783D03*
X1703306Y550064D03*
X1703452Y639381D03*
X1700852D03*
X1698232Y639440D03*
X1700852Y655141D03*
X1703452Y647341D03*
Y649941D03*
Y652541D03*
Y644741D03*
X1700852Y647341D03*
Y649941D03*
Y652541D03*
Y644741D03*
X1698232Y655200D03*
Y644800D03*
Y647400D03*
Y650000D03*
Y652600D03*
X1703452Y641981D03*
X1700852D03*
X1698232Y642040D03*
X1700922Y657781D03*
X1698302Y657840D03*
X1698048Y705662D03*
X1701320Y705678D03*
X1698020Y702962D03*
X1696402Y709533D03*
X1699110Y727452D03*
X1705035Y729210D03*
X1704973Y753019D03*
X1703310Y749455D03*
X1690620Y760702D03*
X1691412Y1372492D03*
Y1367492D03*
Y1369992D03*
Y1377492D03*
Y1374992D03*
Y1382492D03*
Y1379992D03*
X1691086Y1436290D03*
Y1433390D03*
X1693392Y1429808D03*
X1691086Y1439190D03*
X1704723Y1500862D03*
Y1520362D03*
Y1541362D03*
X1705003Y1564057D03*
X1707220Y15662D03*
X1715210Y18282D03*
X1714589Y21562D03*
X1709589Y26062D03*
X1719589Y25862D03*
X1717089D03*
X1710106Y48720D03*
Y40020D03*
X1720895Y68062D03*
X1716875D03*
X1712520Y117862D03*
X1712720Y111862D03*
X1719943Y112667D03*
Y116667D03*
X1713418Y130862D03*
X1721418Y135327D03*
X1717418D03*
X1714490Y142920D03*
X1717140Y148910D03*
X1711700Y140200D03*
X1717619Y165909D03*
X1718110Y159040D03*
X1719530Y162950D03*
X1722078Y189483D03*
X1720310Y191252D03*
X1707159Y217580D03*
Y215080D03*
Y210080D03*
Y222580D03*
Y225080D03*
Y220080D03*
X1713720Y381152D03*
X1717220D03*
X1719200Y371162D03*
X1713720Y391652D03*
Y384652D03*
Y388152D03*
X1717220Y391652D03*
Y388152D03*
Y384652D03*
X1709000Y413362D03*
X1706500D03*
X1709000Y415862D03*
X1706500D03*
X1721220Y458362D03*
X1713977Y457137D03*
X1708977Y458542D03*
X1721936Y469263D03*
X1716134Y478443D03*
X1715711Y474399D03*
X1713977Y470804D03*
X1708977D03*
X1716148Y483720D03*
X1716087Y495665D03*
X1716156Y487685D03*
X1716278Y491676D03*
X1707552Y503331D03*
X1709844Y516106D03*
X1707610Y534113D03*
X1709356Y541144D03*
X1709680Y545432D03*
X1716110Y532632D03*
X1707346Y547504D03*
X1717987Y569705D03*
X1716480Y691410D03*
X1710550Y691327D03*
X1712824Y696476D03*
X1710122Y703509D03*
X1713920Y700962D03*
X1709828Y719283D03*
X1713450Y728222D03*
X1719727Y1472088D03*
X1726720Y49862D03*
X1733720D03*
X1730220D03*
X1736040Y41792D03*
X1732810Y52482D03*
X1736040Y44292D03*
X1730140Y52552D03*
X1727600Y52582D03*
X1725320Y67962D03*
X1723018Y101667D03*
X1723218Y93267D03*
X1738220Y98862D03*
X1736720Y101862D03*
X1729080Y118132D03*
X1739720Y120892D03*
X1728999Y112895D03*
X1730765Y151362D03*
X1733920D03*
X1723670Y149102D03*
X1728320Y169862D03*
X1723090Y173072D03*
Y177072D03*
X1734857Y184865D03*
X1737470Y177147D03*
X1737500Y217962D03*
Y214962D03*
Y211962D03*
Y208962D03*
Y226962D03*
Y223962D03*
Y220962D03*
X1725344Y359334D03*
X1728300Y377787D03*
X1733780Y390620D03*
X1729810D03*
X1737660D03*
X1734290Y423820D03*
X1727700Y417265D03*
X1739316Y480939D03*
X1730954Y478062D03*
X1725522Y482869D03*
X1733354Y490869D03*
Y486869D03*
X1738014Y1287344D03*
X1724431Y1336311D03*
X1734717Y1404340D03*
X1729700Y1462932D03*
X1733200D03*
X1736700D03*
X1736400Y1458942D03*
Y1455442D03*
X1731600Y1457230D03*
X1726120Y1490262D03*
X1726149Y1496270D03*
X1724649Y1513945D03*
X1727674D03*
X1729310Y1520951D03*
X1735310D03*
X1724649Y1505895D03*
X1727674D03*
X1726310Y1530445D03*
X1732310D03*
X1729310D03*
X1735310D03*
X1726310Y1520951D03*
X1732310D03*
X1751065Y39017D03*
X1754620Y39062D03*
X1747720Y31862D03*
Y34362D03*
X1740858Y72330D03*
Y79830D03*
Y74830D03*
Y82330D03*
X1745220Y98862D03*
X1741720D03*
X1743720Y101862D03*
X1740220D03*
X1748720Y97362D03*
X1745010Y122952D03*
X1750820Y119972D03*
X1738520Y151362D03*
X1751220Y147562D03*
X1748465D03*
X1754120Y171562D03*
X1750920Y171662D03*
X1754234Y190836D03*
X1752078Y216728D03*
X1740500Y217962D03*
Y214962D03*
Y211962D03*
Y208962D03*
X1747600Y209062D03*
X1744600D03*
X1751800Y206762D03*
X1752078Y226728D03*
Y224228D03*
Y221728D03*
Y219228D03*
X1740500Y226962D03*
Y223962D03*
Y220962D03*
X1746484Y279682D03*
X1749450Y293862D03*
X1756204Y301695D03*
X1752000Y306562D03*
X1756933Y372452D03*
X1744380Y382892D03*
X1744510Y377452D03*
X1747080Y435870D03*
X1746720Y464862D03*
X1752316Y703969D03*
Y695669D03*
X1752217Y692988D03*
X1752276Y720529D03*
X1752316Y712269D03*
X1747814Y1287344D03*
X1742714Y1287244D03*
X1754165Y1304422D03*
Y1307422D03*
Y1301422D03*
Y1295422D03*
Y1298422D03*
Y1310422D03*
X1738740Y1451742D03*
X1740200Y1462932D03*
X1745111Y1463262D03*
X1747677Y1507388D03*
X1744677D03*
X1747304Y1524976D03*
X1744304D03*
X1762420Y21562D03*
X1765238Y22062D03*
X1768026Y24165D03*
X1769669Y15244D03*
X1761998Y15187D03*
X1765260Y18262D03*
X1757320Y15872D03*
X1758672Y26431D03*
X1755272D03*
X1767220Y26962D03*
X1758669Y50649D03*
X1755269D03*
X1762738Y53262D03*
X1767220Y53342D03*
X1767185Y48817D03*
X1767400Y39915D03*
X1769274Y50742D03*
X1771774Y53682D03*
X1758063Y72623D03*
X1767170Y83607D03*
X1767990Y76797D03*
X1760478Y90027D03*
X1770368Y72691D03*
X1757978Y116727D03*
X1760978D03*
X1763678Y106127D03*
X1769278Y108027D03*
Y110927D03*
Y113727D03*
X1755978Y108427D03*
Y111027D03*
X1760478Y106127D03*
X1758300Y128242D03*
X1763435Y166862D03*
X1765820Y182282D03*
X1767300Y174587D03*
X1755078Y216928D03*
X1761500Y214062D03*
X1765000D03*
X1768500D03*
X1755078Y219428D03*
Y221928D03*
Y224428D03*
X1760104Y301648D03*
X1761936Y310709D03*
X1769230Y310478D03*
X1756800Y364048D03*
Y368048D03*
X1770280Y372452D03*
X1770220Y377452D03*
Y382952D03*
X1757066Y435721D03*
X1757650Y461393D03*
X1768560Y539042D03*
X1766060D03*
X1768317Y686375D03*
X1755112Y703948D03*
Y695648D03*
X1755013Y692967D03*
X1757612Y703948D03*
Y695648D03*
X1755072Y720508D03*
X1755112Y712248D03*
X1757572Y720508D03*
X1757612Y712248D03*
X1757165Y1304422D03*
X1760165D03*
Y1307422D03*
X1757165D03*
X1769165Y1301422D03*
X1766165D03*
X1763165D03*
X1757165D03*
X1760165D03*
X1769165Y1295422D03*
X1766165D03*
X1763165D03*
X1760165D03*
X1757165D03*
X1760165Y1298422D03*
X1757165D03*
X1763165D03*
X1766165D03*
X1769165D03*
X1758352Y1317368D03*
Y1322168D03*
X1757165Y1310422D03*
X1760165D03*
X1759987Y1325375D03*
Y1328275D03*
X1763829Y1337548D03*
X1766829D03*
Y1340448D03*
X1769829Y1337548D03*
Y1340448D03*
X1766829Y1343348D03*
X1769829Y1346248D03*
Y1343348D03*
Y1349148D03*
Y1351858D03*
X1782305Y13647D03*
X1775556Y21471D03*
X1775830Y26522D03*
X1777754Y37746D03*
X1781774Y54462D03*
X1774274Y50742D03*
X1776710Y53562D03*
X1779411Y50692D03*
X1774328Y60087D03*
X1779778Y70027D03*
X1774328Y62987D03*
X1775580Y73330D03*
X1779778Y72927D03*
X1787790Y85132D03*
X1781485Y88192D03*
X1785142Y76032D03*
X1773611Y88293D03*
X1778578Y97927D03*
X1778478Y90627D03*
X1784178Y108227D03*
Y111127D03*
Y113927D03*
X1780320Y153162D03*
X1774950Y167392D03*
X1779500Y171692D03*
X1777520Y178403D03*
Y173903D03*
X1782600Y175932D03*
X1778778Y216928D03*
X1783878D03*
X1772000Y214062D03*
X1778778Y219428D03*
Y221928D03*
X1783878Y224428D03*
Y226928D03*
Y219428D03*
Y221928D03*
X1786089Y287641D03*
X1783563D03*
X1777354Y295489D03*
X1783018Y301729D03*
X1782324Y410432D03*
Y403932D03*
Y425432D03*
Y418932D03*
X1782420Y447137D03*
X1781470Y452065D03*
X1778310Y591152D03*
X1781720Y592742D03*
X1778165Y1307422D03*
Y1304422D03*
Y1301422D03*
X1775165D03*
X1772165D03*
X1778165Y1295422D03*
X1775165D03*
X1772165D03*
Y1298422D03*
X1775165D03*
X1778165D03*
X1784165Y1307422D03*
Y1304422D03*
X1781165Y1307422D03*
Y1304422D03*
X1784165Y1301422D03*
Y1295422D03*
Y1298422D03*
X1781165Y1301422D03*
Y1295422D03*
Y1298422D03*
X1781829Y1324448D03*
X1784829D03*
X1778829D03*
X1778165Y1310422D03*
Y1312922D03*
X1784165Y1310422D03*
Y1312922D03*
X1781165Y1310422D03*
Y1312922D03*
X1781829Y1333148D03*
Y1330248D03*
Y1327348D03*
X1784829Y1333148D03*
Y1330248D03*
Y1327348D03*
X1781829Y1337548D03*
Y1340448D03*
X1784829Y1337548D03*
Y1340448D03*
X1778829Y1333148D03*
Y1330248D03*
Y1327348D03*
Y1337548D03*
X1772829D03*
X1775829D03*
X1778829Y1340448D03*
X1775829D03*
X1772829D03*
X1781829Y1346248D03*
Y1343348D03*
Y1349148D03*
Y1351858D03*
Y1354758D03*
X1772829Y1346248D03*
X1775829D03*
X1778829D03*
X1772829Y1343348D03*
X1775829D03*
X1778829D03*
X1772829Y1349148D03*
X1775829D03*
X1778829D03*
X1772829Y1351858D03*
X1775829D03*
X1778829D03*
X1772829Y1354758D03*
X1775829D03*
X1778829D03*
X1799920Y52594D03*
X1788238Y82292D03*
Y78062D03*
Y74912D03*
X1803215Y154032D03*
X1793269Y287641D03*
X1790743D03*
X1791619Y294441D03*
X1789093D03*
X1800160Y362542D03*
X1800340Y387062D03*
X1791494Y386536D03*
X1792450Y410615D03*
X1792507Y403932D03*
X1792220Y425432D03*
X1792335Y418775D03*
X1796020Y451162D03*
X1791888Y683805D03*
X1800450Y1505230D03*
X1795561Y1524729D03*
X1806920Y150862D03*
X1808910Y143902D03*
X1813335Y155435D03*
X1813325Y177257D03*
X1807220Y179897D03*
X1817157Y373829D03*
X1816224Y410432D03*
X1816994Y398052D03*
X1815724Y423932D03*
X1810792Y417432D03*
X1812161Y472521D03*
X1814537Y1322105D03*
X1813700Y1494762D03*
X1807150Y1505675D03*
X1818289Y1501591D03*
X1811494Y1505349D03*
X1813994Y1507891D03*
X1825762Y167662D03*
X1835760Y185772D03*
X1829695Y226333D03*
X1832295D03*
X1827095D03*
X1824095D03*
X1834895D03*
Y223733D03*
X1824095D03*
X1827095D03*
X1832295D03*
X1829695D03*
X1832295Y233933D03*
X1829695D03*
X1827095D03*
X1824095D03*
X1829695Y231433D03*
X1832295D03*
X1829695Y228933D03*
X1832295D03*
X1827095Y231433D03*
X1824095D03*
X1827095Y228933D03*
X1824095D03*
X1834895Y233933D03*
Y231433D03*
Y228933D03*
X1828204Y328654D03*
X1829189Y363731D03*
X1829434Y406348D03*
X1834005Y401421D03*
X1821280Y413432D03*
X1834600Y406442D03*
X1826914Y431718D03*
X1829514Y1498198D03*
Y1500807D03*
X1832114Y1498198D03*
Y1500807D03*
X1824995Y1502201D03*
X1846691Y166450D03*
X1844157Y182210D03*
X1848435Y172187D03*
X1838880Y195162D03*
X1837895Y226333D03*
Y223733D03*
Y233933D03*
Y231433D03*
Y228933D03*
X1836294Y383592D03*
X1838379Y453921D03*
G54D31*
X174685Y647210D03*
X174393Y678354D03*
X195316Y1430034D03*
X383224Y1354446D03*
X412990D03*
X443326D03*
X458600Y1379662D03*
X472700Y1353962D03*
X526478Y1449795D03*
X708795Y1429579D03*
X1131715Y1532913D03*
X1168627Y1466363D03*
X1175215Y1532913D03*
X1359365Y1353946D03*
X1389131D03*
X1419467D03*
X1434200Y1379362D03*
X1449233Y1353946D03*
X1502956Y1449373D03*
X1670101Y1463655D03*
X1682882Y628017D03*
Y678952D03*
X1769790Y204632D03*
X1799350D03*
X1826405Y269763D03*
Y299056D03*
G54D27*
X70472Y173228D03*
Y236220D03*
G54D46*
X450000Y278543D03*
X470000D03*
X483500Y246362D03*
X473500D03*
X480000Y278543D03*
X490000D03*
X500000D03*
X498563Y607067D03*
X510000Y278543D03*
X520000D03*
X518563Y607067D03*
X508563D03*
X549236Y1441207D03*
X569236D03*
X688500Y1611900D03*
Y1621900D03*
X1041435Y143357D03*
X1056225Y143131D03*
X1041435Y163357D03*
X1056225Y163131D03*
X1099970Y1712570D03*
Y1722570D03*
X1689646Y115669D03*
X1679646D03*
X1689646Y125669D03*
Y135669D03*
X1679646Y125669D03*
Y135669D03*
X1689646Y145669D03*
Y155669D03*
X1679646Y145669D03*
Y155669D03*
X1689646Y165669D03*
X1679646D03*
X1689646Y175669D03*
X1679646D03*
X1771457Y1624646D03*
Y1644646D03*
G54D17*
X27699Y1258727D03*
Y1255381D03*
Y1265420D03*
Y1262074D03*
X43841Y994357D03*
X36399Y1054593D03*
X43841Y1255381D03*
Y1258727D03*
Y1252034D03*
Y1262074D03*
Y1265420D03*
X57299Y766798D03*
X52541Y957546D03*
Y954200D03*
Y1021129D03*
Y1024475D03*
Y1051247D03*
X57399Y1258727D03*
X52820Y1253862D03*
X57399Y1265420D03*
Y1262074D03*
X66099Y780184D03*
Y773491D03*
Y786877D03*
Y803609D03*
Y796916D03*
Y790223D03*
Y847113D03*
Y853806D03*
Y860499D03*
Y863845D03*
Y883924D03*
Y877231D03*
Y870538D03*
Y890617D03*
Y897310D03*
Y900656D03*
Y914042D03*
Y907349D03*
Y927428D03*
Y920735D03*
Y934121D03*
Y944160D03*
Y937467D03*
Y950853D03*
Y980971D03*
Y974278D03*
Y994357D03*
Y987664D03*
Y1027822D03*
Y1021129D03*
Y1047900D03*
Y1041207D03*
Y1034515D03*
Y1061286D03*
Y1054593D03*
Y1074672D03*
Y1067979D03*
Y1091404D03*
Y1081365D03*
Y1084711D03*
Y1098097D03*
Y1111483D03*
Y1104790D03*
Y1128215D03*
Y1118176D03*
Y1121522D03*
Y1141601D03*
Y1134908D03*
Y1148294D03*
Y1154987D03*
Y1158333D03*
Y1171719D03*
Y1165026D03*
Y1185105D03*
Y1178412D03*
Y1191798D03*
Y1208530D03*
Y1201837D03*
Y1195144D03*
X73541Y1255381D03*
Y1258727D03*
Y1252034D03*
Y1265420D03*
Y1262074D03*
X82241Y770144D03*
X86999Y766798D03*
X82241Y776837D03*
Y786877D03*
Y783530D03*
Y800263D03*
Y793570D03*
Y850459D03*
Y843766D03*
Y867192D03*
Y860499D03*
Y857152D03*
Y873885D03*
Y880577D03*
Y887270D03*
Y897310D03*
Y893963D03*
Y917389D03*
Y910696D03*
Y904003D03*
Y924081D03*
Y934121D03*
Y930774D03*
Y947507D03*
Y940814D03*
Y957546D03*
Y954200D03*
Y977625D03*
Y970932D03*
Y991011D03*
Y984318D03*
Y994357D03*
Y1021129D03*
Y1024475D03*
Y1031168D03*
Y1044554D03*
Y1037861D03*
Y1051247D03*
Y1071326D03*
Y1064633D03*
Y1078018D03*
Y1094751D03*
Y1088058D03*
Y1081365D03*
Y1108137D03*
Y1101444D03*
Y1124869D03*
Y1118176D03*
Y1114829D03*
Y1144948D03*
Y1138255D03*
Y1131562D03*
Y1161680D03*
Y1154987D03*
Y1151641D03*
Y1175066D03*
Y1168373D03*
Y1181759D03*
Y1191798D03*
Y1188452D03*
Y1205184D03*
Y1198491D03*
X87099Y1258727D03*
X82241Y1248688D03*
X84334Y1254263D03*
X87099Y1265420D03*
Y1262074D03*
X103241Y994357D03*
Y1255381D03*
Y1258727D03*
Y1252034D03*
Y1265420D03*
Y1262074D03*
X116567Y766775D03*
X111941Y957546D03*
Y954200D03*
X125499Y1061286D03*
X116799Y1258727D03*
X111941Y1248688D03*
X114191Y1254604D03*
X116799Y1265420D03*
Y1262074D03*
X141641Y957546D03*
Y954200D03*
Y994357D03*
Y1057940D03*
X129933Y1238461D03*
X132941Y1255381D03*
Y1258727D03*
Y1252034D03*
X141641Y1248688D03*
X143675Y1255567D03*
X132941Y1265420D03*
Y1262074D03*
X146367Y766775D03*
X160130Y1251847D03*
X146499Y1258727D03*
Y1265420D03*
Y1262074D03*
X176099Y766798D03*
X171341Y957546D03*
Y954200D03*
X162641Y994357D03*
X176199Y1258727D03*
X162641Y1255381D03*
Y1258727D03*
Y1252034D03*
X171341Y1248688D03*
X171947Y1255837D03*
X176199Y1265420D03*
X162641D03*
Y1262074D03*
X176199D03*
X184899Y1061286D03*
X192341Y1255381D03*
Y1258727D03*
Y1252034D03*
Y1265420D03*
Y1262074D03*
X188897Y1578182D03*
X192297D03*
X188897Y1590094D03*
X192297D03*
X205799Y766798D03*
X201041Y957546D03*
Y954200D03*
Y994357D03*
X205899Y1258727D03*
X201041Y1248688D03*
X201193Y1257900D03*
X205899Y1265420D03*
Y1262074D03*
X200957Y1578182D03*
X204357D03*
X200957Y1590094D03*
X204357D03*
X222041Y957546D03*
Y954200D03*
Y994357D03*
Y1255381D03*
X219660Y1260492D03*
X222041Y1252034D03*
Y1265420D03*
Y1262074D03*
X225077Y1578182D03*
X213017D03*
X216417D03*
X225077Y1590094D03*
X213017D03*
X216417D03*
X235499Y766798D03*
X236391Y1002557D03*
X240521Y1000395D03*
X237841Y1000437D03*
X233891Y1002557D03*
X231391D03*
X228891D03*
X235599Y1258727D03*
X230741Y1248688D03*
X235480Y1265406D03*
X235599Y1262074D03*
X237137Y1578182D03*
X240537D03*
X228477D03*
X237137Y1590094D03*
X240537D03*
X228477D03*
X251741Y957546D03*
Y954200D03*
Y994357D03*
X254881Y999650D03*
X257561Y999608D03*
X244299Y1061286D03*
X248047Y1259155D03*
X250467Y1259175D03*
X251707Y1252034D03*
X249603Y1266204D03*
X251699Y1265254D03*
X249197Y1578182D03*
X252597D03*
X249197Y1590094D03*
X252597D03*
X272529Y111053D03*
X265442D03*
X261899D03*
Y108553D03*
X265442D03*
X268985Y111053D03*
Y108553D03*
X272529D03*
X260441Y1057940D03*
Y1248688D03*
X273317Y1578182D03*
X261257D03*
X264657D03*
X273317Y1590094D03*
X261257D03*
X264657D03*
X285377Y1578182D03*
X288777D03*
X276717D03*
X285377Y1590094D03*
X288777D03*
X276717D03*
X297437Y1578182D03*
X300837D03*
X297437Y1590094D03*
X300837D03*
X321557Y1578182D03*
X309497D03*
X312897D03*
X321557Y1590094D03*
X309497D03*
X312897D03*
X333617Y1578182D03*
X337017D03*
X324957D03*
X333617Y1590094D03*
X337017D03*
X324957D03*
X345677Y1578182D03*
X349077D03*
X345677Y1590094D03*
X349077D03*
X369797Y1578182D03*
X357737D03*
X361137D03*
X369797Y1590094D03*
X357737D03*
X361137D03*
X373197Y1578182D03*
Y1590094D03*
X476451Y1578182D03*
X485111D03*
X473051D03*
X476451Y1590094D03*
X485111D03*
X473051D03*
X500571Y1578182D03*
X488511D03*
X497171D03*
X500571Y1590094D03*
X488511D03*
X497171D03*
X512631Y1578182D03*
X509231D03*
X512631Y1590094D03*
X509231D03*
X524691Y1578182D03*
X533351D03*
X521291D03*
X524691Y1590094D03*
X533351D03*
X521291D03*
X536751Y1578182D03*
X548811D03*
X545411D03*
X536751Y1590094D03*
X548811D03*
X545411D03*
X560871Y1578182D03*
X557471D03*
X560871Y1590094D03*
X557471D03*
X572931Y1578182D03*
X581591D03*
X569531D03*
X572931Y1590094D03*
X581591D03*
X569531D03*
X597051Y1578182D03*
X584991D03*
X593651D03*
X597051Y1590094D03*
X584991D03*
X593651D03*
X609111Y1578182D03*
X605711D03*
X609111Y1590094D03*
X605711D03*
X629658Y766478D03*
X623347Y999665D03*
X625780Y1000198D03*
X620899Y1061286D03*
X629931Y1258727D03*
X632080Y1262074D03*
X629699Y1255381D03*
X631270Y1264942D03*
X621171Y1578182D03*
X629831D03*
X617771D03*
X621171Y1590094D03*
X629831D03*
X617771D03*
X636941Y957546D03*
Y954200D03*
X644347Y1003135D03*
X640327D03*
X640467Y1000735D03*
X647447Y1002865D03*
X647397Y1000135D03*
X644257Y1000325D03*
X636946Y1258414D03*
X647690Y1260812D03*
X637041Y1252034D03*
X645897Y1248785D03*
X647877Y1254076D03*
X636877Y1261235D03*
X645291Y1578182D03*
X633231D03*
X641891D03*
X645291Y1590094D03*
X633231D03*
X641891D03*
X667677Y441636D03*
X650107Y1002825D03*
X650599Y1258727D03*
X666741Y1255381D03*
X664630Y1259442D03*
X649587Y1266766D03*
X661400Y1263522D03*
X657351Y1578182D03*
X653951D03*
X657351Y1590094D03*
X653951D03*
X674628Y424313D03*
X671479Y421163D03*
X667660Y429037D03*
X674628Y427462D03*
X677778Y414864D03*
Y424313D03*
X671479Y414864D03*
X674628Y421163D03*
Y418013D03*
X677778D03*
Y421163D03*
X668329D03*
X677778Y427462D03*
Y430612D03*
X674628Y436911D03*
X671479D03*
X677778Y433761D03*
X668329Y436911D03*
X677778Y440061D03*
X674628D03*
X677778Y436911D03*
Y443210D03*
X680928Y440061D03*
X674628Y430612D03*
X671479Y443211D03*
X677778Y449510D03*
X668329Y452659D03*
X674628D03*
X671479D03*
X677778D03*
X668329Y455809D03*
X671479Y458959D03*
X674628D03*
X668329D03*
X677778D03*
Y455809D03*
X674628D03*
X668067Y462090D03*
X677778Y462108D03*
X671479Y455809D03*
X680928Y458959D03*
X674628Y449510D03*
Y462108D03*
X677778Y477856D03*
Y471557D03*
Y474707D03*
X671479Y465258D03*
X674628D03*
X668329D03*
X677778D03*
Y468407D03*
X671479Y481006D03*
X667350Y470680D03*
X671479Y474707D03*
X674628Y484006D03*
X680299Y766798D03*
X666641Y957546D03*
Y954200D03*
X672063Y998632D03*
X680299Y1061286D03*
Y1258727D03*
X666741Y1252034D03*
X675537Y1248885D03*
X677980Y1262074D03*
X666741D03*
X666646Y1264464D03*
X680046Y1264964D03*
X695055Y112678D03*
Y115178D03*
X687227Y414864D03*
X690376Y421163D03*
Y418013D03*
Y414864D03*
X693526Y427462D03*
X687227Y424313D03*
X690376Y427462D03*
X680928Y414864D03*
Y418013D03*
X684077Y421163D03*
X680928Y427462D03*
X684077Y418013D03*
Y427462D03*
X680928Y421163D03*
X684077Y424313D03*
X687227Y427462D03*
X696676D03*
X693526Y421163D03*
Y424313D03*
X690376D03*
X696676Y421163D03*
Y424313D03*
Y418013D03*
X680928Y436911D03*
Y433761D03*
X693526Y430612D03*
X696676Y440061D03*
Y443210D03*
X684077Y430612D03*
Y440061D03*
X687227Y436911D03*
Y443210D03*
X684077D03*
Y436911D03*
X680928Y443210D03*
X690376Y436911D03*
Y443210D03*
X687227Y440061D03*
X693526Y433761D03*
X696676D03*
X684077D03*
X687227Y430612D03*
X690376D03*
X696676D03*
X687227Y433761D03*
X680928Y430612D03*
X687227Y462108D03*
X680928Y455809D03*
X693526Y462108D03*
X680928Y449510D03*
X687227D03*
X690376Y462108D03*
X684077Y449510D03*
X680928Y452659D03*
X684077D03*
X687227Y455809D03*
X684077D03*
X680928Y462108D03*
X696676Y449510D03*
Y452659D03*
X690376Y449510D03*
Y455809D03*
X687227Y452659D03*
X693526Y458959D03*
X696676D03*
Y462108D03*
X687227Y458959D03*
X684077D03*
Y468407D03*
X687227Y471557D03*
Y474707D03*
Y477856D03*
X684077Y471557D03*
X690376Y465258D03*
X684077D03*
X680928Y471557D03*
Y474707D03*
Y477856D03*
X693526Y465258D03*
Y471557D03*
X690376Y468407D03*
Y477856D03*
Y471557D03*
X687227Y465258D03*
X690376Y474707D03*
X687227Y468407D03*
X693526D03*
X684077Y474707D03*
X696676Y465258D03*
Y474707D03*
Y468407D03*
X693526Y474707D03*
X696676Y471557D03*
X693526Y477856D03*
X696441Y957546D03*
Y954200D03*
Y994357D03*
Y1255381D03*
X694100Y1261562D03*
X696441Y1248688D03*
X692233Y1252480D03*
X696046Y1263764D03*
X698598Y115178D03*
X705685D03*
X702141D03*
X698598Y112678D03*
X705685D03*
X702141D03*
X706125Y418013D03*
X712424Y424313D03*
X699825Y427462D03*
X699826Y414864D03*
X699825Y424313D03*
X712424Y430612D03*
X709274Y440061D03*
Y443210D03*
X706125D03*
X699825D03*
X709274Y433761D03*
X712424D03*
X699825D03*
X706125D03*
X699825Y430612D03*
X706125Y462108D03*
X709274D03*
X712424D03*
X709274Y449510D03*
X699825D03*
X706125D03*
X709274Y452659D03*
X699825Y458959D03*
X706125D03*
X709274D03*
X712424D03*
X699825Y462108D03*
X709274Y474707D03*
Y471557D03*
Y465258D03*
Y468407D03*
X712424Y474707D03*
Y468407D03*
Y465258D03*
X706125Y471557D03*
Y468407D03*
X699825Y471557D03*
Y474707D03*
X706125Y477856D03*
X699825Y465258D03*
X712424Y471557D03*
X706125Y481006D03*
X709899Y766798D03*
X709999Y1258727D03*
X708090Y1262074D03*
X705037Y1252034D03*
X706493Y1256563D03*
X705167Y1262074D03*
X709977Y1264985D03*
X721873Y427462D03*
X725022D03*
X728172Y418013D03*
X718723D03*
X715574Y427462D03*
X728172Y421163D03*
X718723Y414864D03*
X725022Y424313D03*
X721873D03*
X725022Y421163D03*
X728172Y427462D03*
X731322Y421163D03*
X725022Y418013D03*
X718723Y427462D03*
Y424313D03*
Y421163D03*
X715574Y424313D03*
Y421163D03*
Y418013D03*
X728172Y424313D03*
X718723Y436911D03*
X721873Y433761D03*
Y436911D03*
Y440061D03*
Y430612D03*
X718723Y433761D03*
Y440061D03*
X725022Y436911D03*
Y433761D03*
X728172D03*
X718723Y430612D03*
X715574D03*
X725022D03*
X728172Y436911D03*
X715574D03*
Y440061D03*
Y443210D03*
X728172D03*
Y430612D03*
X725022Y440061D03*
X718723Y443210D03*
X721873D03*
X725022D03*
X728172Y440061D03*
X731322D03*
X728172Y455809D03*
Y458959D03*
X718723Y455809D03*
X721873Y458959D03*
Y452659D03*
X725022D03*
X728172D03*
X715574Y462108D03*
X725022Y458959D03*
X721873Y455809D03*
X725022Y462108D03*
X718723Y452659D03*
X715574Y449510D03*
Y452659D03*
Y455809D03*
X728172Y462108D03*
X718723Y449510D03*
X721873D03*
X725022D03*
X718723Y458959D03*
X721873Y462108D03*
X718723D03*
X725022Y468407D03*
X721873Y465258D03*
Y477856D03*
X718723Y468407D03*
X715574Y474707D03*
Y471557D03*
Y468407D03*
Y465258D03*
X718723Y474707D03*
Y471557D03*
X728172Y477856D03*
X721873Y471557D03*
X725022D03*
X718723Y465258D03*
X728172D03*
X725022Y474707D03*
X728172Y468407D03*
X721873Y474707D03*
Y468407D03*
X728172Y474707D03*
Y471557D03*
X725022Y465258D03*
X718723Y477856D03*
X725132Y481116D03*
X728272Y481006D03*
X726041Y957546D03*
Y954200D03*
Y994357D03*
X726141Y1057940D03*
Y1255381D03*
X723700Y1258727D03*
X726141Y1248688D03*
Y1262074D03*
X726107Y1265420D03*
X734471Y418013D03*
X731322Y427462D03*
Y418013D03*
X734471Y421163D03*
X731322Y424313D03*
X734471D03*
X737621D03*
X731322Y414864D03*
Y433761D03*
X734471Y436911D03*
X731322D03*
X734471Y443210D03*
X737621D03*
X731322D03*
Y455809D03*
X737621Y458959D03*
X731322D03*
X734471Y452659D03*
X731322D03*
Y449510D03*
X734471Y458959D03*
X731322Y465258D03*
Y477856D03*
X737621Y471557D03*
X734471Y468407D03*
X731322D03*
X731321Y474707D03*
X731322Y471557D03*
X734471Y481006D03*
X739699Y766798D03*
Y1061286D03*
Y1258727D03*
X734967Y1252034D03*
X737580Y1262074D03*
X739697Y1265420D03*
X755841Y957546D03*
Y954200D03*
Y994357D03*
X755541Y1057940D03*
X750890Y1248500D03*
X755890Y1255381D03*
X753000Y1261352D03*
X755841Y1252034D03*
Y1248688D03*
X750040Y1254179D03*
X755841Y1262074D03*
X755797Y1265420D03*
X769399Y766798D03*
Y1258727D03*
X767080Y1262074D03*
X766148Y1255882D03*
X769399Y1265420D03*
X785541Y957546D03*
Y954200D03*
Y994357D03*
Y1255381D03*
X783130Y1259372D03*
X794157Y1252034D03*
X785541Y1248688D03*
X796880Y1262074D03*
X796280Y1254402D03*
X785541Y1265420D03*
Y1262074D03*
X797417Y767345D03*
X799099Y780184D03*
Y773491D03*
Y786877D03*
Y803609D03*
Y796916D03*
Y790223D03*
Y847113D03*
Y853806D03*
Y860499D03*
Y863845D03*
Y883924D03*
Y877231D03*
Y870538D03*
Y890617D03*
Y897310D03*
Y900656D03*
Y914042D03*
Y907349D03*
Y927428D03*
Y920735D03*
Y934121D03*
Y944160D03*
Y937467D03*
Y950853D03*
Y980971D03*
Y974278D03*
Y994357D03*
Y987664D03*
Y1027822D03*
Y1021129D03*
Y1047900D03*
Y1041207D03*
Y1034515D03*
Y1061286D03*
Y1054593D03*
Y1074672D03*
Y1067979D03*
Y1091404D03*
Y1081365D03*
Y1084711D03*
Y1098097D03*
Y1111483D03*
Y1104790D03*
Y1128215D03*
Y1118176D03*
Y1121522D03*
Y1141601D03*
Y1134908D03*
Y1148294D03*
Y1154987D03*
Y1158333D03*
Y1171719D03*
Y1165026D03*
Y1185105D03*
Y1178412D03*
Y1191798D03*
Y1208530D03*
Y1201837D03*
Y1195144D03*
Y1258727D03*
X812440D03*
X799099Y1265420D03*
X815241Y770144D03*
Y776837D03*
Y786877D03*
Y783530D03*
Y800263D03*
Y793570D03*
Y850459D03*
Y843766D03*
Y867192D03*
Y860499D03*
Y857152D03*
Y873885D03*
Y880577D03*
Y887270D03*
Y897310D03*
Y893963D03*
Y917389D03*
Y910696D03*
Y904003D03*
Y924081D03*
Y934121D03*
Y930774D03*
Y947507D03*
Y940814D03*
Y957546D03*
Y954200D03*
Y977625D03*
Y970932D03*
Y991011D03*
Y984318D03*
Y994357D03*
Y1021129D03*
Y1024475D03*
Y1031168D03*
Y1044554D03*
Y1037861D03*
X814941Y1051247D03*
X815241Y1071325D03*
Y1064633D03*
Y1078018D03*
Y1094751D03*
Y1088058D03*
Y1081365D03*
Y1108136D03*
Y1101444D03*
Y1124869D03*
Y1118176D03*
Y1114829D03*
Y1144947D03*
Y1138255D03*
Y1131562D03*
Y1161680D03*
Y1154987D03*
Y1151640D03*
Y1175066D03*
Y1168373D03*
Y1181758D03*
Y1191798D03*
Y1188451D03*
Y1205184D03*
Y1198491D03*
Y1255381D03*
X826750Y1262074D03*
X823877Y1252034D03*
X815241Y1248688D03*
X826501Y1254553D03*
X815241Y1265420D03*
Y1262074D03*
X828699Y766798D03*
X828799Y1054593D03*
Y1258727D03*
X842630Y1256912D03*
X828799Y1265420D03*
X844841Y957546D03*
Y954200D03*
Y994357D03*
X844941Y1021129D03*
Y1024475D03*
Y1051247D03*
Y1258727D03*
Y1252034D03*
X844997Y1248155D03*
X844941Y1265420D03*
Y1262074D03*
X998205Y195735D03*
Y192191D03*
X1000705Y195735D03*
Y192191D03*
X998205Y199278D03*
X1000705D03*
X998205Y202821D03*
X1000705D03*
X1001970Y1251522D03*
X1003831Y1259077D03*
X1002070Y1256942D03*
X1003841Y1265420D03*
Y1262074D03*
X1012769Y766798D03*
X1019983Y994357D03*
X1012541Y1054593D03*
X1017900Y1247632D03*
X1019983Y1255381D03*
Y1252034D03*
Y1248688D03*
Y1262074D03*
Y1265420D03*
X1033441Y766798D03*
X1028683Y957546D03*
Y954200D03*
Y1021129D03*
Y1024475D03*
Y1051247D03*
X1033541Y1258727D03*
X1030830Y1261302D03*
X1030270Y1256042D03*
X1033541Y1265420D03*
X1042241Y780184D03*
Y773491D03*
Y786877D03*
Y803609D03*
Y796916D03*
Y790223D03*
Y847113D03*
Y853806D03*
Y860499D03*
Y863845D03*
Y883924D03*
Y877231D03*
Y870538D03*
Y890617D03*
Y897310D03*
Y900656D03*
Y914042D03*
Y907349D03*
Y927428D03*
Y920735D03*
Y934121D03*
Y944160D03*
Y937467D03*
Y950853D03*
Y980971D03*
Y974278D03*
Y994357D03*
Y987664D03*
Y1027822D03*
Y1021129D03*
Y1047900D03*
Y1041207D03*
Y1034515D03*
Y1061286D03*
Y1054593D03*
Y1074672D03*
Y1067979D03*
Y1091404D03*
Y1081365D03*
Y1084711D03*
Y1098097D03*
Y1111483D03*
Y1104790D03*
Y1128215D03*
Y1118176D03*
Y1121522D03*
Y1141601D03*
Y1134908D03*
Y1148294D03*
Y1154987D03*
Y1158333D03*
Y1171719D03*
Y1165026D03*
Y1185105D03*
Y1178412D03*
Y1191798D03*
Y1208530D03*
Y1201837D03*
Y1195144D03*
X1047010Y1259222D03*
X1049683Y1258727D03*
Y1265420D03*
Y1262074D03*
X1044930Y1263492D03*
X1058383Y770144D03*
X1063141Y766798D03*
X1058383Y776837D03*
Y786877D03*
Y783530D03*
Y800263D03*
Y793570D03*
Y850459D03*
Y843766D03*
Y867192D03*
Y860499D03*
Y857152D03*
Y873885D03*
Y880577D03*
Y887270D03*
Y897310D03*
Y893963D03*
Y917389D03*
Y910696D03*
Y904003D03*
Y924081D03*
Y934121D03*
Y930774D03*
Y947507D03*
Y940814D03*
Y957546D03*
Y954200D03*
Y977625D03*
Y970932D03*
Y991011D03*
Y984318D03*
Y994357D03*
Y1021129D03*
Y1024475D03*
Y1031168D03*
Y1044554D03*
Y1037861D03*
Y1051247D03*
Y1071326D03*
Y1064633D03*
Y1078018D03*
Y1094751D03*
Y1088058D03*
Y1081365D03*
Y1108137D03*
Y1101444D03*
Y1124869D03*
Y1118176D03*
Y1114829D03*
Y1144948D03*
Y1138255D03*
Y1131562D03*
Y1161680D03*
Y1154987D03*
Y1151641D03*
Y1175066D03*
Y1168373D03*
Y1181759D03*
Y1191798D03*
Y1188452D03*
Y1205184D03*
Y1198491D03*
X1063241Y1258727D03*
X1061330Y1262074D03*
X1058383Y1248688D03*
X1059410Y1252272D03*
X1063241Y1265420D03*
X1079383Y994357D03*
X1076520Y1259072D03*
X1079383Y1258727D03*
X1088262Y1252293D03*
X1079383Y1265420D03*
Y1262074D03*
X1092709Y766775D03*
X1088083Y957546D03*
Y954200D03*
X1101641Y1061286D03*
X1090273Y1246800D03*
X1092941Y1258727D03*
X1088083Y1248688D03*
X1091000Y1262074D03*
X1106200Y1250162D03*
X1092941Y1265420D03*
X1103530Y1263602D03*
X1117783Y957546D03*
Y954200D03*
Y994357D03*
Y1057940D03*
X1120800Y1262074D03*
X1117783Y1248688D03*
X1109083Y1265420D03*
X1109050Y1262972D03*
X1106740Y1267902D03*
X1122541Y766798D03*
X1122641Y1258727D03*
X1133200Y1255702D03*
X1122620Y1264622D03*
X1152241Y766798D03*
X1147483Y957546D03*
Y954200D03*
X1138783Y994357D03*
X1152341Y1258727D03*
X1138783Y1255381D03*
Y1258727D03*
Y1252034D03*
X1147483Y1248688D03*
X1150400Y1262074D03*
X1148563Y1257097D03*
X1152341Y1265420D03*
X1138783Y1262027D03*
X1137980Y1264212D03*
X1161041Y1061286D03*
X1168483Y1255381D03*
Y1258727D03*
Y1252034D03*
Y1265420D03*
Y1262074D03*
X1177183Y957546D03*
Y954200D03*
Y994357D03*
X1177120Y1248688D03*
X1177222Y1255567D03*
X1182041Y1265420D03*
X1181850Y1260192D03*
X1179180Y1265872D03*
X1198183Y957546D03*
Y954200D03*
Y994357D03*
Y1252034D03*
X1198180Y1262112D03*
X1196470Y1265382D03*
X1193590Y1267912D03*
X1195470Y1262802D03*
X1211641Y766798D03*
X1213983Y1000437D03*
X1216663Y1000395D03*
X1212533Y1002557D03*
X1205033D03*
X1207533D03*
X1210033D03*
X1208830Y1256692D03*
X1206883Y1248688D03*
X1207048Y1255174D03*
X1211240Y1265502D03*
X1208750Y1266546D03*
X1214132Y1614292D03*
X1202072D03*
X1217532D03*
X1205472D03*
X1214132Y1602380D03*
X1202072D03*
X1217532D03*
X1205472D03*
X1227883Y957546D03*
Y954200D03*
Y994357D03*
X1233703Y999608D03*
X1231023Y999650D03*
X1220441Y1061286D03*
X1224189Y1259155D03*
X1226899Y1257968D03*
X1227847Y1251715D03*
X1227670Y1265162D03*
X1225540Y1266402D03*
X1226192Y1614292D03*
X1229592D03*
X1226192Y1602380D03*
X1229592D03*
X1236583Y1057940D03*
Y1248688D03*
X1238252Y1614292D03*
X1241652D03*
X1238252Y1602380D03*
X1241652D03*
X1262372Y1614292D03*
X1250312D03*
X1265772D03*
X1253712D03*
X1262372Y1602380D03*
X1250312D03*
X1265772D03*
X1253712D03*
X1274432Y1614292D03*
X1277832D03*
X1274432Y1602380D03*
X1277832D03*
X1298552Y1614292D03*
X1286492D03*
X1289892D03*
X1298552Y1602380D03*
X1286492D03*
X1289892D03*
X1310612Y1614292D03*
X1314012D03*
X1301952D03*
X1310612Y1602380D03*
X1314012D03*
X1301952D03*
X1322672Y1614292D03*
X1326072D03*
X1322672Y1602380D03*
X1326072D03*
X1346792Y1614292D03*
X1334732D03*
X1338132D03*
X1346792Y1602380D03*
X1334732D03*
X1338132D03*
X1358852Y1614292D03*
X1362252D03*
X1350192D03*
X1358852Y1602380D03*
X1362252D03*
X1350192D03*
X1370912Y1614292D03*
X1374312D03*
X1370912Y1602380D03*
X1374312D03*
X1382972Y1614292D03*
X1386372D03*
X1382972Y1602380D03*
X1386372D03*
X1477755Y1578182D03*
X1462295D03*
X1474355D03*
X1465695D03*
X1477755Y1590094D03*
X1462295D03*
X1474355D03*
X1465695D03*
X1489815Y1578182D03*
X1486415D03*
X1489815Y1590094D03*
X1486415D03*
X1501875Y1578182D03*
X1498475D03*
X1501875Y1590094D03*
X1498475D03*
X1525995Y1578182D03*
X1513935D03*
X1522595D03*
X1510535D03*
X1525995Y1590094D03*
X1513935D03*
X1522595D03*
X1510535D03*
X1538055Y1578182D03*
X1534655D03*
X1538055Y1590094D03*
X1534655D03*
X1550115Y1578182D03*
X1558775D03*
X1546715D03*
X1550115Y1590094D03*
X1558775D03*
X1546715D03*
X1574235Y1578182D03*
X1562175D03*
X1570835D03*
X1574235Y1590094D03*
X1562175D03*
X1570835D03*
X1586295Y1578182D03*
X1582895D03*
X1586295Y1590094D03*
X1582895D03*
X1605800Y766478D03*
X1601922Y1000198D03*
X1599489Y999665D03*
X1597041Y1061286D03*
X1606481Y1258649D03*
X1608000Y1261662D03*
X1607897Y1264445D03*
X1598355Y1578182D03*
X1607015D03*
X1594955D03*
X1598355Y1590094D03*
X1607015D03*
X1594955D03*
X1613083Y957546D03*
Y954200D03*
X1616609Y1000735D03*
X1616469Y1003135D03*
X1623539Y1000135D03*
X1620489Y1003135D03*
X1623589Y1002865D03*
X1620399Y1000325D03*
X1621983Y1258727D03*
X1624600Y1262074D03*
X1613183Y1252034D03*
X1613027Y1248805D03*
X1609056Y1250602D03*
X1623930Y1252242D03*
X1613019Y1261235D03*
X1622475Y1578182D03*
X1610415D03*
X1619075D03*
X1622475Y1590094D03*
X1610415D03*
X1619075D03*
X1626741Y766798D03*
X1626249Y1002825D03*
X1626741Y1258727D03*
X1634535Y1578182D03*
X1631135D03*
X1634535Y1590094D03*
X1631135D03*
X1656441Y766798D03*
X1642783Y957546D03*
Y954200D03*
X1648205Y998632D03*
X1656441Y1061286D03*
X1642883Y1255381D03*
Y1258727D03*
Y1252034D03*
X1651679Y1248885D03*
X1653140Y1257862D03*
X1656188Y1264964D03*
X1642788Y1264464D03*
X1642883Y1262074D03*
X1656170Y1260352D03*
X1654600Y1262742D03*
X1646595Y1578182D03*
X1643195D03*
X1646595Y1590094D03*
X1643195D03*
X1672583Y957546D03*
Y954200D03*
Y994357D03*
Y1255381D03*
Y1258727D03*
Y1248688D03*
X1672188Y1263764D03*
X1686041Y766798D03*
X1686141Y1258727D03*
X1681179Y1252034D03*
X1683578Y1253780D03*
X1686119Y1264985D03*
X1681309Y1262074D03*
X1683500Y1264312D03*
X1702183Y957546D03*
Y954200D03*
Y994357D03*
X1702283Y1057940D03*
X1699852Y1245418D03*
X1699089Y1258842D03*
X1702283Y1248688D03*
X1702249Y1265420D03*
X1702283Y1262074D03*
X1699030Y1263912D03*
X1715841Y766798D03*
Y1061286D03*
X1713620Y1258512D03*
X1711109Y1252034D03*
X1713930Y1262074D03*
X1715839Y1265420D03*
X1737020Y112177D03*
Y109677D03*
X1731983Y957546D03*
Y954200D03*
Y994357D03*
X1731683Y1057940D03*
X1727041Y1248688D03*
X1731983Y1255381D03*
Y1258727D03*
Y1252034D03*
Y1248688D03*
X1731939Y1265420D03*
X1731983Y1262074D03*
X1747650Y109677D03*
Y112177D03*
X1744106Y109677D03*
Y112177D03*
X1740563Y109677D03*
Y112177D03*
X1745541Y766798D03*
Y1258727D03*
X1743710Y1262074D03*
X1742337Y1252300D03*
X1745541Y1265420D03*
X1761683Y957546D03*
Y954200D03*
Y994357D03*
X1756922Y1247632D03*
X1761683Y1255381D03*
Y1258727D03*
X1770299Y1252034D03*
X1761683Y1248688D03*
Y1262074D03*
Y1265420D03*
X1773559Y767345D03*
X1775241Y780184D03*
Y773491D03*
Y786877D03*
Y803609D03*
Y796916D03*
Y790223D03*
Y847113D03*
Y853806D03*
Y860499D03*
Y863845D03*
Y883924D03*
Y877231D03*
Y870538D03*
Y890617D03*
Y897310D03*
Y900656D03*
Y914042D03*
Y907349D03*
Y927428D03*
Y920735D03*
Y934121D03*
Y944160D03*
Y937467D03*
Y950853D03*
Y980971D03*
Y974278D03*
Y994357D03*
Y987664D03*
Y1027822D03*
Y1021129D03*
Y1047900D03*
Y1041207D03*
Y1034515D03*
Y1061286D03*
Y1054593D03*
Y1074672D03*
Y1067979D03*
Y1091404D03*
Y1081365D03*
Y1084711D03*
Y1098097D03*
Y1111483D03*
Y1104790D03*
Y1128215D03*
Y1118176D03*
Y1121522D03*
Y1141601D03*
Y1134908D03*
Y1148294D03*
Y1154987D03*
Y1158333D03*
Y1171719D03*
Y1165026D03*
Y1185105D03*
Y1178412D03*
Y1191798D03*
Y1208530D03*
Y1201837D03*
Y1195144D03*
Y1258727D03*
X1788219Y1259312D03*
X1773390Y1262074D03*
X1773480Y1253692D03*
X1775241Y1265420D03*
X1788360Y1264522D03*
X1791383Y770144D03*
Y776837D03*
Y786877D03*
Y783530D03*
Y800263D03*
Y793570D03*
Y850459D03*
Y843766D03*
Y867192D03*
Y860499D03*
Y857152D03*
Y873885D03*
Y880577D03*
Y887270D03*
Y897310D03*
Y893963D03*
Y917389D03*
Y910696D03*
Y904003D03*
Y924081D03*
Y934121D03*
Y930774D03*
Y947507D03*
Y940814D03*
Y957546D03*
Y954200D03*
Y977625D03*
Y970932D03*
Y991011D03*
Y984318D03*
Y994357D03*
Y1021129D03*
Y1024475D03*
Y1031168D03*
Y1044554D03*
Y1037861D03*
X1791083Y1051247D03*
X1791383Y1071325D03*
Y1064633D03*
Y1078018D03*
Y1094751D03*
Y1088058D03*
Y1081365D03*
Y1108136D03*
Y1101444D03*
Y1124869D03*
Y1118176D03*
Y1114829D03*
Y1144947D03*
Y1138255D03*
Y1131562D03*
Y1161680D03*
Y1154987D03*
Y1151640D03*
Y1175066D03*
Y1168373D03*
Y1181758D03*
Y1191798D03*
Y1188451D03*
Y1205184D03*
Y1198491D03*
X1788373Y1241769D03*
X1800427Y1248125D03*
X1803100Y1262074D03*
X1800019Y1252034D03*
X1791383Y1248688D03*
Y1265420D03*
Y1262074D03*
X1804841Y766798D03*
X1804941Y1054593D03*
X1815063Y1233103D03*
X1804941Y1258727D03*
X1813814Y1254693D03*
X1804941Y1265420D03*
X1820983Y957546D03*
Y954200D03*
Y994357D03*
X1821083Y1021129D03*
Y1024475D03*
Y1051247D03*
X1830379Y1250358D03*
X1829920Y1258322D03*
X1821139Y1248155D03*
X1821083Y1262074D03*
Y1265420D03*
X1829940Y1263662D03*
G54D29*
X159474Y1328627D03*
X183847Y1328652D03*
X208247D03*
X275289Y583576D03*
Y607735D03*
Y631889D03*
Y656043D03*
X270252Y676260D03*
Y700414D03*
X387897Y1242785D03*
X412297D03*
X436619D03*
X461019D03*
X485419D03*
X673093Y1328652D03*
X697466Y1328677D03*
X721866D03*
X1100800Y259362D03*
X1100700Y283662D03*
X1131100Y1364962D03*
X1155500D03*
X1179900D03*
X1364038Y1242785D03*
X1388438D03*
X1412760D03*
X1437160D03*
X1461560D03*
X1577000Y599762D03*
Y624262D03*
Y648762D03*
Y673162D03*
Y697662D03*
Y722162D03*
X1634259Y1362248D03*
X1658632Y1362273D03*
X1683032D03*
G54D52*
X705760Y-26500D03*
Y-16500D03*
D03*
Y-6500D03*
X730760Y-26500D03*
Y-16500D03*
D03*
Y-6500D03*
X822720Y3500D03*
Y13500D03*
D03*
Y23500D03*
X847720Y3500D03*
Y13500D03*
D03*
Y23500D03*
X973180Y-26500D03*
Y-16500D03*
D03*
Y-6500D03*
Y3500D03*
Y13500D03*
Y23500D03*
Y13500D03*
X998180Y-26500D03*
Y-16500D03*
D03*
Y-6500D03*
Y3500D03*
Y13500D03*
Y23500D03*
Y13500D03*
X1015152Y-26511D03*
Y-36511D03*
Y-26511D03*
Y-16511D03*
D03*
Y-6511D03*
D03*
Y3489D03*
D03*
Y13489D03*
D03*
Y23489D03*
X1040152Y-26511D03*
Y-36511D03*
Y-26511D03*
Y-16511D03*
D03*
Y-6511D03*
D03*
Y3489D03*
D03*
Y13489D03*
D03*
Y23489D03*
X1282572Y-36511D03*
Y-26511D03*
D03*
Y-16511D03*
D03*
Y-6511D03*
Y3489D03*
Y-6511D03*
Y3489D03*
Y13489D03*
Y23489D03*
Y13489D03*
X1307572Y-36511D03*
Y-26511D03*
D03*
Y-16511D03*
D03*
Y-6511D03*
Y3489D03*
Y-6511D03*
Y3489D03*
Y13489D03*
Y23489D03*
Y13489D03*
X1324471Y-26511D03*
Y-36511D03*
Y-26511D03*
Y-16511D03*
D03*
Y-6511D03*
D03*
Y3489D03*
D03*
Y13489D03*
D03*
Y23489D03*
X1349471Y-26511D03*
Y-36511D03*
Y-26511D03*
Y-16511D03*
D03*
Y-6511D03*
D03*
Y3489D03*
D03*
Y13489D03*
D03*
Y23489D03*
X1474931Y-36511D03*
Y-26511D03*
D03*
Y-16511D03*
D03*
Y-6511D03*
Y3489D03*
Y-6511D03*
Y3489D03*
Y13489D03*
Y23489D03*
Y13489D03*
X1499931Y-36511D03*
Y-26511D03*
D03*
Y-16511D03*
D03*
Y-6511D03*
Y3489D03*
Y-6511D03*
Y3489D03*
Y13489D03*
Y23489D03*
Y13489D03*
X1565236Y184783D03*
Y264035D03*
G54D55*
X793879Y194881D03*
X789942Y204724D03*
X793879Y214567D03*
X805690Y188976D03*
Y220472D03*
X817501Y194881D03*
Y214567D03*
X821438Y204724D03*
X841240Y1407480D03*
X832154Y1411244D03*
X828390Y1420330D03*
X832154Y1429416D03*
X841240Y1433180D03*
X850326Y1411244D03*
X854090Y1420330D03*
X850326Y1429416D03*
X1003390Y1420330D03*
X1016240Y1407480D03*
X1007154Y1411244D03*
Y1429416D03*
X1016240Y1433180D03*
X1025326Y1411244D03*
X1029090Y1420330D03*
X1025326Y1429416D03*
X1045847Y194881D03*
X1041910Y204724D03*
X1045847Y214567D03*
X1069469Y194881D03*
X1057658Y188976D03*
X1069469Y214567D03*
X1057658Y220472D03*
X1073406Y204724D03*
G54D11*
X3010Y63308D03*
Y123308D03*
Y163308D03*
Y183308D03*
Y203308D03*
Y223308D03*
Y243308D03*
Y263308D03*
Y283308D03*
Y303308D03*
X10884Y321693D03*
Y341693D03*
Y361693D03*
Y381693D03*
Y401693D03*
Y421693D03*
Y441693D03*
Y461693D03*
Y481693D03*
Y501693D03*
Y521693D03*
Y661693D03*
Y681693D03*
Y701693D03*
Y721693D03*
Y741693D03*
Y781693D03*
Y801693D03*
Y821693D03*
Y841693D03*
Y861693D03*
Y881693D03*
Y901693D03*
Y921693D03*
Y941693D03*
Y961693D03*
Y981693D03*
Y1001693D03*
Y1021693D03*
Y1041693D03*
Y1061693D03*
Y1081693D03*
Y1101693D03*
Y1121693D03*
Y1141693D03*
Y1161693D03*
Y1181693D03*
Y1201693D03*
Y1221693D03*
Y1241693D03*
Y1401693D03*
Y1421693D03*
Y1441693D03*
Y1461693D03*
Y1481693D03*
Y1501693D03*
Y1521693D03*
Y1541693D03*
Y1561693D03*
Y1581693D03*
X26615Y670036D03*
X28601Y1617541D03*
Y1637541D03*
Y1657541D03*
Y1677541D03*
X38220Y595862D03*
X54593Y19183D03*
X87565Y670441D03*
X94473Y698926D03*
X127313Y649765D03*
X114021Y669409D03*
X118021D03*
X127738Y659226D03*
X117220Y1680287D03*
X130067Y650213D03*
X134205Y643603D03*
X128193Y662015D03*
X128275Y665515D03*
X190800Y675662D03*
X219752Y1405499D03*
Y1401999D03*
Y1398599D03*
X259845Y461117D03*
X282640Y214102D03*
X301751Y127466D03*
Y124466D03*
Y121466D03*
X311758Y124469D03*
Y121469D03*
Y127469D03*
X313995Y237724D03*
X335285Y210609D03*
X332285D03*
X325755Y230719D03*
X338985Y229509D03*
X325855Y227619D03*
X325055Y237219D03*
X328965Y237214D03*
X332465D03*
X381068Y1674824D03*
X373320Y1688202D03*
X388220Y1631404D03*
X445944Y359053D03*
X446730Y382432D03*
X443744Y429553D03*
X451421D03*
X443744Y452462D03*
X437520Y484837D03*
X447520D03*
X442520D03*
X451520D03*
X448079Y1562177D03*
X443910Y1555602D03*
X450020Y1570412D03*
X453621Y359053D03*
X462720Y404762D03*
X465421Y424928D03*
X466520Y475812D03*
X456520Y484837D03*
X461520D03*
X456961Y1559697D03*
X456020Y1580412D03*
X464020D03*
X462079Y1572177D03*
X454661Y1596755D03*
X459779Y1609235D03*
X480393Y429412D03*
X479169Y484696D03*
X474169D03*
X484169D03*
X478308Y1439986D03*
X502070Y424787D03*
X488070Y429412D03*
X498169Y484696D03*
X493169D03*
X488169D03*
X513444Y473281D03*
X503169Y475671D03*
X550024Y369123D03*
Y401023D03*
X557701Y369123D03*
X649218Y504277D03*
X641386Y1687283D03*
X661534Y41748D03*
X656877Y514716D03*
X661743Y521166D03*
X657734Y528255D03*
X656725Y1657619D03*
X669004Y41698D03*
X694720Y491962D03*
X690720D03*
X702462Y1673258D03*
X725537Y-23978D03*
Y-19022D03*
Y-13978D03*
Y-9022D03*
X719194Y172909D03*
X714202D03*
X719194Y177865D03*
X714202D03*
X719194Y184909D03*
X714202D03*
X719194Y189865D03*
X714202D03*
X719194Y196409D03*
X714202D03*
X719194Y201365D03*
X714202D03*
X719194Y208243D03*
X714202D03*
X719194Y213199D03*
X714202D03*
X714203Y1639776D03*
X745685Y265322D03*
Y269322D03*
X730282Y1580391D03*
X741382Y1585251D03*
Y1580121D03*
X735882Y1580391D03*
X730282Y1590651D03*
Y1585521D03*
X735882Y1590651D03*
X732504Y1600321D03*
Y1597321D03*
X744504D03*
Y1600321D03*
X741504Y1597321D03*
Y1600321D03*
X735504Y1597321D03*
Y1600321D03*
X738504Y1597321D03*
Y1600321D03*
X744504Y1609521D03*
Y1612521D03*
X741504Y1609521D03*
X738504D03*
X735504D03*
X741504Y1612521D03*
X738504D03*
X735504D03*
X732504Y1603321D03*
Y1606321D03*
X744504Y1603321D03*
Y1606321D03*
X741504Y1603321D03*
Y1606321D03*
X738504Y1603321D03*
X735504D03*
X738504Y1606321D03*
X735504D03*
X742655Y1682362D03*
Y1678362D03*
X761720Y283262D03*
X748085Y278942D03*
X758360Y276122D03*
X747504Y1600321D03*
Y1609521D03*
Y1612521D03*
X750504D03*
Y1609521D03*
X747504Y1603321D03*
Y1606321D03*
X755859Y1686090D03*
X755183Y1709850D03*
X764850Y249792D03*
X776052Y1611893D03*
X763359Y1729520D03*
X785135Y281822D03*
Y267822D03*
X788079Y1580393D03*
X782479D03*
X793579D03*
X788079Y1590653D03*
X782479D03*
Y1585523D03*
X793579Y1590653D03*
Y1585523D03*
X785052Y1600693D03*
Y1597693D03*
X782052D03*
Y1600693D03*
X794052D03*
X788052D03*
X791052D03*
X794052Y1597693D03*
X788052D03*
X791052D03*
X785052Y1607793D03*
X782052D03*
X779052D03*
X785052Y1611893D03*
X782052D03*
X779052D03*
X794052Y1607793D03*
X791052D03*
X788052D03*
X797052Y1611893D03*
X794052D03*
X788052D03*
X791052D03*
X785052Y1603693D03*
X782052D03*
X794052D03*
X788052D03*
X791052D03*
X797052Y1607793D03*
X824479Y1580393D03*
Y1590653D03*
Y1585523D03*
X824052Y1597693D03*
Y1600693D03*
X827052D03*
Y1597693D03*
X824052Y1611893D03*
Y1607793D03*
Y1603693D03*
X827052Y1611893D03*
Y1607793D03*
Y1603693D03*
X821052Y1611893D03*
Y1607793D03*
X818052Y1611893D03*
X842497Y6022D03*
Y16022D03*
Y20978D03*
Y10978D03*
X830079Y1580393D03*
X835579D03*
X833052Y1597693D03*
X836052D03*
X830079Y1590653D03*
X835579D03*
X833052Y1600693D03*
X836052D03*
X835579Y1585523D03*
X830052Y1600693D03*
Y1597693D03*
X833052Y1603693D03*
X836052D03*
X839052Y1611893D03*
X833052Y1607793D03*
Y1611893D03*
X836052Y1607793D03*
Y1611893D03*
X830052D03*
Y1607793D03*
Y1603693D03*
X839052Y1607793D03*
X866479Y1580393D03*
X872079D03*
X866052Y1597693D03*
X869052D03*
X866479Y1590653D03*
X869052Y1600693D03*
X866052D03*
X872052Y1597693D03*
X872079Y1590653D03*
X872052Y1600693D03*
X866479Y1585523D03*
X875052Y1597693D03*
Y1600693D03*
X869052Y1603693D03*
X866052D03*
X872052D03*
X869052Y1607793D03*
Y1611893D03*
X866052Y1607793D03*
X863052Y1611893D03*
X866052D03*
X872052Y1607793D03*
Y1611893D03*
X875052Y1603693D03*
Y1607793D03*
Y1611893D03*
X863052Y1607793D03*
X860052Y1611893D03*
X877579Y1580393D03*
Y1585523D03*
X878052Y1597693D03*
Y1600693D03*
X877579Y1590653D03*
X878052Y1603693D03*
Y1607793D03*
X881052Y1611893D03*
X878052D03*
X881052Y1607793D03*
X908675Y455386D03*
X908479Y1580393D03*
Y1590653D03*
Y1585523D03*
X908052Y1600693D03*
Y1597693D03*
Y1611893D03*
X905052D03*
X902052D03*
X908052Y1607793D03*
X905052D03*
X908052Y1603693D03*
X913913Y455396D03*
X919579Y1580393D03*
X914079D03*
X919579Y1590653D03*
X914079D03*
X919579Y1585523D03*
X917052Y1600693D03*
Y1597693D03*
X914052Y1600693D03*
Y1597693D03*
X911052Y1600693D03*
Y1597693D03*
X920052Y1600693D03*
Y1597693D03*
X917052Y1611893D03*
X914052D03*
X911052D03*
X917052Y1607793D03*
X914052D03*
X911052D03*
X920052Y1611893D03*
X923052D03*
Y1607793D03*
X920052D03*
X917052Y1603693D03*
X914052D03*
X911052D03*
X920052D03*
X957420Y153699D03*
X960420D03*
X968022Y1620730D03*
X965022D03*
X971022D03*
X965022Y1632730D03*
X968022Y1629730D03*
X965022D03*
X968022Y1626730D03*
X965022D03*
Y1623730D03*
X968022D03*
X971022Y1626730D03*
Y1623730D03*
Y1629730D03*
Y1632730D03*
X968022D03*
X981445Y181058D03*
X1002735Y153943D03*
X999735D03*
X999915Y180548D03*
X996415D03*
X992505Y180553D03*
X993205Y174053D03*
X993305Y170953D03*
X990495Y212923D03*
X1001065Y304622D03*
Y307122D03*
Y309622D03*
X996662Y1620870D03*
X999662D03*
X1002662D03*
Y1626870D03*
Y1623870D03*
X996662Y1629870D03*
X999662Y1626870D03*
X996662D03*
Y1623870D03*
X999662D03*
X996662Y1632870D03*
X1021908Y60392D03*
Y120392D03*
X1015300Y148736D03*
X1012187Y148749D03*
X1006435Y172843D03*
X1009895Y192359D03*
X1008067Y194356D03*
X1019935Y206463D03*
Y203333D03*
X1010828Y304822D03*
Y307322D03*
Y309822D03*
X1034929Y-33989D03*
Y-29033D03*
Y-13989D03*
Y-9033D03*
Y-23989D03*
Y-19033D03*
Y-3989D03*
Y967D03*
X1036915Y290969D03*
X1035920Y428962D03*
X1034252Y1623870D03*
Y1626870D03*
X1031252Y1623870D03*
Y1626870D03*
X1028252Y1623870D03*
Y1626870D03*
X1031252Y1620870D03*
X1034252D03*
X1028252D03*
X1065721Y1633043D03*
X1068721D03*
Y1624043D03*
Y1627043D03*
Y1630043D03*
X1065721Y1624043D03*
Y1627043D03*
Y1630043D03*
X1062721Y1633043D03*
Y1624043D03*
Y1627043D03*
Y1630043D03*
X1059721Y1633043D03*
Y1624043D03*
Y1627043D03*
Y1630043D03*
X1068721Y1621043D03*
X1065721D03*
X1062721D03*
X1059721D03*
X1099901Y1633203D03*
Y1624203D03*
Y1627203D03*
Y1630203D03*
Y1621203D03*
X1093901Y1633203D03*
X1096901D03*
Y1624203D03*
Y1627203D03*
Y1630203D03*
X1093901Y1624203D03*
Y1627203D03*
Y1630203D03*
X1090901Y1633203D03*
X1087901D03*
X1090901Y1624203D03*
X1087901D03*
Y1627203D03*
X1090901D03*
X1087901Y1630203D03*
X1090901D03*
X1096901Y1621203D03*
X1093901D03*
X1087901D03*
X1090901D03*
X1132142Y1555301D03*
X1120472Y1615010D03*
X1127377Y1628485D03*
X1131632Y1625969D03*
X1148220Y501362D03*
X1139392Y1620851D03*
X1172720Y527862D03*
X1202600Y759662D03*
X1245574Y234042D03*
X1245593Y241462D03*
Y237462D03*
X1280223Y256841D03*
X1279841Y253052D03*
X1344248Y-33989D03*
Y-29033D03*
Y-13989D03*
Y-9033D03*
Y-23989D03*
Y-19033D03*
Y-3989D03*
Y967D03*
X1412954Y138742D03*
X1404402D03*
X1409716Y171696D03*
X1418268D03*
X1454829Y1439732D03*
X1465179Y213102D03*
X1477700Y236522D03*
X1466292Y631634D03*
X1473228D03*
X1486884Y374338D03*
X1479207D03*
X1478203Y406207D03*
X1493384Y419263D03*
X1481384Y419392D03*
X1505378Y225502D03*
X1509571Y239053D03*
X1507860Y249792D03*
X1513110Y247412D03*
X1522883Y305187D03*
X1526216Y306909D03*
X1529002Y32290D03*
X1528716Y306909D03*
X1533716D03*
X1536216D03*
X1534899Y310447D03*
X1559387Y589340D03*
X1564690Y663302D03*
X1619980Y590685D03*
X1615800Y584062D03*
X1620170Y623762D03*
X1622770D03*
X1612980D03*
X1620170Y626362D03*
X1622770D03*
X1612980D03*
X1615580Y650092D03*
Y657762D03*
X1620170D03*
X1622770D03*
X1622109Y652469D03*
X1619509D03*
X1612980Y657762D03*
Y650092D03*
X1615580Y660362D03*
X1620170D03*
X1622770D03*
X1612980D03*
X1622109Y686469D03*
X1619509D03*
X1615580Y684092D03*
X1612980D03*
X1622770Y691762D03*
Y694362D03*
X1620170Y691762D03*
Y694362D03*
X1615580D03*
X1612980D03*
X1615580Y691762D03*
X1612980D03*
X1619509Y720469D03*
X1622109D03*
X1612980Y718092D03*
X1615580D03*
X1610100Y725152D03*
X1637667Y587844D03*
Y590444D03*
X1629867D03*
Y587844D03*
X1632467Y590444D03*
Y587844D03*
X1635067Y590444D03*
Y587844D03*
X1626606Y616576D03*
X1629206D03*
X1631806D03*
X1634406D03*
X1637006D03*
X1639606D03*
X1630570Y623762D03*
X1627970D03*
X1625370D03*
X1636412Y638451D03*
X1636417Y630007D03*
X1640061Y639497D03*
X1636412Y641051D03*
X1630570Y626362D03*
X1627970D03*
X1625370D03*
X1630198Y638651D03*
Y636051D03*
Y641251D03*
X1633305Y638651D03*
Y641251D03*
X1630198Y632851D03*
X1630214Y629907D03*
X1633321D03*
X1640061Y644457D03*
Y641977D03*
X1630570Y657762D03*
X1627970D03*
X1625370D03*
X1629909Y652469D03*
X1632509D03*
X1624709D03*
X1627309D03*
X1630198Y643851D03*
X1633305Y646451D03*
Y643851D03*
X1630198Y646451D03*
X1636412Y672451D03*
X1636417Y664007D03*
X1640061Y673497D03*
X1630570Y660362D03*
X1627970D03*
X1625370D03*
X1630198Y672651D03*
Y670051D03*
X1633305Y672651D03*
X1630198Y666851D03*
X1630214Y663907D03*
X1633321D03*
X1629909Y686469D03*
X1632509D03*
X1624709D03*
X1627309D03*
X1640061Y678457D03*
Y675977D03*
X1636412Y675051D03*
X1630198Y677851D03*
Y675251D03*
X1633305Y680451D03*
Y675251D03*
Y677851D03*
X1630198Y680451D03*
X1636417Y698007D03*
X1636412Y706451D03*
X1630214Y697907D03*
X1633321D03*
X1630198Y704051D03*
Y706651D03*
X1633305D03*
X1630198Y700851D03*
X1625370Y691762D03*
Y694362D03*
X1630570D03*
Y691762D03*
X1627970D03*
Y694362D03*
X1640061Y707497D03*
Y712457D03*
Y709977D03*
X1636412Y709051D03*
X1632509Y720469D03*
X1627309D03*
X1629909D03*
X1624709D03*
X1633305Y711851D03*
Y709251D03*
X1630198D03*
Y711851D03*
X1633305Y714451D03*
X1630198D03*
X1642873Y604206D03*
Y607206D03*
X1645625Y600495D03*
Y603295D03*
X1642873Y601206D03*
Y598206D03*
X1645625Y597795D03*
Y594995D03*
X1642873Y595006D03*
X1642340Y618546D03*
X1642873Y610206D03*
X1645661Y639497D03*
X1656550Y653086D03*
X1645661Y644457D03*
Y641977D03*
Y673497D03*
X1656550Y687086D03*
X1645661Y678457D03*
Y675977D03*
Y707497D03*
Y709977D03*
Y712457D03*
X1665700Y583462D03*
X1661510Y583442D03*
X1672770Y580512D03*
X1669770D03*
X1663720Y620434D03*
X1659914Y649681D03*
Y683681D03*
Y717681D03*
X1686154Y434160D03*
X1704444Y407045D03*
X1697914Y427155D03*
X1698014Y424055D03*
X1701124Y433650D03*
X1697214Y433655D03*
X1704624Y433650D03*
X1717280Y174970D03*
X1707444Y407045D03*
X1711144Y425945D03*
X1765870Y179392D03*
X1780320Y177602D03*
G54D14*
X26054Y195148D03*
X25752Y203274D03*
X24754Y220220D03*
X24814Y236472D03*
X35600Y227380D03*
X45182Y426310D03*
X45034Y449106D03*
X62833Y410047D03*
X62808Y418425D03*
X50138Y426310D03*
X60393D03*
X49990Y449106D03*
X73020Y28406D03*
Y40020D03*
X65349Y426310D03*
X75516Y436519D03*
X73865Y763164D03*
X94279Y28406D03*
X87193D03*
X80106D03*
X94279Y40020D03*
X87193D03*
X80106D03*
X85826Y424319D03*
Y420319D03*
X82661Y449604D03*
X79451Y699517D03*
X92895Y1737108D03*
X108453Y28406D03*
X101366D03*
X108453Y40020D03*
X101366D03*
X104220Y400862D03*
X101720D03*
X113597Y488434D03*
X102152Y509374D03*
X102334Y500628D03*
X102359Y497374D03*
X102152Y513374D03*
X108909Y654926D03*
X102909Y648926D03*
Y642926D03*
Y655102D03*
X108909Y642926D03*
X122626Y28406D03*
X115539D03*
X122626Y40020D03*
X115539D03*
X125007Y392071D03*
Y388071D03*
Y384071D03*
Y396071D03*
X114507Y404571D03*
X117597Y488434D03*
X114909Y654926D03*
Y648926D03*
Y642926D03*
X116798Y1617262D03*
X112895Y1737108D03*
X129713Y28406D03*
Y40020D03*
X136301Y179095D03*
X143340Y204622D03*
X140974Y396885D03*
Y401885D03*
Y399385D03*
X142166Y490835D03*
X144263Y1412275D03*
X138492Y1717592D03*
X132895Y1737108D03*
X158492Y28406D03*
X151405D03*
X158492Y40020D03*
X151405D03*
X147901Y188852D03*
X159125Y448664D03*
X152171Y490615D03*
X149472Y502810D03*
X149486Y498810D03*
X149518Y522810D03*
X159898Y1360790D03*
X152895Y1737108D03*
X172665Y28406D03*
X165579D03*
X172665Y40020D03*
X165579D03*
X175640Y453779D03*
X162398Y1360790D03*
X164898D03*
X172895Y1737108D03*
X166761Y1732967D03*
X179752Y28406D03*
Y40020D03*
X184490Y402203D03*
X191305Y430216D03*
X188221Y454048D03*
X184147Y447078D03*
X192895Y1737108D03*
X202626Y28406D03*
X195539D03*
X202626Y40020D03*
X195539D03*
X199047Y428626D03*
X199139Y422882D03*
X196215Y447565D03*
X194858Y684348D03*
X203441Y1360790D03*
X198041D03*
X200941D03*
X223886Y28406D03*
X216799D03*
X209713D03*
X223886Y40020D03*
X216799D03*
X209713D03*
X223330Y426467D03*
X220843Y430004D03*
X220874Y442079D03*
X224137Y1414345D03*
X224077Y1416975D03*
X224350Y1432032D03*
X212895Y1737108D03*
X230972Y28406D03*
Y40020D03*
X242215Y151788D03*
X253000Y28362D03*
X256500D03*
X249500D03*
X252195Y144320D03*
X257434Y415896D03*
X252895Y1737108D03*
X260000Y28362D03*
X258746Y407842D03*
X260807Y424403D03*
X270322Y740207D03*
X272895Y1737108D03*
X286071Y28406D03*
X278984D03*
X279277Y99183D03*
X289557Y121803D03*
X280687Y140746D03*
X284482Y569548D03*
X286582Y630757D03*
X305025Y144202D03*
X302891Y141811D03*
X292895Y1737108D03*
X324733Y148598D03*
X321119Y1313108D03*
X317119D03*
X313119D03*
X330417Y380482D03*
X336370Y406302D03*
X325119Y1313108D03*
X328915Y1326704D03*
X331515D03*
X332895Y1737108D03*
X344776Y148462D03*
X343411Y363143D03*
Y375364D03*
X343354Y387988D03*
X343720Y400628D03*
X339769Y1299868D03*
X342769D03*
X352895Y1737108D03*
X366675Y158702D03*
X364179Y394596D03*
X371066Y400628D03*
X369690Y431812D03*
X365970Y444662D03*
X361769Y1300008D03*
X364769D03*
X383140Y119822D03*
X375330Y121182D03*
X374981Y131433D03*
X376770Y387272D03*
X385520Y429262D03*
X373190Y438342D03*
X384510Y438662D03*
X385730Y460922D03*
X382860Y471122D03*
X383239Y1286578D03*
X378069Y1286568D03*
X375069D03*
X386239Y1286578D03*
X372895Y1737108D03*
X403700Y402422D03*
X390892Y406863D03*
X403260Y439352D03*
X391150Y445302D03*
X396570Y472602D03*
X391360Y495712D03*
X402780Y499372D03*
X394860Y518812D03*
X403200Y572622D03*
X396139Y1286708D03*
X399139D03*
X400926Y1402207D03*
X391249Y1401048D03*
X396921Y1549810D03*
X396946Y1560810D03*
X419012Y368762D03*
X418602Y394722D03*
X417010Y439352D03*
X415130Y480202D03*
X410532Y1153341D03*
X407948Y1153370D03*
Y1161570D03*
X410532Y1161541D03*
X407948Y1169597D03*
X410532D03*
X429050Y117491D03*
X430980Y132672D03*
X432006Y363644D03*
X431596Y389604D03*
X424980Y439462D03*
X427790Y500862D03*
X427880Y506442D03*
X428510Y515842D03*
X436822Y1161570D03*
Y1153370D03*
X431722D03*
Y1161570D03*
X434272Y1153370D03*
Y1161570D03*
X436822Y1170070D03*
X431722D03*
X434272D03*
X430999Y1286758D03*
X423229D03*
X426229D03*
X433999D03*
X436920Y1541562D03*
X422566Y1550046D03*
X432996Y1558322D03*
X436840Y1632682D03*
X436880Y1622442D03*
X432895Y1737108D03*
X447100Y1622562D03*
X447020Y1632632D03*
X452895Y1737108D03*
X465236Y293823D03*
X467736Y312938D03*
X455326Y520389D03*
X457196Y1161570D03*
X459696D03*
X462196D03*
X459696Y1153370D03*
X457196D03*
X462196D03*
X459696Y1170070D03*
X462196D03*
X457196D03*
X460049Y1286978D03*
X463049D03*
X469019Y1286718D03*
X465749Y1401238D03*
X455602Y1412334D03*
X473870Y506622D03*
X474220Y572782D03*
X471940Y597532D03*
X483030Y1153370D03*
Y1161570D03*
Y1170070D03*
X474509Y1286848D03*
X481509D03*
X477509D03*
X484509D03*
X475285Y1395402D03*
X477835Y1673462D03*
Y1685462D03*
X472895Y1737108D03*
X498636Y293123D03*
X501136Y312238D03*
X486861Y309398D03*
X490759Y1291978D03*
X495309Y1300058D03*
X498309D03*
X492895Y1737108D03*
X517914Y42257D03*
X517902Y49194D03*
X510815D03*
X517989Y1300108D03*
X514989D03*
X508881Y1404880D03*
X506181D03*
X503559Y1405025D03*
X508775Y1409889D03*
X508828Y1407385D03*
X508802Y1412420D03*
X506075Y1409889D03*
X506128Y1407385D03*
X503572Y1407539D03*
Y1415039D03*
Y1412539D03*
X506102Y1412420D03*
X503572Y1410039D03*
X512895Y1737108D03*
X525000Y42257D03*
X524988Y49194D03*
X532533Y299500D03*
X529533D03*
X526941Y447802D03*
X521561Y550819D03*
X526280Y569122D03*
X520710Y592552D03*
X532895Y1737108D03*
X549610Y120682D03*
X535290Y572932D03*
X543450Y590262D03*
X562780Y32842D03*
X564430Y45132D03*
X565849Y1346968D03*
X552895Y1737108D03*
X578620Y45112D03*
X573849Y1346968D03*
X569849D03*
X572895Y1737108D03*
X596840Y45152D03*
X593925Y49193D03*
X590350Y294402D03*
X607890Y34389D03*
X615420Y42342D03*
X605060Y42402D03*
X615185Y49193D03*
X611310Y266272D03*
X612895Y1737108D03*
X621740Y265952D03*
X632895Y1737108D03*
X661681Y49193D03*
X654595D03*
X652895Y1737108D03*
X675854Y49193D03*
X668768D03*
X673517Y1360815D03*
X676017D03*
X678517D03*
X671112Y1639962D03*
X672895Y1737108D03*
X697122Y1632667D03*
X683592Y1634844D03*
X697197Y1644667D03*
X712433Y103308D03*
X712060Y1360815D03*
X722580Y49182D03*
X724133Y141288D03*
X713820Y488762D03*
Y484662D03*
X714560Y1360815D03*
X717060D03*
X744800Y1664840D03*
X732895Y1737108D03*
X762198Y129684D03*
Y126684D03*
X758110Y172636D03*
X752895Y1737108D03*
X777283Y320892D03*
X772208Y1731911D03*
X792208D03*
X810781Y372615D03*
X821164Y372312D03*
X812208Y1731911D03*
X836502Y161553D03*
X837975Y210064D03*
X832208Y1731911D03*
X856776Y129268D03*
X846846Y127064D03*
X851895Y160262D03*
X849710Y212062D03*
X845220Y216532D03*
X854706Y229878D03*
X852206D03*
X856842Y410760D03*
X852208Y1731911D03*
X874295Y163862D03*
X863488Y176332D03*
X872208Y1731911D03*
X886280Y174085D03*
X887671Y487831D03*
Y494767D03*
X878931Y509051D03*
X878941Y503813D03*
X892208Y1731911D03*
X899625Y473856D03*
X893321Y480293D03*
X893311Y485531D03*
X893572Y503050D03*
Y496114D03*
X920246Y184138D03*
X914550Y239924D03*
X923403Y983327D03*
X923322Y990227D03*
X921880Y1525110D03*
X924380D03*
X921880Y1527610D03*
X924380D03*
X912208Y1731911D03*
X935496Y195925D03*
Y203012D03*
Y210098D03*
Y217185D03*
Y224272D03*
Y231358D03*
X940596Y498648D03*
X939097Y527257D03*
X939282Y534020D03*
X930233Y983298D03*
X930274Y990237D03*
X939380Y1525110D03*
X926880D03*
X929380D03*
X931880D03*
X934380D03*
X936880D03*
X926880Y1527610D03*
X929380D03*
X931880D03*
X934380D03*
X936880D03*
X939380D03*
X932208Y1731911D03*
X947190Y527330D03*
X952208Y1731911D03*
X972208D03*
X989910Y-27961D03*
X989925Y-25446D03*
X983632Y-26655D03*
X989925Y-21572D03*
X983632Y-16626D03*
X989910Y-17932D03*
X989925Y-15417D03*
Y-11543D03*
X989910Y-7903D03*
X989925Y-5388D03*
X983632Y-6597D03*
X989925Y4641D03*
X989910Y2126D03*
X983632Y3432D03*
X989925Y14670D03*
X989910Y12155D03*
X989925Y8515D03*
X983632Y13461D03*
X989925Y19044D03*
X983632Y23990D03*
X987259Y276094D03*
X998500Y269862D03*
X1002500D03*
X992208Y1731911D03*
X1014500Y269862D03*
X1018000D03*
X1006500D03*
X1010500D03*
X1021419Y305704D03*
X1012208Y1731911D03*
X1032208D03*
X1053028Y246518D03*
X1053428Y261118D03*
X1052208Y1731911D03*
X1058028Y246518D03*
X1055528D03*
X1068093Y265503D03*
X1058428Y261118D03*
X1055928D03*
X1067618Y273800D03*
X1070718Y273700D03*
X1067718Y285600D03*
X1070618D03*
X1072208Y1731911D03*
X1102561Y78461D03*
X1117574Y1448604D03*
X1111866Y1737108D03*
X1135709Y1397119D03*
X1133209D03*
X1127008Y1524203D03*
X1135748Y1524187D03*
X1131866Y1737108D03*
X1138209Y1397119D03*
X1170337Y607327D03*
X1171752Y1397119D03*
X1176752D03*
X1174252D03*
X1179922Y1524203D03*
X1201110Y1681767D03*
X1191866Y1737108D03*
X1211866D03*
X1231866D03*
X1253586Y1334649D03*
X1257586D03*
X1251866Y1737108D03*
X1276745Y125850D03*
X1275807Y132922D03*
X1281600Y137962D03*
X1282568Y212722D03*
X1272707Y1334865D03*
X1271866Y1737108D03*
X1293024Y-36695D03*
Y-26666D03*
Y-16637D03*
Y-6608D03*
Y3421D03*
Y13450D03*
Y23979D03*
X1291280Y58262D03*
X1293860Y58312D03*
X1284930Y124922D03*
X1285793Y141562D03*
X1288258Y145501D03*
X1283781Y149115D03*
Y155788D03*
X1283425Y179272D03*
X1283397Y202085D03*
X1295150Y1323217D03*
X1298150D03*
X1291010Y1323307D03*
X1288010D03*
X1291866Y1737108D03*
X1299317Y-35486D03*
Y-31612D03*
X1299302Y-38001D03*
Y-27972D03*
X1299317Y-25457D03*
Y-21583D03*
X1299302Y-17943D03*
X1299317Y-15428D03*
Y-11554D03*
X1299302Y-7914D03*
X1299317Y-5399D03*
Y4630D03*
X1299302Y2115D03*
X1299317Y-1525D03*
Y14659D03*
X1299302Y12144D03*
X1299317Y8504D03*
Y19033D03*
X1304066Y1323578D03*
X1307656Y1326704D03*
X1305056D03*
X1311866Y1737108D03*
X1323958Y146227D03*
X1333811Y235348D03*
X1338652Y536654D03*
Y543590D03*
X1337663Y1301001D03*
X1340663D03*
X1331866Y1737108D03*
X1349704Y145385D03*
X1357888Y145893D03*
X1361111Y236448D03*
X1353982Y1287048D03*
X1362382D03*
X1359382D03*
X1350982D03*
X1351866Y1737108D03*
X1366868Y147341D03*
X1369593Y147462D03*
X1369916Y154132D03*
X1379969Y176330D03*
X1370586Y176366D03*
X1370405Y186938D03*
X1369479Y208384D03*
X1370636Y227292D03*
X1369410Y224504D03*
X1375463Y1287048D03*
X1372463D03*
X1376666Y1402778D03*
X1376686Y1399758D03*
X1371866Y1737108D03*
X1384173Y1161549D03*
X1384089Y1153369D03*
X1386673Y1161520D03*
Y1153340D03*
X1384173Y1169599D03*
X1386673Y1169570D03*
X1391866Y1737108D03*
X1407613Y177159D03*
X1398770D03*
X1402258Y184263D03*
X1411101D03*
X1407913Y1161569D03*
X1410413Y1153369D03*
X1407913D03*
X1410613Y1161569D03*
X1407913Y1170069D03*
X1410613D03*
X1410819Y1287198D03*
X1407819D03*
X1399419D03*
X1402419D03*
X1411866Y1737108D03*
X1420222Y184263D03*
X1429250Y1623391D03*
X1419270Y1631000D03*
X1429382Y184263D03*
X1430000Y220018D03*
X1435387Y1161569D03*
X1435837Y1153369D03*
X1432887Y1161569D03*
X1433337Y1153369D03*
X1435387Y1170069D03*
X1432887D03*
X1437258Y1287198D03*
X1445106Y1287158D03*
X1440258Y1287198D03*
X1431829Y1412370D03*
X1443325Y1410068D03*
X1431717Y1424125D03*
X1441800Y1620300D03*
Y1632900D03*
X1431866Y1737108D03*
X1458911Y1161569D03*
Y1170069D03*
X1453366Y1287198D03*
X1458766D03*
X1461766D03*
X1450366D03*
X1474180Y1300407D03*
X1471180D03*
X1491661Y-27972D03*
X1491676Y-25457D03*
X1485383Y-26666D03*
X1491661Y-38001D03*
X1491676Y-35486D03*
Y-31612D03*
X1485383Y-36695D03*
X1491661Y-17943D03*
X1491676Y-15428D03*
Y-11554D03*
X1485383Y-16637D03*
X1491676Y-21583D03*
X1485383Y3421D03*
X1491661Y2115D03*
X1491676Y4630D03*
X1491661Y-7914D03*
X1491676Y-5399D03*
Y-1525D03*
X1485383Y-6608D03*
X1491676Y14659D03*
X1491661Y12144D03*
X1485383Y13450D03*
X1491676Y8504D03*
Y19033D03*
X1485383Y23979D03*
X1487058Y281456D03*
X1484958Y289656D03*
X1487658D03*
X1484758Y312356D03*
X1487458D03*
X1484858Y305956D03*
X1487558D03*
X1491840Y1300447D03*
X1479658Y1405397D03*
X1485301Y1409442D03*
X1485274Y1406911D03*
X1485380Y1412202D03*
X1479671Y1410411D03*
Y1412911D03*
Y1407911D03*
X1482201Y1409442D03*
X1482174Y1406911D03*
X1482280Y1412202D03*
X1491866Y1737108D03*
X1504602Y312867D03*
X1494840Y1300447D03*
X1511866Y1737108D03*
X1540937Y576522D03*
X1536527Y589012D03*
X1531866Y1737108D03*
X1547429Y28406D03*
X1554515D03*
Y40020D03*
X1547429D03*
X1547312Y579080D03*
X1551866Y1737108D03*
X1561602Y28406D03*
X1568688D03*
Y40020D03*
X1561602D03*
X1575775Y28406D03*
X1582862D03*
X1589948D03*
Y40020D03*
X1582862D03*
X1575775D03*
X1591866Y1737108D03*
X1597035Y28406D03*
X1604122D03*
Y40020D03*
X1597035D03*
X1623881Y117627D03*
X1619980Y615201D03*
X1614116Y1411169D03*
X1611866Y1737108D03*
X1625814Y28406D03*
X1632901D03*
X1639988D03*
X1625814Y40020D03*
X1632901D03*
X1639988D03*
X1637183Y1394411D03*
X1639683D03*
X1634683D03*
X1631866Y1737108D03*
X1654161Y28406D03*
X1647074D03*
Y40020D03*
X1654161D03*
X1652113Y527325D03*
X1652138Y524071D03*
X1651931Y540071D03*
Y536071D03*
X1649291Y556057D03*
X1649149Y607022D03*
X1653929Y604546D03*
X1649139Y604576D03*
X1653736Y607033D03*
X1649117Y602139D03*
X1653930Y602099D03*
X1651866Y1737108D03*
X1669948Y28406D03*
Y40020D03*
X1663376Y515531D03*
X1667376D03*
X1664997Y604762D03*
X1659458Y637149D03*
X1658085Y639511D03*
X1659458Y671149D03*
X1658085Y673511D03*
X1659458Y705149D03*
X1658085Y707511D03*
X1673226Y1394411D03*
X1671866Y1737108D03*
X1677035Y28406D03*
X1684122D03*
X1677035Y40020D03*
X1684122D03*
X1681612Y499290D03*
X1675926Y1394411D03*
X1678426D03*
X1691208Y28406D03*
X1698295D03*
X1705381D03*
X1697824Y39974D03*
X1691208Y40020D03*
X1693987Y230174D03*
Y233174D03*
X1703487Y232174D03*
X1699265Y525507D03*
X1699291Y537507D03*
X1699251Y529507D03*
X1699297Y549507D03*
X1705723Y1583821D03*
X1691866Y1737108D03*
X1711866D03*
X1738200Y193862D03*
X1731866Y1737108D03*
X1753388Y28360D03*
X1754398Y100307D03*
X1752200Y197762D03*
X1748500Y193862D03*
X1745500D03*
X1741200D03*
X1740831Y489362D03*
X1740886Y493960D03*
X1751866Y1737108D03*
X1760475Y28360D03*
X1764678Y122927D03*
X1766880Y234842D03*
Y231842D03*
X1758500Y231822D03*
Y234822D03*
X1755378Y233528D03*
X1782000Y128455D03*
X1771915Y128393D03*
X1782000Y125955D03*
Y123455D03*
X1771915Y125893D03*
Y123393D03*
X1783800Y231762D03*
Y234762D03*
X1775140Y234792D03*
Y231792D03*
X1779226Y275604D03*
X1783563Y273471D03*
X1786089D03*
X1771866Y1737108D03*
X1797663Y269571D03*
X1800189D03*
X1790563Y273471D03*
X1793089D03*
X1802763Y308671D03*
X1795763D03*
X1798289D03*
X1788763D03*
X1791289D03*
X1814349Y269634D03*
X1811823D03*
X1807249D03*
X1804723D03*
X1812349Y308734D03*
X1809823D03*
X1805289Y308671D03*
X1828777Y156520D03*
X1841257Y151402D03*
G54D19*
X20188Y1599396D03*
G54D67*
X1156378Y133866D03*
G54D71*
X1850331Y311946D03*
G54D26*
X60303Y20354D03*
X312921Y24291D03*
X505185Y41142D03*
X757803Y45079D03*
X922441Y237697D03*
X929331Y160413D03*
X1534712Y20354D03*
X1787330Y24291D03*
G54D42*
X337778Y854584D03*
X335924Y857789D03*
X334079Y880219D03*
X332228Y877014D03*
X335928D03*
X334078Y893036D03*
X335928Y896240D03*
X332229Y902649D03*
X332228Y915466D03*
X335928D03*
X332229Y921875D03*
Y941100D03*
X332228Y934692D03*
X335928D03*
X334079Y957122D03*
X335928Y953917D03*
X332228D03*
X332229Y973143D03*
X334079Y976347D03*
X338210Y996480D03*
X332661Y1006093D03*
X338211Y1002888D03*
X332661Y1025318D03*
Y1018910D03*
X338211Y1015705D03*
Y1022114D03*
X332661Y1044544D03*
X338211Y1041340D03*
X334511D03*
X338211Y1060565D03*
X336360Y1082995D03*
X338211Y1111834D03*
Y1105426D03*
Y1124651D03*
X336361Y1115039D03*
Y1127856D03*
X347028Y844971D03*
X345178Y848176D03*
X350727Y844971D03*
X347027Y851380D03*
X343327D03*
X354429D03*
X341478Y854584D03*
X339628Y857789D03*
X347029Y864197D03*
Y857789D03*
X348878Y854584D03*
X345179Y860993D03*
X343327Y857789D03*
X354429Y864197D03*
X350729D03*
X341479Y867401D03*
X348879D03*
X352579D03*
X354429Y877014D03*
X339629D03*
X341479Y873810D03*
X345179Y880219D03*
Y873810D03*
X343329Y877014D03*
X352579Y880219D03*
X350729Y877014D03*
X339629Y883423D03*
X347029D03*
X350729D03*
X352578Y899445D03*
X339629Y896240D03*
Y889832D03*
X348879Y886627D03*
X345179Y893036D03*
X343328Y896240D03*
X352578Y893036D03*
Y886627D03*
X345179Y899445D03*
X348878Y905853D03*
X352578D03*
X341479Y912262D03*
X341478Y905853D03*
X347029Y909057D03*
Y902649D03*
X345179Y912262D03*
X352578D03*
X339629Y915466D03*
X343329D03*
X348878Y925079D03*
X352578D03*
Y918670D03*
X341478Y925079D03*
X347029Y928283D03*
Y921875D03*
X345179Y918670D03*
X341479Y931488D03*
X345179D03*
X352578D03*
X341478Y944304D03*
X352578D03*
X347029Y941100D03*
X348878Y944304D03*
X347029Y947509D03*
X352578Y937896D03*
X339629Y934692D03*
X345179Y937896D03*
X343328Y934692D03*
X348878Y963530D03*
X347029Y960326D03*
X343328D03*
X343329Y966735D03*
X339629D03*
Y953917D03*
X343328D03*
X345179Y957122D03*
X352578D03*
X347029Y966735D03*
X352578Y963530D03*
X341479Y950713D03*
X345179D03*
X352578D03*
X354428Y973143D03*
X339629D03*
X345179Y976347D03*
Y969939D03*
X350729Y973143D03*
X347029Y979552D03*
X352579Y976347D03*
X352578Y969939D03*
X348878Y982756D03*
X352578D03*
X339629Y979552D03*
X343329Y973143D03*
X341911Y1009297D03*
Y1002888D03*
X347461Y999684D03*
X345611Y1009297D03*
X343761Y1006093D03*
X345611Y1002888D03*
X351162Y1006093D03*
X354861D03*
X353011Y1009297D03*
Y1002888D03*
X347461Y1012501D03*
X353011Y1028523D03*
Y1015705D03*
X341911Y1022114D03*
Y1015705D03*
X349311D03*
X347461Y1018910D03*
X345611Y1028523D03*
X343761Y1018910D03*
X345611Y1022114D03*
Y1015705D03*
X353011Y1022114D03*
X343761Y1031727D03*
X347461D03*
X353011Y1034931D03*
Y1047749D03*
X341911Y1041340D03*
X343761Y1038136D03*
X349311Y1034931D03*
X347461Y1038136D03*
X345611Y1041340D03*
X343761Y1044544D03*
X353011Y1041340D03*
X345611Y1047749D03*
X349311Y1054157D03*
X353011Y1060565D03*
Y1054157D03*
X343761Y1057361D03*
Y1050952D03*
X347461D03*
Y1057361D03*
X345611Y1060565D03*
X343761Y1063770D03*
X353011Y1073383D03*
X343761Y1076587D03*
Y1070178D03*
X340062Y1076587D03*
X347461D03*
Y1070178D03*
X349312Y1073383D03*
X345611Y1066974D03*
X353011D03*
X345611Y1079791D03*
X341911D03*
X353011D03*
Y1086200D03*
X349310Y1092609D03*
X347461Y1089404D03*
X345610Y1086200D03*
X343760Y1082995D03*
X340060D03*
X353011Y1092608D03*
X340061Y1095813D03*
X347461Y1108630D03*
X354861D03*
X353011Y1099017D03*
X340061Y1108630D03*
Y1102221D03*
X349311Y1099017D03*
X347461Y1102221D03*
X343761D03*
X340061Y1115039D03*
X349311Y1124651D03*
X349312Y1118243D03*
X345611D03*
X343761Y1115039D03*
X341911Y1124651D03*
X354861Y1115039D03*
X351161Y1121447D03*
Y1115039D03*
X345611Y1137469D03*
Y1131060D03*
X349311D03*
X343761Y1134264D03*
X353011Y1137469D03*
Y1131060D03*
X361829Y851380D03*
X358129D03*
X365529Y864197D03*
X361829D03*
X359979Y854584D03*
X358129Y864197D03*
X369229D03*
X367379Y854584D03*
X359979Y867401D03*
X367379D03*
X365529Y877014D03*
X361829D03*
X358129D03*
X369229D03*
X367379Y880219D03*
X356278Y886627D03*
X365529Y896240D03*
Y889832D03*
X361828Y896240D03*
X361829Y889832D03*
X359979Y893036D03*
X358128Y889832D03*
X369229Y896240D03*
Y889832D03*
X356278Y905853D03*
X365529Y909057D03*
Y902649D03*
X359978Y912262D03*
X358128Y909057D03*
X358129Y902649D03*
X371079Y912262D03*
X365529Y915466D03*
X361828D03*
X369229D03*
X356279Y925079D03*
X365529Y928283D03*
Y921875D03*
X358128Y928283D03*
X358129Y921875D03*
X371078Y918670D03*
X359978Y931488D03*
X371079D03*
X358128Y947509D03*
X358129Y941100D03*
X356279Y944304D03*
X365529Y947509D03*
Y934691D03*
X361828D03*
X369229D03*
X356279Y963530D03*
X358129Y960326D03*
X359979Y957122D03*
X358128Y966735D03*
X361829Y953917D03*
X359978Y950713D03*
X371078Y957122D03*
X371079Y950713D03*
X365529Y953917D03*
X367378Y963530D03*
X363679D03*
X365529Y960326D03*
X365528Y966735D03*
X369229Y953917D03*
X359979Y976347D03*
X358129Y979552D03*
X359978Y969939D03*
X361828Y973143D03*
X356279Y982756D03*
X371078Y976347D03*
X371079Y969939D03*
X369229Y973143D03*
X365529Y979552D03*
Y973143D03*
X365962Y999684D03*
Y1006093D03*
X362261D03*
X360411Y1009297D03*
X360412Y1002888D03*
X358562Y999684D03*
X371512Y1009297D03*
X365961Y1012501D03*
X358561D03*
X356712Y1015705D03*
X365962Y1025318D03*
Y1018910D03*
X364112Y1015705D03*
X360411Y1028523D03*
X362261Y1025318D03*
X360412Y1022114D03*
X358562Y1018910D03*
X369662Y1025318D03*
X367811Y1015705D03*
X371511Y1028523D03*
Y1022114D03*
X365962Y1031727D03*
X358561D03*
X356712Y1034931D03*
X365962Y1044544D03*
Y1038136D03*
X362261Y1044544D03*
X360412Y1041340D03*
X358562Y1038136D03*
X369662Y1044544D03*
X371511Y1041340D03*
X360411Y1047749D03*
X371511D03*
X356712Y1054157D03*
X365962Y1057361D03*
Y1050952D03*
X360412Y1060565D03*
X358562Y1057361D03*
X358561Y1050952D03*
X371511Y1060565D03*
X365962Y1063770D03*
X362261D03*
X369662D03*
X356712Y1073383D03*
X365962Y1070178D03*
X360411Y1066974D03*
X358561Y1070178D03*
X358562Y1076587D03*
X371512Y1066974D03*
X360412Y1079791D03*
X371511D03*
X365962Y1089404D03*
Y1082995D03*
X362261D03*
X360411Y1086200D03*
X358561Y1089404D03*
X356712Y1092608D03*
X369662Y1082995D03*
X371512Y1086200D03*
X365962Y1095813D03*
X358561D03*
X365962Y1102221D03*
X362262D03*
X360411Y1099017D03*
X356711Y1105426D03*
Y1099017D03*
X371512Y1105426D03*
Y1099017D03*
X364112Y1111834D03*
X356712D03*
X371512D03*
X364111Y1118243D03*
X362261Y1115039D03*
X360411Y1118243D03*
X356711D03*
X367811D03*
X371511D03*
X365962Y1127856D03*
X358561D03*
X365961Y1140973D03*
X364112Y1131060D03*
X360412D03*
X358561Y1140973D03*
X356712Y1131060D03*
X367811D03*
X371511D03*
X382179Y854584D03*
X380329Y864197D03*
X376629D03*
X374779Y854584D03*
X372929Y864197D03*
X384029D03*
X387729D03*
X382179Y867401D03*
X374779D03*
X382179Y880219D03*
X380329Y877014D03*
X376629D03*
X374779Y880219D03*
X372929Y877014D03*
X384029D03*
X387729D03*
X380329Y889832D03*
X378479Y893036D03*
X376629Y889832D03*
X372929D03*
X384029D03*
X387729Y896240D03*
Y889832D03*
X378478Y899445D03*
X385879D03*
X382179Y905853D03*
X378478Y912262D03*
Y905853D03*
X374778D03*
X372929Y909057D03*
X372928Y902649D03*
X385878Y912262D03*
X384028Y909057D03*
X384029Y902649D03*
X387728Y915466D03*
X382179Y925079D03*
X378478D03*
Y918670D03*
X374778Y925079D03*
X372929Y928283D03*
X372928Y921875D03*
X385879Y918670D03*
X384028Y928283D03*
X384029Y921875D03*
X385878Y931488D03*
X384029Y941100D03*
X384028Y947509D03*
X374778Y944304D03*
X372929Y947509D03*
X372928Y941100D03*
X382179Y944304D03*
X378478D03*
Y937896D03*
X385879D03*
X387728Y934691D03*
X387729Y953917D03*
X372928Y960326D03*
X374778Y963530D03*
X372929Y966735D03*
X382179Y963530D03*
X378478D03*
Y957122D03*
X384029Y960326D03*
X385879Y957122D03*
X384028Y966735D03*
X385878Y950713D03*
X378478D03*
X387728Y973143D03*
X376629D03*
X380328D03*
X378479Y976347D03*
X378478Y969939D03*
X385879Y976347D03*
X384029Y979552D03*
X385878Y969939D03*
X374778Y982756D03*
X382179D03*
X378478D03*
X372928Y979552D03*
X375210Y996480D03*
X373361Y999684D03*
X378911Y1009297D03*
Y1002888D03*
X386311Y1009297D03*
X386312Y1002888D03*
X384462Y999684D03*
X373362Y1012501D03*
X384461D03*
X382612Y1015705D03*
X378911Y1028523D03*
Y1022114D03*
Y1015705D03*
X375211D03*
X373361Y1018910D03*
X386311Y1028523D03*
X386312Y1022114D03*
X384462Y1018910D03*
X373362Y1031727D03*
X384461D03*
X382612Y1034931D03*
X378911Y1041340D03*
Y1034931D03*
X375211D03*
X373361Y1038136D03*
X386312Y1041340D03*
X384462Y1038136D03*
X378911Y1047749D03*
X386311D03*
X382612Y1054157D03*
X378911D03*
X375211D03*
X373361Y1057361D03*
X373362Y1050952D03*
X386312Y1060565D03*
X384462Y1057361D03*
X384461Y1050952D03*
X382612Y1073383D03*
X378911D03*
Y1066974D03*
X375211Y1073383D03*
X373361Y1076587D03*
X373362Y1070178D03*
X386311Y1066974D03*
X384462Y1076587D03*
X384461Y1070178D03*
X378911Y1079791D03*
X386311D03*
X382611Y1092608D03*
X378911D03*
Y1086200D03*
X375211Y1092608D03*
X373362Y1089404D03*
X386311Y1086200D03*
X384461Y1089404D03*
X373362Y1095813D03*
X384462D03*
X380762Y1108630D03*
X378911Y1099017D03*
X377062Y1102221D03*
X373361Y1108630D03*
Y1102221D03*
X386312Y1099017D03*
X384462Y1102221D03*
X382611Y1118243D03*
X378911D03*
X377061Y1115039D03*
X375211Y1118243D03*
X373361Y1115039D03*
X386311Y1118243D03*
X384461Y1115039D03*
X380761Y1127856D03*
X373361D03*
X382611Y1131060D03*
X380761Y1140973D03*
X378911Y1131060D03*
X375211D03*
X373361Y1140973D03*
X386311Y1131060D03*
X396979Y841467D03*
X398829Y851380D03*
X395129D03*
X391429D03*
X402529D03*
X398829Y864197D03*
X396979Y854584D03*
X395129Y864197D03*
X391429D03*
X389579Y854584D03*
X402529Y864197D03*
X396979Y867401D03*
X389579D03*
X398829Y877014D03*
X396979Y880219D03*
X395129Y877014D03*
X391429D03*
X389579Y880219D03*
X402529Y877014D03*
X398829Y889832D03*
X395129Y896240D03*
Y889832D03*
X391428Y896240D03*
X391429Y889832D03*
X389579Y893036D03*
X402529Y889832D03*
X398829Y909057D03*
X398828Y902649D03*
X396979Y912262D03*
X391429Y909057D03*
Y902649D03*
X395129Y915466D03*
X391429D03*
X398829Y928283D03*
X398828Y921875D03*
X396978Y918670D03*
X391429Y928283D03*
Y921875D03*
X400678Y925079D03*
X396979Y931488D03*
X398828Y941100D03*
X395129Y934691D03*
X391429Y941100D03*
Y934691D03*
X400678Y937896D03*
X398829Y947509D03*
X391429D03*
X398828Y960326D03*
X396978Y957122D03*
X396979Y950713D03*
X395129Y953917D03*
X391429Y960326D03*
Y953917D03*
X400678Y957122D03*
X398829Y966735D03*
X391429D03*
X400678Y963530D03*
X398828Y979552D03*
X396978Y976347D03*
X396979Y969939D03*
X395129Y973143D03*
X391429Y979552D03*
Y973143D03*
X400678Y982756D03*
Y969939D03*
X397412Y1009297D03*
X397411Y1002888D03*
X395562Y1006093D03*
X391862D03*
Y999684D03*
X388161Y1006093D03*
X401111Y1002888D03*
X399262Y1012501D03*
X391861D03*
X399261Y1018910D03*
X397411Y1028523D03*
Y1022114D03*
X395562Y1025318D03*
X393711Y1015705D03*
X391862Y1025318D03*
Y1018910D03*
X390012Y1015705D03*
X388161Y1025318D03*
X399262Y1031727D03*
X391862D03*
X399261Y1038136D03*
X397411Y1041340D03*
X395562Y1044544D03*
X391862D03*
Y1038136D03*
X388161Y1044544D03*
X397411Y1047749D03*
X399261Y1057361D03*
X399262Y1050952D03*
X397411Y1060565D03*
X391862Y1057361D03*
Y1050952D03*
X395562Y1063770D03*
X391862D03*
X388161D03*
X399261Y1076587D03*
X399262Y1070178D03*
X397412Y1066974D03*
X391862Y1076587D03*
Y1070178D03*
X401111Y1073383D03*
X397411Y1079791D03*
X401111D03*
X399262Y1089404D03*
X397412Y1086200D03*
X395562Y1082995D03*
X391862Y1089404D03*
Y1082995D03*
X388161D03*
X401112Y1092608D03*
X401111Y1086200D03*
X399261Y1095813D03*
X391862D03*
X402962D03*
X399262Y1102221D03*
X397412Y1099017D03*
X395562Y1102221D03*
X390011Y1105426D03*
X388162Y1108630D03*
Y1102221D03*
X401111Y1105426D03*
X397411Y1111834D03*
X390011D03*
X397411Y1118243D03*
X395561Y1115039D03*
X393711Y1118243D03*
X390011D03*
X388161Y1115039D03*
X401111Y1118243D03*
X395561Y1127856D03*
X388161D03*
X402961D03*
X397411Y1131060D03*
X395561Y1140973D03*
X393711Y1131060D03*
X390011D03*
X388161Y1140973D03*
X402961D03*
X401111Y1131060D03*
X419179Y841467D03*
X404379D03*
X411779D03*
X413629Y851380D03*
X409929D03*
X406229D03*
X417329D03*
X404379Y854584D03*
X413629Y864197D03*
X411779Y854584D03*
X409929Y864197D03*
X406229D03*
X419179Y854584D03*
X417329Y864197D03*
X404379Y867401D03*
X411779D03*
X419179D03*
X404379Y880219D03*
X413629Y877014D03*
X411779Y880219D03*
X409929Y877014D03*
Y870606D03*
X406229Y877014D03*
X419179Y880219D03*
X417329Y877014D03*
X413629Y889832D03*
X411779Y893036D03*
X409929Y889832D03*
X408079Y893036D03*
X406229Y889832D03*
X419179Y893036D03*
X417329Y889832D03*
X413629Y902649D03*
X409929Y909057D03*
Y902649D03*
X404378Y912262D03*
Y905853D03*
X419178Y912262D03*
X419179Y905853D03*
X417329Y902649D03*
X409929Y915466D03*
Y921875D03*
X404378Y918670D03*
X418229Y926896D03*
X419178Y918670D03*
X405048Y930812D03*
X405145Y946239D03*
Y948539D03*
X414093Y942098D03*
X405048Y938046D03*
Y935746D03*
X416393Y942098D03*
X418693D03*
X405122Y965896D03*
Y963596D03*
X414365Y971140D03*
X416755D03*
X404861Y981269D03*
Y978969D03*
Y986421D03*
X405101Y992971D03*
Y995271D03*
X404861Y988721D03*
X405227Y1007156D03*
X405231Y1004848D03*
X417575Y1000060D03*
X415185D03*
X404986Y1022427D03*
X404998Y1026821D03*
X408325Y1031971D03*
Y1034271D03*
X408511Y1041340D03*
X417762Y1044544D03*
X412211Y1047749D03*
X404811D03*
X415911Y1060565D03*
Y1054157D03*
X412211Y1060565D03*
X410361Y1050952D03*
X408511Y1054157D03*
X404811Y1060565D03*
X417761Y1050952D03*
X415911Y1066974D03*
X410362Y1076587D03*
Y1070178D03*
X406661Y1076587D03*
X404811Y1066974D03*
X419611Y1073383D03*
X412211Y1079791D03*
X404811D03*
X415911Y1092608D03*
X415912Y1086200D03*
X412211Y1092608D03*
X408511Y1086200D03*
X417761Y1089404D03*
Y1082995D03*
X410362Y1095813D03*
X406662D03*
X415912Y1099017D03*
X414062Y1108630D03*
X412211Y1099017D03*
X410362Y1102221D03*
X406661Y1108630D03*
Y1102221D03*
X404812Y1105426D03*
X417762Y1102221D03*
X404812Y1111834D03*
X415911Y1118243D03*
X414061Y1121447D03*
X412211Y1124651D03*
Y1118243D03*
X410361Y1115039D03*
X408511Y1118243D03*
X406661Y1115039D03*
X404811Y1118243D03*
X417761Y1115039D03*
X410361Y1127856D03*
X414062Y1134264D03*
X412212Y1131060D03*
X410361Y1140973D03*
X408511Y1131060D03*
X404811D03*
X432128Y844671D03*
X426579Y841467D03*
X432129Y851380D03*
X428429D03*
X424729D03*
X421029D03*
X432129Y864197D03*
X428429D03*
X426579Y854584D03*
X424729Y864197D03*
X421029D03*
X433979Y854584D03*
X426579Y867401D03*
X433979D03*
X432129Y877014D03*
X428429D03*
X426579Y880219D03*
X424729Y877014D03*
X421029D03*
X433979Y880219D03*
X432129Y889832D03*
X428429D03*
X426579Y893036D03*
X424729Y889832D03*
X421029D03*
X433979Y893036D03*
X424729Y902649D03*
X432129D03*
X428429Y909057D03*
Y902649D03*
X421029D03*
X428429Y915466D03*
X433980Y925079D03*
Y931487D03*
X426875Y947199D03*
Y949499D03*
X427875Y936470D03*
X426905Y965935D03*
Y963635D03*
Y980336D03*
Y978036D03*
Y994722D03*
Y992422D03*
Y1006875D03*
Y1009175D03*
Y1021963D03*
Y1019663D03*
X428862Y1044544D03*
X430712Y1047749D03*
X423311D03*
X425162Y1057361D03*
X432561Y1050952D03*
X434411Y1060565D03*
Y1054157D03*
X421462Y1063770D03*
X430711Y1073383D03*
X427011D03*
Y1066974D03*
X425162Y1076587D03*
X423311Y1066974D03*
X432561Y1076587D03*
X434411Y1073383D03*
Y1066974D03*
X427012Y1079791D03*
X434411D03*
X428861Y1082995D03*
X425162Y1089404D03*
X421462Y1082995D03*
X432561Y1089404D03*
Y1082995D03*
X434411Y1086200D03*
X428861Y1095813D03*
X421462D03*
X432561D03*
X427011Y1099017D03*
X425161Y1102221D03*
X423311Y1105426D03*
X421462Y1108630D03*
X434411Y1105426D03*
X423311Y1111834D03*
X434411D03*
X423311Y1124651D03*
Y1118243D03*
X421462Y1115039D03*
X434411Y1124651D03*
Y1118243D03*
X423312Y1137469D03*
X423311Y1131060D03*
X434412Y1137769D03*
X434411Y1131060D03*
X452478Y848176D03*
X445078D03*
X441378D03*
X439529Y844671D03*
X446929Y851380D03*
X443228D03*
X439529D03*
X448779Y854584D03*
X446929Y864197D03*
X443229D03*
X441379Y854584D03*
X439529Y864197D03*
X439528Y857789D03*
X437680Y860992D03*
X450629Y864197D03*
X448779Y867401D03*
X441379D03*
X448779Y880219D03*
X446929Y877014D03*
X443229D03*
X441379Y880219D03*
X439529Y877014D03*
X448779Y893036D03*
X446929Y889832D03*
X443229D03*
X441379Y893036D03*
X439529Y896240D03*
Y889832D03*
X437678Y886627D03*
X450629Y889832D03*
X437679Y899445D03*
X446929Y909057D03*
Y902649D03*
X443229D03*
X439528D03*
X437679Y905853D03*
X450629Y902649D03*
X446929Y915466D03*
X446930Y928283D03*
X441379Y925079D03*
Y931487D03*
X446929Y921875D03*
X437678Y918670D03*
X448779Y937897D03*
X447360Y1038136D03*
X452911Y1041340D03*
X451061Y1044544D03*
X449211Y1047749D03*
X447361Y1057361D03*
Y1050952D03*
X452911Y1060565D03*
X447361Y1063770D03*
Y1076587D03*
Y1070178D03*
X449211Y1073383D03*
X452911Y1079791D03*
X449211D03*
X447361Y1082995D03*
X452911Y1092608D03*
X451062Y1089404D03*
X449212Y1086200D03*
X451062Y1095813D03*
X447361Y1108630D03*
Y1102221D03*
X452911Y1099017D03*
X447361Y1121447D03*
Y1115039D03*
Y1127856D03*
Y1134264D03*
X461729Y851380D03*
X458029D03*
X454328D03*
X456179Y841467D03*
X463579D03*
X469129Y851380D03*
X465429D03*
X456179Y854584D03*
X463579D03*
X461729Y864197D03*
X458029D03*
X454329D03*
X469129D03*
X465429D03*
X456179Y867401D03*
X463579D03*
X461729Y877014D03*
X458029D03*
X456179Y880219D03*
X454329Y877014D03*
X463579Y880219D03*
X469129Y877014D03*
X465429D03*
X461729Y889832D03*
X458029D03*
X456179Y893036D03*
X454329Y889832D03*
X463579Y893036D03*
X469129Y896240D03*
Y889832D03*
X465429D03*
X461729Y902649D03*
X458029D03*
X456178Y905853D03*
X454329Y902649D03*
X465429D03*
Y909057D03*
Y915466D03*
X454103Y931359D03*
Y933659D03*
X456178Y918670D03*
X454434Y1022186D03*
Y1019886D03*
X460311Y1041340D03*
X467372Y1036874D03*
X465861Y1044544D03*
X456611Y1047749D03*
X464011D03*
X456611Y1054157D03*
X462162Y1050952D03*
X454761Y1076587D03*
X462162Y1070178D03*
X456612Y1079791D03*
X467711D03*
X458461Y1082995D03*
X456611Y1086200D03*
X460311Y1092608D03*
X464011Y1086200D03*
X467712D03*
Y1092608D03*
X460312Y1105426D03*
X458462Y1102221D03*
X456611Y1099017D03*
X464012Y1105426D03*
Y1099017D03*
X462162Y1108630D03*
X465861D03*
Y1102221D03*
X464012Y1111834D03*
X467711Y1105426D03*
Y1111834D03*
X458462Y1121447D03*
Y1115039D03*
X467712Y1124651D03*
X467711Y1118243D03*
X465862Y1121447D03*
Y1115039D03*
X458462Y1127856D03*
Y1134264D03*
X478379Y841467D03*
X470979D03*
X476529Y851380D03*
X480229D03*
X472829D03*
X483929D03*
X480229Y864197D03*
X478379Y854584D03*
X476529Y864197D03*
X470979Y854584D03*
X472829Y864197D03*
X483929D03*
X478379Y867401D03*
X470979D03*
X480229Y877014D03*
X478379Y880219D03*
X476529Y877014D03*
X472829D03*
X472828Y870606D03*
X470979Y880219D03*
Y873810D03*
X483929Y877014D03*
X480228Y896240D03*
X480229Y889832D03*
X478379Y893036D03*
X470979D03*
X476529Y889832D03*
X472829D03*
X483929D03*
X482078Y899445D03*
X474678Y905853D03*
X483929Y909057D03*
X482079Y912262D03*
X483928Y902649D03*
X476285Y930126D03*
X476528Y921875D03*
X474678Y918670D03*
X483929Y928283D03*
X482078Y918670D03*
X483928Y921875D03*
X482079Y931488D03*
X476285Y934726D03*
X476180Y945355D03*
Y947655D03*
X478378Y944304D03*
X480229Y934691D03*
X483928Y941100D03*
X482079Y944304D03*
X482078Y937896D03*
X483928Y947509D03*
X476285Y962326D03*
Y960026D03*
Y964626D03*
X483928Y960326D03*
X482078Y957122D03*
X482079Y950713D03*
X483929Y966735D03*
X476285Y966926D03*
X476192Y977670D03*
X476335Y980737D03*
X482079Y969939D03*
X483928Y979552D03*
X482078Y976347D03*
X476285Y996826D03*
Y994526D03*
Y989926D03*
Y987626D03*
X476295Y1010500D03*
X476285Y1012926D03*
Y1006026D03*
Y1003726D03*
X484361Y999684D03*
X482512Y1009297D03*
X482511Y1002888D03*
X484362Y1012501D03*
X476275Y1022636D03*
X476285Y1017526D03*
X482511Y1028523D03*
Y1022114D03*
X484361Y1018910D03*
Y1031727D03*
X471282Y1036526D03*
X473507Y1035928D03*
X475111Y1041340D03*
X482511D03*
X482512Y1034931D03*
X484361Y1038136D03*
X471411Y1047749D03*
X482511D03*
X480662Y1050952D03*
X471411Y1054157D03*
X482511Y1060565D03*
X484362Y1050952D03*
Y1070178D03*
X482511Y1079791D03*
X480662Y1082995D03*
X476962Y1089404D03*
X473262Y1082995D03*
X469561Y1089404D03*
X482512Y1086200D03*
X484362Y1089404D03*
X480661Y1095813D03*
X469562D03*
X484362D03*
X480662Y1108630D03*
X478811Y1099017D03*
X473262Y1108630D03*
X476962Y1102221D03*
X475112Y1099017D03*
X471411D03*
X469562Y1102221D03*
X482511Y1105426D03*
Y1111834D03*
X484362Y1108630D03*
X475111Y1111834D03*
X471411D03*
X478811Y1105426D03*
X469562Y1108630D03*
X473262Y1102221D03*
X482511Y1099017D03*
X478811Y1111834D03*
X476962Y1108630D03*
X471411Y1105426D03*
X475111D03*
X484362Y1102221D03*
X480661Y1115039D03*
X478811Y1118243D03*
X476961Y1115039D03*
X475111Y1118243D03*
X471411D03*
X469561Y1115039D03*
X482511Y1118243D03*
X476961Y1127856D03*
X469562D03*
X484361D03*
X484362Y1115039D03*
X473262D03*
X478811Y1131060D03*
X476961Y1140973D03*
X475111Y1131060D03*
X471412Y1137469D03*
Y1131060D03*
X469561Y1140973D03*
X473261Y1134264D03*
X482511Y1131060D03*
X484361Y1140973D03*
X493179Y841467D03*
X485779D03*
X500579D03*
X495029Y851380D03*
X491329D03*
X487629D03*
X498729D03*
X495029Y864197D03*
X493179Y854584D03*
X491329Y864197D03*
X487629D03*
X485779Y854584D03*
X498729Y864197D03*
X500579Y854584D03*
X493179Y867401D03*
X485779D03*
X500579D03*
X495029Y877014D03*
X493179Y880219D03*
X491329Y877014D03*
X487629D03*
X485779Y880219D03*
X500579D03*
X498729Y877014D03*
X489479Y893036D03*
X495029Y889832D03*
X491329D03*
X487629D03*
X498729D03*
X500579Y893036D03*
X498729Y896240D03*
X496879Y899445D03*
X489478D03*
X496878Y912262D03*
X495029Y909057D03*
X489478Y905853D03*
X495029Y902649D03*
X493179Y905853D03*
X485778D03*
X498728Y915466D03*
X495028Y928283D03*
X493179Y925079D03*
X489478D03*
Y918670D03*
X485778Y925079D03*
X496879Y918670D03*
X495029Y921875D03*
X496878Y931488D03*
X489478D03*
X496879Y937896D03*
X495029Y941100D03*
X493179Y944304D03*
X489478D03*
Y937896D03*
X485778Y944304D03*
X498729Y934691D03*
X495028Y947509D03*
X496879Y957122D03*
X495029Y960326D03*
X489478Y957122D03*
Y950713D03*
X496878D03*
X498729Y953917D03*
X495028Y966735D03*
X493179Y963530D03*
X485778D03*
X489478D03*
X500579D03*
X496879Y976347D03*
X496878Y969939D03*
X489478Y976347D03*
Y969939D03*
X495029Y979552D03*
X498728Y973143D03*
X493179Y982756D03*
X489478D03*
X485778D03*
X497311Y1009297D03*
X497312Y1002888D03*
X495462Y999684D03*
X489911Y1009297D03*
X489912Y1002888D03*
X491761Y1006093D03*
X488062D03*
X499161D03*
X495461Y1012501D03*
X497311Y1028523D03*
X489911D03*
Y1022114D03*
Y1015705D03*
X497311Y1022114D03*
X495462Y1018910D03*
X493612Y1015705D03*
X486211D03*
X501012D03*
X499161Y1025318D03*
X495461Y1031727D03*
X497312Y1041340D03*
X489911D03*
Y1034931D03*
X495462Y1038136D03*
X493612Y1034931D03*
X486211D03*
X499161Y1044544D03*
X489911Y1047749D03*
X497311D03*
Y1060565D03*
X489911D03*
Y1054157D03*
X495461Y1050952D03*
X493611Y1054157D03*
X486211D03*
X489911Y1066974D03*
X495461Y1070178D03*
X489911Y1073383D03*
X497312Y1079791D03*
X489911D03*
X497311Y1086200D03*
X493612Y1092608D03*
X489911D03*
Y1086200D03*
X486211Y1092608D03*
X495461Y1089404D03*
X499161Y1082995D03*
X495462Y1095813D03*
X499162D03*
X491762D03*
X497312Y1105426D03*
X493611D03*
X491762Y1102221D03*
X488061D03*
X486211Y1105426D03*
X486212Y1099017D03*
X499161Y1108630D03*
Y1102221D03*
X497312Y1111834D03*
X489911D03*
Y1099017D03*
X495462Y1102221D03*
X501011Y1099017D03*
X493611D03*
X497311D03*
X489911Y1105426D03*
X486211Y1111834D03*
X491762Y1108630D03*
X488062D03*
X497311Y1118243D03*
X495462Y1121447D03*
X493612Y1118243D03*
X489911D03*
X486211D03*
X501011D03*
X499161Y1115039D03*
X491761Y1127856D03*
X499161D03*
X491762Y1115039D03*
X495462D03*
X497311Y1131060D03*
X493611D03*
X489911D03*
X486211D03*
X491761Y1140973D03*
X501011Y1131060D03*
X499161Y1140973D03*
X507979Y841467D03*
X515379D03*
X506129Y851380D03*
X502429D03*
X513529D03*
X509829D03*
X517229D03*
X513529Y864197D03*
X509829D03*
X506129D03*
X502429D03*
X507979Y854584D03*
X515379D03*
X517229Y864197D03*
X507979Y867401D03*
X515379D03*
X509829Y877014D03*
X507979Y880219D03*
X502429Y877014D03*
X513529D03*
X506129D03*
X515379Y880219D03*
X517229Y877014D03*
X506129Y889832D03*
X502428Y896240D03*
X502429Y889832D03*
X513529D03*
X509829D03*
X506128Y896240D03*
X504279Y893036D03*
X515379D03*
X517229Y889832D03*
X507978Y899445D03*
X515378D03*
X511678Y905853D03*
X509829Y909057D03*
X507979Y912262D03*
X502429Y909057D03*
Y902649D03*
X509828D03*
X515378Y912262D03*
Y905853D03*
X502429Y915466D03*
X506129D03*
X511678Y925079D03*
X509829Y928283D03*
X502429D03*
Y921875D03*
X509828D03*
X507978Y918670D03*
X515378Y925079D03*
Y918670D03*
X507979Y931488D03*
X515378D03*
X511678Y944304D03*
X509828Y941100D03*
X506129Y934691D03*
X502429Y941100D03*
Y934691D03*
X515378Y944304D03*
Y937896D03*
X502429Y947509D03*
X509828Y960326D03*
X507978Y957122D03*
X506129Y953917D03*
X502429Y960326D03*
Y953917D03*
X507979Y950713D03*
X515378Y957122D03*
Y950713D03*
X509829Y966735D03*
X502428D03*
X511678Y963530D03*
X504278D03*
X515378D03*
X507978Y976347D03*
X507979Y969939D03*
X502429Y979552D03*
Y973143D03*
X513529D03*
X509828Y979552D03*
X506129Y973143D03*
X515379Y976347D03*
X515378Y969939D03*
X517228Y973143D03*
X511678Y982756D03*
X515378D03*
X510261Y999684D03*
X508411Y1002888D03*
X506562Y1006093D03*
X502862Y999684D03*
X502861Y1012501D03*
X508412Y1009297D03*
X510262Y1012501D03*
X515811Y1009297D03*
Y1002888D03*
X508411Y1028523D03*
X502862Y1025318D03*
Y1018910D03*
X510261D03*
X508411Y1022114D03*
X506562Y1025318D03*
X504711Y1015705D03*
X515811Y1028523D03*
Y1022114D03*
X510262Y1031727D03*
X502862D03*
X515811Y1015705D03*
X512111D03*
X502862Y1044544D03*
Y1038136D03*
X512111Y1034931D03*
X510261Y1038136D03*
X508411Y1041340D03*
X506562Y1044544D03*
X515811Y1034931D03*
Y1041340D03*
X508411Y1047749D03*
X515811D03*
X508411Y1060565D03*
X502862Y1057361D03*
Y1050952D03*
X512111Y1054157D03*
X510262Y1050952D03*
X515811Y1054157D03*
Y1060565D03*
X502862Y1063770D03*
X510262Y1070178D03*
X502862Y1076587D03*
Y1070178D03*
X515811Y1073383D03*
Y1079791D03*
X512112Y1092608D03*
X510262Y1089404D03*
X508412Y1086200D03*
X506562Y1082995D03*
X502862Y1089404D03*
Y1082995D03*
X515812Y1092608D03*
X513961Y1095813D03*
X502862D03*
X517662D03*
X513962Y1108630D03*
Y1102221D03*
X512112Y1099017D03*
X508411D03*
X506562Y1108630D03*
X504711Y1099017D03*
X502862Y1102221D03*
X515811Y1105426D03*
Y1111834D03*
X517662Y1108630D03*
X513961Y1115039D03*
X512111Y1118243D03*
X508411D03*
X504711D03*
X510261Y1115039D03*
X515811Y1118243D03*
X513961Y1127856D03*
X506561D03*
X517662Y1115039D03*
X513961Y1140973D03*
X512111Y1131060D03*
X508411D03*
X504711D03*
X506561Y1140973D03*
X515811Y1131060D03*
X528329Y844671D03*
X522779Y841467D03*
X528329Y851380D03*
X524629D03*
X520929D03*
X532029D03*
X528329Y864197D03*
X524629D03*
X520929D03*
X530179Y860993D03*
Y854584D03*
X522779D03*
X532028Y857789D03*
X533879Y860993D03*
X530178Y867401D03*
X522779D03*
X533879D03*
X528329Y877014D03*
X522779Y880219D03*
X520929Y877014D03*
X530179Y880219D03*
X524629Y877014D03*
X532029D03*
X533879Y880219D03*
Y873810D03*
X532028Y883423D03*
X528329Y896240D03*
Y889832D03*
X524629D03*
X526479Y893036D03*
X524629Y896240D03*
X520929Y889832D03*
X532029D03*
Y896240D03*
X533879Y893036D03*
X522779Y899445D03*
X533879D03*
X528329Y902649D03*
X522778Y912262D03*
X520928Y909057D03*
X519079Y905853D03*
X520929Y902649D03*
X528329Y915466D03*
X524628D03*
X532029D03*
X528329Y909057D03*
X533879Y912262D03*
X528329Y921875D03*
X520928Y928283D03*
X519079Y925079D03*
X522779Y918670D03*
X520929Y921875D03*
X522778Y931488D03*
X528329Y928283D03*
X533879Y918670D03*
X533878Y931488D03*
X528329Y941100D03*
Y934691D03*
X524628D03*
X522779Y937896D03*
X520929Y941100D03*
X519079Y944304D03*
X520928Y947509D03*
X532029Y934691D03*
X533879Y937896D03*
X528329Y947509D03*
Y960326D03*
Y953917D03*
X524629D03*
X522779Y957122D03*
X520929Y960326D03*
X522778Y950713D03*
X520928Y966735D03*
X526479Y963530D03*
X519079D03*
X533879Y957122D03*
X532029Y953917D03*
X533879Y950713D03*
X530178Y963530D03*
X528329Y966735D03*
Y979552D03*
Y973143D03*
X522779Y976347D03*
X522778Y969939D03*
X524628Y973143D03*
X520929Y979552D03*
X533879Y976347D03*
X519079Y982756D03*
X533901Y980606D03*
X533879Y969939D03*
X532029Y973143D03*
X521361Y1012501D03*
Y999684D03*
X528762Y1006093D03*
Y999684D03*
X525061Y1006093D03*
X523211Y1009297D03*
X523212Y1002888D03*
X534311Y1009297D03*
Y1002888D03*
X532461Y1006093D03*
X528761Y1012501D03*
X528762Y1025318D03*
X523211Y1028523D03*
X525061Y1025318D03*
X528762Y1031727D03*
X521361D03*
X519512Y1015705D03*
X521362Y1018910D03*
X523211Y1022114D03*
X526912Y1015705D03*
X528762Y1018910D03*
X530611Y1015705D03*
X534311Y1028523D03*
X534310Y1022114D03*
X532461Y1025318D03*
X528762Y1044544D03*
X525061D03*
X523212Y1041340D03*
X521362Y1038136D03*
X519512Y1034931D03*
X532462Y1044544D03*
X523211Y1047749D03*
X528762Y1038136D03*
X534311Y1041340D03*
Y1047749D03*
X528762Y1057361D03*
Y1050952D03*
X523212Y1060565D03*
X521361Y1050952D03*
X519512Y1054157D03*
X528762Y1063770D03*
X534311Y1060565D03*
X528762Y1076587D03*
Y1070178D03*
X521361D03*
X523212Y1079791D03*
X534311D03*
X523211Y1086200D03*
X521361Y1089404D03*
X519511Y1092608D03*
X528762Y1089404D03*
Y1082995D03*
X525061D03*
X532462Y1082996D03*
X534311Y1086200D03*
X528761Y1095813D03*
X526911Y1105426D03*
X521361Y1102221D03*
X519511Y1105426D03*
X519512Y1099017D03*
X532461Y1108630D03*
X530612Y1111834D03*
X523211D03*
X526911Y1099017D03*
X534311D03*
X532460Y1102221D03*
X521362Y1108630D03*
X525062D03*
X534311Y1111834D03*
X523211Y1105426D03*
X534311D03*
X528762Y1108630D03*
X519511Y1111834D03*
X526911D03*
X530611Y1124651D03*
Y1118243D03*
X528762Y1121447D03*
X523211Y1118243D03*
X521361Y1115039D03*
X519511Y1118243D03*
X532461Y1115039D03*
X528761Y1127856D03*
X521361D03*
X525062Y1115039D03*
X528762D03*
X530612Y1137469D03*
Y1131060D03*
X526912D03*
X523211D03*
X519511D03*
X528761Y1134264D03*
X521361Y1140973D03*
X534311Y1131060D03*
X537580Y848176D03*
X535729Y844671D03*
Y851380D03*
X544979Y860993D03*
Y854584D03*
X539428Y864197D03*
X537579Y854584D03*
Y860993D03*
X544979Y867401D03*
X541279D03*
X537579D03*
X546829Y870606D03*
X541279Y873810D03*
X535729Y870606D03*
Y883423D03*
X541279Y880219D03*
X546829Y883423D03*
X537579Y893036D03*
X541279Y886627D03*
X544979D03*
X537579D03*
X535729Y889832D03*
X550529D03*
X537579Y899445D03*
X548679Y912262D03*
X537579D03*
X539429Y909057D03*
X537579Y905853D03*
X535729Y909057D03*
X543129D03*
X535729Y902649D03*
X548679Y905853D03*
X537579Y918670D03*
X535729Y921875D03*
X537578Y931488D03*
X548678D03*
X537579Y937896D03*
X535729Y941100D03*
X539429Y947509D03*
X535729D03*
X537579Y957122D03*
Y950713D03*
X535729Y960326D03*
Y966735D03*
X537579Y963530D03*
X539429Y979552D03*
X537579Y982756D03*
X541279Y969939D03*
X539429Y973143D03*
X535729D03*
X539862Y1006092D03*
X539861Y999684D03*
X536161D03*
Y1006093D03*
X543563Y1006092D03*
X549254Y1000648D03*
X536161Y1012501D03*
Y1025318D03*
X539861Y1018910D03*
X541712Y1015705D03*
X545412D03*
X538012D03*
X536161Y1018910D03*
X549112Y1015705D03*
X536161Y1031727D03*
X545412Y1034931D03*
X539862Y1044544D03*
X539861Y1038136D03*
X541711Y1034931D03*
X538011D03*
X536161Y1038136D03*
X549112Y1034931D03*
X541711Y1054157D03*
X538011D03*
X545411D03*
X538011Y1060565D03*
X536161Y1050952D03*
X538011Y1066974D03*
X539861Y1076587D03*
X536162Y1082996D03*
X538011Y1092608D03*
X536161Y1089404D03*
X545411Y1092608D03*
X547262Y1082996D03*
X543561Y1095813D03*
X536161D03*
X547261D03*
X545412Y1105426D03*
X541711D03*
X539861Y1108630D03*
Y1102221D03*
X536161D03*
X541711Y1111834D03*
X545411D03*
X538011Y1105426D03*
X536161Y1108630D03*
X538011Y1111834D03*
X543561Y1108630D03*
X545411Y1124651D03*
Y1118243D03*
X543562Y1115039D03*
X539862D03*
X538011Y1124651D03*
X536161Y1115039D03*
X541711Y1131060D03*
X536162Y1134264D03*
X551429Y979057D03*
X550701Y972608D03*
X550961Y1031727D03*
X560571Y1614292D03*
X580431Y1602380D03*
X688999Y1051247D03*
X748399D03*
X1293802Y162999D03*
X1297007Y161149D03*
X1297012Y168549D03*
X1297007Y164849D03*
X1293802Y183349D03*
Y187049D03*
Y190749D03*
Y198149D03*
Y194449D03*
Y201849D03*
X1296999Y209249D03*
X1300774Y155288D03*
X1309832Y161149D03*
X1303417D03*
X1309832Y168549D03*
X1303417D03*
X1303422Y172249D03*
X1313033Y174099D03*
X1306622D03*
X1300207Y185199D03*
X1306617Y181499D03*
X1300207Y192599D03*
X1309817Y187049D03*
X1306617Y192599D03*
X1313023Y199999D03*
X1306617D03*
X1300207D03*
X1303407Y201849D03*
X1303422Y209249D03*
X1313032Y214799D03*
X1306622Y218499D03*
X1303417Y212949D03*
Y216649D03*
X1300207Y214799D03*
X1301151Y225450D03*
X1309828Y224049D03*
X1306622Y222199D03*
X1309100Y236477D03*
X1313920Y854584D03*
X1312266Y857972D03*
X1312070Y877014D03*
X1310221Y880219D03*
X1308370Y877014D03*
X1312070Y896240D03*
X1310220Y893036D03*
X1308371Y902649D03*
X1312070Y915466D03*
X1308370D03*
X1308371Y921875D03*
X1312070Y934692D03*
X1308371Y941100D03*
X1308370Y934692D03*
X1312070Y953917D03*
X1308370D03*
X1310221Y957122D03*
X1308371Y973143D03*
X1310221Y976347D03*
X1314352Y996480D03*
X1314353Y1002888D03*
X1308803Y1006093D03*
X1314353Y1015705D03*
Y1022114D03*
X1308803Y1025318D03*
Y1018910D03*
X1314353Y1041340D03*
X1308803Y1044544D03*
X1310653Y1041340D03*
X1314353Y1060565D03*
X1312502Y1082995D03*
X1314353Y1111834D03*
Y1105426D03*
X1312503Y1115039D03*
Y1127856D03*
X1320469Y155288D03*
X1322652Y161149D03*
X1316242D03*
X1319452Y166699D03*
X1329062Y168549D03*
X1319442Y170399D03*
X1318502Y176574D03*
Y186024D03*
Y182874D03*
X1329062Y172249D03*
X1316237D03*
X1331102Y176574D03*
X1327952Y186024D03*
Y182874D03*
X1318502Y189174D03*
X1315352Y195474D03*
X1327952Y189174D03*
X1331102Y195474D03*
X1327952Y198624D03*
X1321652D03*
X1325852Y214799D03*
X1319442Y218499D03*
X1329062Y209249D03*
X1319442Y207399D03*
X1329062Y216649D03*
X1319442Y222199D03*
X1329061Y224049D03*
X1326377Y235784D03*
X1321986Y236726D03*
X1326869Y844971D03*
X1323170D03*
X1321320Y848176D03*
X1330571Y851380D03*
X1323170D03*
X1319469D03*
X1317620Y854584D03*
X1315770Y857789D03*
X1330571Y864197D03*
X1326871D03*
X1323171D03*
Y857789D03*
X1325020Y854584D03*
X1321321Y860993D03*
X1319469Y857789D03*
X1317621Y867401D03*
X1328721D03*
X1325021D03*
X1330571Y877014D03*
X1328722Y880219D03*
X1326871Y877014D03*
X1321321Y873810D03*
X1315771Y877014D03*
X1317621Y873810D03*
X1321321Y880219D03*
X1319471Y877014D03*
X1315771Y883423D03*
X1326871D03*
X1323171D03*
X1328720Y899445D03*
X1315771Y896240D03*
Y889832D03*
X1328720Y893036D03*
Y886627D03*
X1325021D03*
X1321321Y893036D03*
X1319470Y896240D03*
X1321321Y899445D03*
X1328720Y905853D03*
X1325020D03*
X1317621Y912262D03*
X1317620Y905853D03*
X1328720Y912262D03*
X1323171Y909057D03*
Y902649D03*
X1321321Y912262D03*
X1315771Y915466D03*
X1319471D03*
X1328720Y925079D03*
Y918670D03*
X1325020Y925079D03*
X1317620D03*
X1323171Y928283D03*
Y921875D03*
X1321321Y918670D03*
X1317621Y931488D03*
X1328720D03*
X1321321D03*
X1323171Y941100D03*
X1325020Y944304D03*
X1323171Y947509D03*
X1317620Y944304D03*
X1328720D03*
Y937896D03*
X1315771Y934692D03*
X1321321Y937896D03*
X1319470Y934692D03*
X1321321Y957122D03*
X1323171Y966735D03*
X1325020Y963530D03*
X1323171Y960326D03*
X1321321Y950713D03*
X1315771Y953917D03*
Y966735D03*
X1319470Y953917D03*
X1319471Y966735D03*
X1319470Y960326D03*
X1317621Y950713D03*
X1328720Y957122D03*
Y963530D03*
Y950713D03*
X1321321Y969939D03*
X1325020Y982756D03*
X1323171Y979552D03*
X1321321Y976347D03*
X1315771Y973143D03*
X1319471D03*
X1328720Y969939D03*
X1330570Y973143D03*
X1326871D03*
X1328720Y982756D03*
X1328721Y976347D03*
X1315771Y979552D03*
X1318053Y1009297D03*
Y1002888D03*
X1327304Y1006093D03*
X1331003D03*
X1329153Y1009297D03*
Y1002888D03*
X1323603Y999684D03*
X1321753Y1009297D03*
X1319903Y1006093D03*
X1321753Y1002888D03*
X1323603Y1012501D03*
X1329153Y1028523D03*
Y1015705D03*
X1318053Y1022114D03*
Y1015705D03*
X1329153Y1022114D03*
X1325453Y1015705D03*
X1323603Y1018910D03*
X1321753Y1028523D03*
X1319903Y1018910D03*
X1321753Y1022114D03*
Y1015705D03*
X1319903Y1031727D03*
X1323603D03*
X1329153Y1034931D03*
Y1047749D03*
X1318053Y1041340D03*
X1319903Y1038136D03*
X1329153Y1041340D03*
X1325453Y1034931D03*
X1323603Y1038136D03*
X1321753Y1041340D03*
X1319903Y1044544D03*
X1321753Y1047749D03*
X1329153Y1060565D03*
Y1054157D03*
X1325453D03*
X1319903Y1057361D03*
Y1050952D03*
X1323603D03*
Y1057361D03*
X1321753Y1060565D03*
X1319903Y1063770D03*
X1329153Y1073383D03*
X1319903Y1076587D03*
Y1070178D03*
X1316204Y1076587D03*
X1329153Y1066974D03*
X1323603Y1076587D03*
Y1070178D03*
X1325454Y1073383D03*
X1321753Y1066974D03*
X1329153Y1079791D03*
X1321753D03*
X1318053D03*
X1329153Y1086200D03*
Y1092608D03*
X1325452Y1092609D03*
X1323603Y1089404D03*
X1321752Y1086200D03*
X1319902Y1082995D03*
X1316202D03*
X1316203Y1095813D03*
X1331003Y1108630D03*
X1329153Y1099017D03*
X1323603Y1108630D03*
X1316203D03*
Y1102221D03*
X1325453Y1099017D03*
X1323603Y1102221D03*
X1319903D03*
X1316203Y1115039D03*
X1331003D03*
X1327303Y1121447D03*
Y1115039D03*
X1325453Y1124651D03*
X1325454Y1118243D03*
X1321753D03*
X1319903Y1115039D03*
X1329152Y1137469D03*
X1329153Y1131060D03*
X1321752Y1137469D03*
X1325453Y1131060D03*
X1319903Y1134264D03*
X1344103Y155288D03*
X1342936Y159301D03*
X1335472Y161149D03*
X1346137Y168549D03*
X1342907Y166699D03*
X1332268D03*
X1346137Y164849D03*
X1339727D03*
X1335472Y168549D03*
X1339568Y176028D03*
X1339727Y179649D03*
X1342937Y181499D03*
Y185199D03*
X1346137Y172249D03*
X1335472D03*
X1339727Y190749D03*
X1342937Y188899D03*
X1334252Y195474D03*
X1346137Y194449D03*
Y190749D03*
X1346147Y209248D03*
X1332262Y218499D03*
Y214799D03*
X1332285Y226210D03*
X1342937Y222199D03*
X1332267D03*
X1343521Y841467D03*
X1336121D03*
X1345371Y851380D03*
X1341671D03*
X1337971D03*
X1334271D03*
X1345371Y864197D03*
X1343521Y854584D03*
X1341671Y864197D03*
X1337971D03*
X1336121Y854584D03*
X1334271Y864197D03*
X1343521Y867401D03*
X1336121D03*
X1345371Y877014D03*
X1343521Y880219D03*
X1341671Y877014D03*
X1337971D03*
X1334271D03*
X1332420Y886627D03*
X1345371Y896240D03*
Y889832D03*
X1341671Y896240D03*
Y889832D03*
X1337970Y896240D03*
X1337971Y889832D03*
X1336121Y893036D03*
X1334270Y889832D03*
X1332420Y905853D03*
X1341671Y909057D03*
Y902649D03*
X1336120Y912262D03*
X1334270Y909057D03*
X1334271Y902649D03*
X1347221Y912262D03*
X1345371Y915466D03*
X1341671D03*
X1337970D03*
X1332421Y925079D03*
X1341671Y928283D03*
Y921875D03*
X1334270Y928283D03*
X1334271Y921875D03*
X1347220Y918670D03*
X1336120Y931488D03*
X1347221D03*
X1341671Y947509D03*
X1334270D03*
X1334271Y941100D03*
X1332421Y944304D03*
X1345371Y934691D03*
X1341671D03*
X1337970D03*
X1337971Y953917D03*
X1345371D03*
X1341671D03*
Y960326D03*
X1347220Y957122D03*
X1343520Y963530D03*
X1339821D03*
X1341670Y966735D03*
X1347221Y950713D03*
X1334271Y960326D03*
X1336121Y957122D03*
X1332421Y963530D03*
X1334270Y966735D03*
X1336120Y950713D03*
X1347221Y969939D03*
X1337970Y973143D03*
X1347220Y976347D03*
X1345371Y973143D03*
X1341671Y979552D03*
Y973143D03*
X1336120Y969939D03*
X1336121Y976347D03*
X1334271Y979552D03*
X1332421Y982756D03*
X1342104Y999684D03*
Y1006093D03*
X1338403D03*
X1336553Y1009297D03*
X1336554Y1002888D03*
X1334704Y999684D03*
X1347654Y1009297D03*
X1342103Y1012501D03*
X1334703D03*
X1332854Y1015705D03*
X1345804Y1025318D03*
X1343953Y1015705D03*
X1342104Y1025318D03*
Y1018910D03*
X1340254Y1015705D03*
X1336553Y1028523D03*
X1338403Y1025318D03*
X1336554Y1022114D03*
X1334704Y1018910D03*
X1347653Y1028523D03*
Y1022114D03*
X1342104Y1031727D03*
X1334703D03*
X1332854Y1034931D03*
X1345804Y1044544D03*
X1342104D03*
Y1038136D03*
X1338403Y1044544D03*
X1336554Y1041340D03*
X1334704Y1038136D03*
X1347653Y1041340D03*
X1336553Y1047749D03*
X1347653D03*
X1332854Y1054157D03*
X1342104Y1057361D03*
Y1050952D03*
X1336554Y1060565D03*
X1334704Y1057361D03*
X1334703Y1050952D03*
X1347653Y1060565D03*
X1345804Y1063770D03*
X1342104D03*
X1338403D03*
X1332854Y1073383D03*
X1342104Y1070178D03*
X1336553Y1066974D03*
X1334703Y1070178D03*
X1334704Y1076587D03*
X1347654Y1066974D03*
X1336554Y1079791D03*
X1347653D03*
X1345804Y1082995D03*
X1342104Y1089404D03*
Y1082995D03*
X1338403D03*
X1336553Y1086200D03*
X1334703Y1089404D03*
X1332854Y1092608D03*
X1347654Y1086200D03*
X1342104Y1095813D03*
X1334703D03*
X1342104Y1102221D03*
X1338404D03*
X1336553Y1099017D03*
X1332853Y1105426D03*
Y1099017D03*
X1347654Y1105426D03*
Y1099017D03*
X1340254Y1111834D03*
X1332854D03*
X1347654D03*
X1343953Y1118243D03*
X1340253D03*
X1338403Y1115039D03*
X1336553Y1118243D03*
X1332853D03*
X1347653D03*
X1342104Y1127856D03*
X1334703D03*
X1343953Y1131060D03*
X1342103Y1140973D03*
X1340254Y1131060D03*
X1336554D03*
X1334703Y1140973D03*
X1332854Y1131060D03*
X1347653D03*
X1349351Y159298D03*
X1355758D03*
X1355761Y162998D03*
X1358865Y166732D03*
Y158854D03*
Y162793D03*
X1349351Y166698D03*
X1352557Y164848D03*
X1358865Y170671D03*
Y174603D03*
Y182484D03*
Y178544D03*
X1355761Y170398D03*
X1352557Y179648D03*
X1358371Y188778D03*
X1358865Y195240D03*
Y199180D03*
X1349351Y196298D03*
X1352561Y194448D03*
X1352551Y190748D03*
X1349345Y188898D03*
X1355761Y192598D03*
X1358865Y207060D03*
Y203120D03*
Y213994D03*
Y217934D03*
X1352560Y205549D03*
X1355765Y207399D03*
X1349351Y214798D03*
X1352561Y212948D03*
X1349351Y211098D03*
Y222198D03*
X1358321Y841467D03*
X1350921D03*
X1360171Y851380D03*
X1356471D03*
X1352771D03*
X1349071D03*
X1363871D03*
X1360171Y864197D03*
X1358321Y854584D03*
X1356471Y864197D03*
X1352771D03*
X1350921Y854584D03*
X1349071Y864197D03*
X1363871D03*
X1358321Y867401D03*
X1350921D03*
X1360171Y877014D03*
X1358321Y880219D03*
X1356471Y877014D03*
X1352771D03*
X1350921Y880219D03*
X1349071Y877014D03*
X1363871D03*
X1360171Y889832D03*
X1356471D03*
X1354621Y893036D03*
X1352771Y889832D03*
X1349071D03*
X1363871Y896240D03*
Y889832D03*
X1362021Y899445D03*
X1354620D03*
X1362020Y912262D03*
X1360170Y909057D03*
X1360171Y902649D03*
X1358321Y905853D03*
X1354620Y912262D03*
Y905853D03*
X1350920D03*
X1349071Y909057D03*
X1349070Y902649D03*
X1363870Y915466D03*
X1362021Y918670D03*
X1360170Y928283D03*
X1360171Y921875D03*
X1358321Y925079D03*
X1354620D03*
Y918670D03*
X1350920Y925079D03*
X1349071Y928283D03*
X1349070Y921875D03*
X1362020Y931488D03*
X1360171Y941100D03*
X1358321Y944304D03*
X1354620D03*
X1360170Y947509D03*
X1350920Y944304D03*
X1349071Y947509D03*
X1349070Y941100D03*
X1362021Y937896D03*
X1354620D03*
X1363870Y934691D03*
X1363871Y953917D03*
X1360171Y960326D03*
X1362021Y957122D03*
X1354620D03*
X1358321Y963530D03*
X1354620D03*
X1360170Y966735D03*
X1354620Y950713D03*
X1362020D03*
X1349070Y960326D03*
X1350920Y963530D03*
X1349071Y966735D03*
X1362020Y969939D03*
X1354620D03*
X1363870Y973143D03*
X1362021Y976347D03*
X1360171Y979552D03*
X1358321Y982756D03*
X1356470Y973143D03*
X1354620Y982756D03*
X1354621Y976347D03*
X1350920Y982756D03*
X1349070Y979552D03*
X1352771Y973143D03*
X1351352Y996480D03*
X1349503Y999684D03*
X1362453Y1009297D03*
X1362454Y1002888D03*
X1360604Y999684D03*
X1355053Y1009297D03*
Y1002888D03*
X1360603Y1012501D03*
X1349504D03*
X1362453Y1028523D03*
X1362454Y1022114D03*
X1360604Y1018910D03*
X1358754Y1015705D03*
X1355053Y1028523D03*
Y1022114D03*
Y1015705D03*
X1351353D03*
X1349503Y1018910D03*
X1360603Y1031727D03*
X1349504D03*
X1362454Y1041340D03*
X1360604Y1038136D03*
X1358754Y1034931D03*
X1355053Y1041340D03*
Y1034931D03*
X1351353D03*
X1349503Y1038136D03*
X1362453Y1047749D03*
X1355053D03*
X1362454Y1060565D03*
X1360604Y1057361D03*
X1360603Y1050952D03*
X1358754Y1054157D03*
X1355053D03*
X1351353D03*
X1349503Y1057361D03*
X1349504Y1050952D03*
X1362453Y1066974D03*
X1360604Y1076587D03*
X1360603Y1070178D03*
X1358754Y1073383D03*
X1355053D03*
Y1066974D03*
X1351353Y1073383D03*
X1349503Y1076587D03*
X1349504Y1070178D03*
X1362453Y1079791D03*
X1355053D03*
X1362453Y1086200D03*
X1360603Y1089404D03*
X1358753Y1092608D03*
X1355053D03*
Y1086200D03*
X1351353Y1092608D03*
X1349504Y1089404D03*
X1360604Y1095813D03*
X1349504D03*
X1362454Y1099017D03*
X1360604Y1102221D03*
X1356904Y1108630D03*
X1355053Y1099017D03*
X1353204Y1102221D03*
X1349503Y1108630D03*
Y1102221D03*
X1362453Y1118243D03*
X1360603Y1115039D03*
X1358753Y1118243D03*
X1355053D03*
X1353203Y1115039D03*
X1351353Y1118243D03*
X1349503Y1115039D03*
X1356903Y1127856D03*
X1349503D03*
X1362453Y1131060D03*
X1358753D03*
X1356903Y1140973D03*
X1355053Y1131060D03*
X1351353D03*
X1349503Y1140973D03*
X1373121Y841467D03*
X1365721D03*
X1378671Y851380D03*
X1374971D03*
X1371271D03*
X1367571D03*
X1378671Y864197D03*
X1374971D03*
X1373121Y854584D03*
X1371271Y864197D03*
X1367571D03*
X1365721Y854584D03*
X1373121Y867401D03*
X1365721D03*
X1378671Y877014D03*
X1374971D03*
X1373121Y880219D03*
X1371271Y877014D03*
X1367571D03*
X1365721Y880219D03*
X1378671Y889832D03*
X1374971D03*
X1371271Y896240D03*
Y889832D03*
X1367570Y896240D03*
X1367571Y889832D03*
X1365721Y893036D03*
X1374971Y909057D03*
X1374970Y902649D03*
X1373121Y912262D03*
X1367571Y909057D03*
Y902649D03*
X1371271Y915466D03*
X1367571D03*
X1376820Y925079D03*
X1374971Y928283D03*
X1374970Y921875D03*
X1373120Y918670D03*
X1367571Y928283D03*
Y921875D03*
X1376820Y937896D03*
X1374970Y941100D03*
X1371271Y934691D03*
X1367571Y941100D03*
Y934691D03*
X1374971Y947509D03*
X1367571D03*
X1376820Y957122D03*
X1374970Y960326D03*
X1373120Y957122D03*
X1373121Y950713D03*
X1371271Y953917D03*
X1367571Y960326D03*
Y953917D03*
X1376820Y963530D03*
X1374971Y966735D03*
X1367571D03*
X1376820Y982756D03*
Y969939D03*
X1374970Y979552D03*
X1373120Y976347D03*
X1373121Y969939D03*
X1371271Y973143D03*
X1367571Y979552D03*
Y973143D03*
X1364303Y1006093D03*
X1377253Y1002888D03*
X1373554Y1009297D03*
X1373553Y1002888D03*
X1371704Y1006093D03*
X1368004D03*
Y999684D03*
X1375404Y1012501D03*
X1368003D03*
X1364303Y1025318D03*
X1375403Y1018910D03*
X1373553Y1028523D03*
Y1022114D03*
X1371704Y1025318D03*
X1369853Y1015705D03*
X1368004Y1025318D03*
Y1018910D03*
X1366154Y1015705D03*
X1375404Y1031727D03*
X1368004D03*
X1364303Y1044544D03*
X1375403Y1038136D03*
X1373553Y1041340D03*
X1371704Y1044544D03*
X1368004D03*
Y1038136D03*
X1373553Y1047749D03*
X1375403Y1057361D03*
X1375404Y1050952D03*
X1373553Y1060565D03*
X1368004Y1057361D03*
Y1050952D03*
X1364303Y1063770D03*
X1371704D03*
X1368004D03*
X1377253Y1073383D03*
X1375403Y1076587D03*
X1375404Y1070178D03*
X1373554Y1066974D03*
X1368004Y1076587D03*
Y1070178D03*
X1377253Y1079791D03*
X1373553D03*
X1364303Y1082995D03*
X1377254Y1092608D03*
X1377253Y1086200D03*
X1375404Y1089404D03*
X1373554Y1086200D03*
X1371704Y1082995D03*
X1368004Y1089404D03*
Y1082995D03*
X1379104Y1095813D03*
X1375403D03*
X1368004D03*
X1364304Y1108630D03*
Y1102221D03*
X1377253Y1105426D03*
X1375404Y1102221D03*
X1373554Y1099017D03*
X1371704Y1102221D03*
X1366153Y1105426D03*
X1373553Y1111834D03*
X1366153D03*
X1364303Y1115039D03*
X1377253Y1118243D03*
X1373553D03*
X1371703Y1115039D03*
X1369853Y1118243D03*
X1366153D03*
X1364303Y1127856D03*
X1379103D03*
X1371703D03*
X1364303Y1140973D03*
X1379103D03*
X1377253Y1131060D03*
X1373553D03*
X1371703Y1140973D03*
X1369853Y1131060D03*
X1366153D03*
X1380521Y841467D03*
X1395321D03*
X1387921D03*
X1393471Y851380D03*
X1389771D03*
X1386071D03*
X1382371D03*
X1380521Y854584D03*
X1395321D03*
X1393471Y864197D03*
X1389771D03*
X1387921Y854584D03*
X1386071Y864197D03*
X1382371D03*
X1380521Y867401D03*
X1395321D03*
X1387921D03*
X1380521Y880219D03*
X1395321D03*
X1393471Y877014D03*
X1389771D03*
X1387921Y880219D03*
X1386071Y877014D03*
Y870606D03*
X1382371Y877014D03*
X1395321Y893036D03*
X1393471Y889832D03*
X1389771D03*
X1387921Y893036D03*
X1386071Y889832D03*
X1384221Y893036D03*
X1382371Y889832D03*
X1386071Y902649D03*
X1380520Y912262D03*
Y905853D03*
X1395320Y912262D03*
X1395321Y905853D03*
X1393471Y902649D03*
X1389771D03*
X1386071Y909057D03*
Y915466D03*
X1380520Y918670D03*
X1395187Y926265D03*
X1395320Y918670D03*
X1386071Y921875D03*
X1381189Y930811D03*
Y938045D03*
X1381287Y946239D03*
Y948539D03*
X1381189Y935745D03*
X1390234Y942097D03*
X1381264Y965896D03*
Y963596D03*
X1390506Y971139D03*
X1392896D03*
X1381003Y981269D03*
Y978969D03*
Y986421D03*
X1381243Y992971D03*
Y995271D03*
X1381003Y988721D03*
X1381369Y1007156D03*
X1381373Y1004848D03*
X1393716Y1000059D03*
X1391326D03*
X1381128Y1022427D03*
X1381140Y1026821D03*
X1384466Y1034270D03*
Y1031970D03*
X1393904Y1044544D03*
X1384653Y1041340D03*
X1380953Y1047749D03*
X1388353D03*
X1380953Y1060565D03*
X1393904Y1050952D03*
X1392053Y1060565D03*
Y1054157D03*
X1388353Y1060565D03*
X1386504Y1050952D03*
X1384653Y1054157D03*
X1380953Y1066974D03*
X1395753Y1073383D03*
X1392053Y1066974D03*
X1386504Y1076587D03*
Y1070178D03*
X1382803Y1076587D03*
X1380953Y1079791D03*
X1388353D03*
X1393903Y1089404D03*
Y1082995D03*
X1392053Y1092608D03*
X1392054Y1086200D03*
X1388353Y1092608D03*
X1384653Y1086200D03*
X1386504Y1095813D03*
X1382804D03*
X1380954Y1105426D03*
X1393904Y1102221D03*
X1392054Y1099017D03*
X1390204Y1108630D03*
X1388353Y1099017D03*
X1386504Y1102221D03*
X1382803Y1108630D03*
Y1102221D03*
X1380954Y1111834D03*
X1380953Y1118243D03*
X1386503Y1115039D03*
X1384653Y1118243D03*
X1382803Y1115039D03*
X1386503Y1127856D03*
X1380953Y1131060D03*
X1386503Y1140973D03*
X1384653Y1131060D03*
X1408269Y844971D03*
X1402721Y841467D03*
X1397171Y851380D03*
X1408271D03*
X1404571D03*
X1400871D03*
X1397171Y864197D03*
X1408271D03*
X1404571D03*
X1402721Y854584D03*
X1400871Y864197D03*
X1410121Y854584D03*
Y867401D03*
X1402721D03*
X1397171Y877014D03*
X1410121Y880219D03*
X1408271Y877014D03*
X1404571D03*
X1402721Y880219D03*
X1400871Y877014D03*
X1397171Y889832D03*
X1410121Y893036D03*
X1408271Y889832D03*
X1404571D03*
X1402721Y893036D03*
X1400871Y889832D03*
Y902649D03*
X1397171D03*
X1408271D03*
X1404571Y909057D03*
Y902649D03*
Y915466D03*
X1410121Y925079D03*
Y931488D03*
X1403016Y949498D03*
Y947198D03*
X1406420Y937896D03*
X1404016Y936469D03*
X1410120Y937896D03*
X1403046Y963634D03*
Y965934D03*
Y978035D03*
Y980335D03*
Y992421D03*
Y994721D03*
Y1009174D03*
Y1006874D03*
Y1021962D03*
Y1019662D03*
X1397604Y1063770D03*
Y1082995D03*
Y1095813D03*
X1428620Y848176D03*
X1415669Y844971D03*
X1421220Y848176D03*
X1417520D03*
X1423070Y851380D03*
X1419370D03*
X1415671D03*
X1413822Y860993D03*
X1426771Y864197D03*
X1424921Y854584D03*
X1423071Y864197D03*
X1419371D03*
X1417521Y854584D03*
X1415671Y864197D03*
Y857789D03*
X1424921Y867401D03*
X1417521D03*
X1424921Y880219D03*
X1423071Y877014D03*
X1419371D03*
X1417521Y880219D03*
X1415671Y877014D03*
X1413820Y886627D03*
X1426771Y889832D03*
X1424921Y893036D03*
X1423071Y889832D03*
X1419371D03*
X1417521Y893036D03*
X1415671Y896240D03*
Y889832D03*
X1413821Y899445D03*
Y905853D03*
X1426771Y902649D03*
X1423071Y909057D03*
Y902649D03*
X1419371D03*
X1415670D03*
X1423071Y915466D03*
Y928283D03*
X1417520Y925079D03*
Y931488D03*
X1413820Y918670D03*
X1423071Y921875D03*
X1424920Y937896D03*
X1421220D03*
X1417520D03*
X1413820D03*
X1427203Y1044544D03*
X1425353Y1047749D03*
X1429053Y1060565D03*
X1423503Y1057361D03*
Y1050952D03*
Y1063770D03*
X1425353Y1073383D03*
X1423503Y1076587D03*
Y1070178D03*
X1429053Y1079791D03*
X1425353D03*
X1425354Y1086200D03*
X1423503Y1082995D03*
X1437871Y851380D03*
X1434171D03*
X1430470D03*
X1432321Y841467D03*
X1439721D03*
X1445271Y851380D03*
X1441571D03*
X1439721Y854584D03*
X1432321D03*
X1437871Y864197D03*
X1434171D03*
X1430471D03*
X1445271D03*
X1441571D03*
X1432321Y867401D03*
X1439721D03*
X1437871Y877014D03*
X1434171D03*
X1432321Y880219D03*
X1430471Y877014D03*
X1445271D03*
X1441571D03*
X1439721Y880219D03*
X1437871Y889832D03*
X1434171D03*
X1432321Y893036D03*
X1430471Y889832D03*
X1445271Y896240D03*
X1439721Y893036D03*
X1445271Y889832D03*
X1441571D03*
X1437871Y902649D03*
X1434171D03*
X1432320Y905853D03*
X1430471Y902649D03*
X1441571D03*
Y909057D03*
Y915466D03*
X1430244Y931358D03*
Y933658D03*
X1432320Y918670D03*
X1430575Y1022185D03*
Y1019885D03*
X1443541Y1036914D03*
X1436453Y1041340D03*
X1442003Y1044544D03*
X1432753Y1047749D03*
X1440153D03*
X1432753Y1054157D03*
X1442004Y1057361D03*
X1438304Y1050952D03*
X1434604Y1063770D03*
X1442004D03*
X1432753Y1073383D03*
X1430903Y1076587D03*
X1430904Y1070178D03*
X1443853Y1073383D03*
Y1066974D03*
X1438304Y1070178D03*
X1432754Y1079791D03*
X1443853D03*
X1434603Y1082995D03*
X1432753Y1086200D03*
X1436453Y1092608D03*
X1443854Y1086200D03*
X1440153D03*
X1443854Y1092608D03*
X1442003Y1108630D03*
Y1102221D03*
X1440154Y1099017D03*
X1443853Y1105426D03*
Y1111834D03*
X1454521Y841467D03*
X1447121D03*
X1460071Y851380D03*
X1452671D03*
X1456371D03*
X1448971D03*
X1460071Y864197D03*
X1456371D03*
X1454521Y854584D03*
X1452671Y864197D03*
X1447121Y854584D03*
X1448971Y864197D03*
X1454521Y867401D03*
X1447121D03*
X1460071Y877014D03*
X1456371D03*
X1454521Y880219D03*
X1452671Y877014D03*
X1448971D03*
X1448970Y870606D03*
X1447121Y880219D03*
Y873810D03*
X1456370Y896240D03*
X1456371Y889832D03*
X1454521Y893036D03*
X1447121D03*
X1460071Y889832D03*
X1452671D03*
X1448971D03*
X1458220Y899445D03*
X1460071Y909057D03*
X1458221Y912262D03*
X1450820Y905853D03*
X1460070Y902649D03*
X1452426Y930125D03*
X1460071Y928283D03*
X1458220Y918670D03*
X1456371Y921875D03*
X1460070D03*
X1452670D03*
X1450820Y918670D03*
X1458220Y931488D03*
X1452426Y934725D03*
X1454520Y944304D03*
X1452321Y945354D03*
Y947654D03*
X1460070Y941100D03*
X1458221Y944304D03*
X1458220Y937896D03*
X1456371Y934691D03*
X1460070Y947509D03*
X1452426Y962325D03*
Y960025D03*
Y964625D03*
X1460070Y960326D03*
X1458220Y957122D03*
X1458221Y950713D03*
X1460071Y966735D03*
X1452426Y966925D03*
X1452333Y977669D03*
X1452476Y980736D03*
X1458221Y969939D03*
X1460070Y979552D03*
X1458220Y976347D03*
X1452426Y996825D03*
Y994525D03*
Y989925D03*
Y987625D03*
X1452436Y1010499D03*
X1452426Y1006025D03*
Y1003725D03*
Y1012925D03*
X1460503Y999684D03*
X1458654Y1009297D03*
X1458653Y1002888D03*
X1460504Y1012501D03*
X1452416Y1022635D03*
X1452426Y1017525D03*
X1458653Y1028523D03*
Y1022114D03*
X1460503Y1018910D03*
Y1031727D03*
X1447424Y1036526D03*
X1449649Y1035928D03*
X1458653Y1041340D03*
X1458654Y1034931D03*
X1451253Y1041340D03*
X1460503Y1038136D03*
X1458653Y1047749D03*
X1447553D03*
X1460503Y1057361D03*
X1458653Y1060565D03*
X1456804Y1050952D03*
X1451253Y1060565D03*
X1447553Y1054157D03*
X1460504Y1050952D03*
X1460503Y1076587D03*
X1451253Y1066974D03*
X1449404Y1070178D03*
X1460504D03*
X1458654Y1066974D03*
X1454953Y1073383D03*
X1458653Y1079791D03*
X1454954D03*
X1451253D03*
X1445703Y1089404D03*
X1458654Y1086200D03*
X1456804Y1082995D03*
X1453104Y1089404D03*
X1449404Y1082995D03*
X1460504Y1089404D03*
X1445704Y1095813D03*
X1460504D03*
X1456803D03*
X1445704Y1102221D03*
X1458653Y1105426D03*
X1456804Y1108630D03*
X1454953Y1099017D03*
X1449404Y1108630D03*
X1453104Y1102221D03*
X1451254Y1099017D03*
X1447553D03*
X1458653Y1111834D03*
X1460504Y1108630D03*
X1451253Y1111834D03*
X1447553D03*
X1454953Y1105426D03*
X1445704Y1108630D03*
X1449404Y1102221D03*
X1458653Y1099017D03*
X1454953Y1111834D03*
X1453104Y1108630D03*
X1447553Y1105426D03*
X1451253D03*
X1460504Y1102221D03*
X1458653Y1118243D03*
X1456803Y1115039D03*
X1454953Y1118243D03*
X1453103Y1115039D03*
X1451253Y1118243D03*
X1460503Y1127856D03*
X1453103D03*
X1460504Y1115039D03*
X1449404D03*
X1458653Y1131060D03*
X1454953D03*
X1453103Y1140973D03*
X1451253Y1131060D03*
X1449403Y1134264D03*
X1460503Y1140973D03*
X1469321Y841467D03*
X1461921D03*
X1476721D03*
X1474871Y851380D03*
X1471171D03*
X1467471D03*
X1463771D03*
X1461921Y854584D03*
X1474871Y864197D03*
X1471171D03*
X1469321Y854584D03*
X1467471Y864197D03*
X1463771D03*
X1476721Y854584D03*
X1461921Y867401D03*
X1476721D03*
X1469321D03*
X1461921Y880219D03*
X1471171Y877014D03*
X1476721Y880219D03*
X1474871Y877014D03*
X1469321Y880219D03*
X1467471Y877014D03*
X1463771D03*
X1474871Y889832D03*
X1465621Y893036D03*
X1476721D03*
X1474871Y896240D03*
X1471171Y889832D03*
X1467471D03*
X1463771D03*
X1473021Y899445D03*
X1465620D03*
X1461920Y905853D03*
X1473020Y912262D03*
X1471171Y909057D03*
X1465620Y905853D03*
X1471171Y902649D03*
X1469321Y905853D03*
X1474870Y915466D03*
X1461920Y925079D03*
X1471170Y928283D03*
X1469321Y925079D03*
X1465620D03*
Y918670D03*
X1473021D03*
X1471171Y921875D03*
X1473020Y931488D03*
X1465620D03*
X1461920Y944304D03*
X1474871Y934691D03*
X1473021Y937896D03*
X1471171Y941100D03*
X1469321Y944304D03*
X1465620D03*
Y937896D03*
X1471170Y947509D03*
X1474871Y953917D03*
X1473021Y957122D03*
X1471171Y960326D03*
X1465620Y957122D03*
Y950713D03*
X1473020D03*
X1461920Y963530D03*
X1476721D03*
X1471170Y966735D03*
X1469321Y963530D03*
X1465620D03*
X1473021Y976347D03*
X1473020Y969939D03*
X1465620Y976347D03*
Y969939D03*
X1474870Y973143D03*
X1471171Y979552D03*
X1461920Y982756D03*
X1469321D03*
X1465620D03*
X1475303Y1006093D03*
X1473453Y1009297D03*
X1473454Y1002888D03*
X1471604Y999684D03*
X1466053Y1009297D03*
X1466054Y1002888D03*
X1467903Y1006093D03*
X1464204D03*
X1471603Y1012501D03*
X1462353Y1015705D03*
X1473453Y1028523D03*
X1466053D03*
Y1022114D03*
Y1015705D03*
X1477154D03*
X1475303Y1025318D03*
X1473453Y1022114D03*
X1471604Y1018910D03*
X1469754Y1015705D03*
X1471603Y1031727D03*
X1462353Y1034931D03*
X1473454Y1041340D03*
X1466053D03*
Y1034931D03*
X1475303Y1044544D03*
X1471604Y1038136D03*
X1469754Y1034931D03*
X1466053Y1047749D03*
X1473453D03*
X1462353Y1054157D03*
X1473453Y1060565D03*
X1471604Y1057361D03*
X1466053Y1060565D03*
Y1054157D03*
X1471603Y1050952D03*
X1469753Y1054157D03*
X1475304Y1063770D03*
X1462353Y1073383D03*
X1471604Y1076587D03*
X1469754Y1073383D03*
X1466053Y1066974D03*
X1473453D03*
X1471603Y1070178D03*
X1466053Y1073383D03*
X1473454Y1079791D03*
X1466053D03*
X1462353Y1092608D03*
X1475303Y1082995D03*
X1473453Y1086200D03*
X1469754Y1092608D03*
X1466053D03*
Y1086200D03*
X1471603Y1089404D03*
X1475304Y1095813D03*
X1471604D03*
X1467904D03*
X1462353Y1105426D03*
X1462354Y1099017D03*
X1475303Y1108630D03*
Y1102221D03*
X1473454Y1105426D03*
X1469753D03*
X1467904Y1102221D03*
X1464203D03*
X1473454Y1111834D03*
X1466053D03*
Y1099017D03*
X1471604Y1102221D03*
X1477153Y1099017D03*
X1469753D03*
X1473453D03*
X1466053Y1105426D03*
X1462353Y1111834D03*
X1467904Y1108630D03*
X1464204D03*
X1462353Y1118243D03*
X1477153D03*
X1475303Y1115039D03*
X1473453Y1118243D03*
X1471604Y1121447D03*
X1469754Y1118243D03*
X1466053D03*
X1475303Y1127856D03*
X1467903D03*
X1467904Y1115039D03*
X1471604D03*
X1462353Y1131060D03*
X1477153D03*
X1475303Y1140973D03*
X1473453Y1131060D03*
X1469753D03*
X1466053D03*
X1467903Y1140973D03*
X1491521Y841467D03*
X1484121D03*
X1478571Y851380D03*
X1482271D03*
X1489671D03*
X1485971D03*
X1493371D03*
X1478571Y864197D03*
X1491521Y854584D03*
X1489671Y864197D03*
X1485971D03*
X1482271D03*
X1493371D03*
X1491521Y867401D03*
X1484121D03*
Y854584D03*
X1478571Y877014D03*
X1491521Y880219D03*
X1485971Y877014D03*
X1484121Y880219D03*
X1489671Y877014D03*
X1482271D03*
X1493371D03*
X1478570Y896240D03*
X1478571Y889832D03*
X1491521Y893036D03*
X1482271Y889832D03*
X1489671D03*
X1485971D03*
X1482270Y896240D03*
X1480421Y893036D03*
X1493371Y889832D03*
X1491520Y899445D03*
X1484120D03*
X1478571Y909057D03*
Y902649D03*
X1491520Y912262D03*
X1487820Y905853D03*
X1485971Y909057D03*
X1484121Y912262D03*
X1491520Y905853D03*
X1485970Y902649D03*
X1478571Y915466D03*
X1482271D03*
X1478571Y928283D03*
Y921875D03*
X1491520Y925079D03*
Y918670D03*
X1487820Y925079D03*
X1485971Y928283D03*
X1485970Y921875D03*
X1484120Y918670D03*
X1491520Y931488D03*
X1484121D03*
X1478571Y941100D03*
Y934691D03*
X1491520Y944304D03*
Y937896D03*
X1487820Y944304D03*
X1485970Y941100D03*
X1482271Y934691D03*
X1478571Y947509D03*
Y960326D03*
Y953917D03*
X1491520Y957122D03*
Y950713D03*
X1485970Y960326D03*
X1484120Y957122D03*
X1482271Y953917D03*
X1484121Y950713D03*
X1478570Y966735D03*
X1491520Y963530D03*
X1485971Y966735D03*
X1487820Y963530D03*
X1480420D03*
X1478571Y979552D03*
Y973143D03*
X1491521Y976347D03*
X1491520Y969939D03*
X1484120Y976347D03*
X1484121Y969939D03*
X1489671Y973143D03*
X1485970Y979552D03*
X1482271Y973143D03*
X1493370D03*
X1491520Y982756D03*
X1487820D03*
X1479004Y999684D03*
X1486403D03*
X1484553Y1002888D03*
X1482704Y1006093D03*
X1479003Y1012501D03*
X1486404D03*
X1491953Y1009297D03*
Y1002888D03*
X1484554Y1009297D03*
X1479004Y1025318D03*
Y1018910D03*
X1491953Y1028523D03*
Y1022114D03*
X1484553Y1028523D03*
X1486403Y1018910D03*
X1484553Y1022114D03*
X1482704Y1025318D03*
X1480853Y1015705D03*
X1479004Y1031727D03*
X1486404D03*
X1488253Y1015705D03*
X1491953D03*
X1479004Y1044544D03*
Y1038136D03*
X1491953Y1034931D03*
Y1041340D03*
X1488253Y1034931D03*
X1486403Y1038136D03*
X1484553Y1041340D03*
X1482704Y1044544D03*
X1491953Y1047749D03*
X1484553D03*
X1479004Y1057361D03*
Y1050952D03*
X1491953Y1054157D03*
X1486404Y1057361D03*
X1484553Y1060565D03*
X1488253Y1054157D03*
X1486404Y1050952D03*
X1491953Y1060565D03*
X1479004Y1063770D03*
X1482704D03*
X1479004Y1076587D03*
Y1070178D03*
X1486404Y1076587D03*
Y1070178D03*
X1488253Y1073383D03*
X1484553Y1066974D03*
X1491953Y1073383D03*
Y1066974D03*
X1484553Y1079791D03*
X1491953D03*
X1479004Y1089404D03*
Y1082995D03*
X1488254Y1092608D03*
X1486404Y1089404D03*
X1484554Y1086200D03*
X1482704Y1082995D03*
X1491954Y1092608D03*
X1479004Y1095813D03*
X1490103D03*
X1493804D03*
X1479004Y1102221D03*
X1490104Y1108630D03*
Y1102221D03*
X1488254Y1099017D03*
X1484553D03*
X1482704Y1108630D03*
X1480853Y1099017D03*
X1491953Y1105426D03*
Y1111834D03*
X1493804Y1108630D03*
X1490103Y1115039D03*
X1488253Y1118243D03*
X1484553D03*
X1480853D03*
X1486403Y1115039D03*
X1491953Y1118243D03*
X1490103Y1127856D03*
X1482703D03*
X1493804Y1115039D03*
X1490103Y1140973D03*
X1488253Y1131060D03*
X1484553D03*
X1480853D03*
X1482703Y1140973D03*
X1491953Y1131060D03*
X1504471Y844671D03*
X1498921Y841467D03*
X1508171Y851380D03*
X1504471D03*
X1500771D03*
X1497071D03*
X1504471Y864197D03*
X1500771D03*
X1508170Y857789D03*
X1497071Y864197D03*
X1506321Y860993D03*
Y854584D03*
X1498921D03*
X1510021Y860993D03*
X1506320Y867401D03*
X1498921D03*
X1510021D03*
X1504471Y877014D03*
X1498921Y880219D03*
X1508171Y877014D03*
X1497071D03*
X1506321Y880219D03*
X1500771Y877014D03*
X1510021Y880219D03*
Y873810D03*
X1508170Y883423D03*
X1508171Y889832D03*
X1504471Y896240D03*
Y889832D03*
X1500771D03*
X1508171Y896240D03*
X1502621Y893036D03*
X1500771Y896240D03*
X1497071Y889832D03*
X1510021Y893036D03*
X1498921Y899445D03*
X1510021D03*
X1495221Y905853D03*
X1504471Y902649D03*
X1498920Y912262D03*
X1497070Y909057D03*
X1497071Y902649D03*
X1508171Y915466D03*
X1504471D03*
X1500770D03*
X1504471Y909057D03*
X1510021Y912262D03*
X1495221Y925079D03*
X1504471Y921875D03*
X1497070Y928283D03*
X1498921Y918670D03*
X1497071Y921875D03*
X1498920Y931488D03*
X1504471Y928283D03*
X1510021Y918670D03*
X1510020Y931488D03*
X1495221Y944304D03*
X1504471Y941100D03*
Y934691D03*
X1500770D03*
X1498921Y937896D03*
X1497071Y941100D03*
X1497070Y947509D03*
X1508171Y934691D03*
X1510021Y937896D03*
X1504471Y947509D03*
Y960326D03*
Y953917D03*
X1500771D03*
X1498921Y957122D03*
X1497071Y960326D03*
X1498920Y950713D03*
X1495221Y963530D03*
X1497070Y966735D03*
X1502621Y963530D03*
X1510021Y957122D03*
X1508171Y953917D03*
X1510021Y950713D03*
X1506320Y963530D03*
X1504471Y966735D03*
Y979552D03*
Y973143D03*
X1498921Y976347D03*
X1498920Y969939D03*
X1500770Y973143D03*
X1497071Y979552D03*
X1510021Y976347D03*
X1495221Y982756D03*
X1510043Y980606D03*
X1510021Y969939D03*
X1508171Y973143D03*
X1497503Y1012501D03*
Y999684D03*
X1504904Y1006093D03*
Y999684D03*
X1501203Y1006093D03*
X1499353Y1009297D03*
X1499354Y1002888D03*
X1510453Y1009297D03*
Y1002888D03*
X1508603Y1006093D03*
X1504903Y1012501D03*
X1504904Y1025318D03*
X1499353Y1028523D03*
X1501203Y1025318D03*
X1504904Y1031727D03*
X1497503D03*
X1495654Y1015705D03*
X1497504Y1018910D03*
X1499353Y1022114D03*
X1503054Y1015705D03*
X1504904Y1018910D03*
X1506753Y1015705D03*
X1510453Y1028523D03*
X1510452Y1022114D03*
X1508603Y1025318D03*
X1504904Y1044544D03*
X1501203D03*
X1499354Y1041340D03*
X1497504Y1038136D03*
X1495654Y1034931D03*
X1508604Y1044544D03*
X1499353Y1047749D03*
X1504904Y1038136D03*
X1510453Y1041340D03*
Y1047749D03*
X1504904Y1057361D03*
Y1050952D03*
X1499354Y1060565D03*
X1497504Y1057361D03*
X1497503Y1050952D03*
X1495654Y1054157D03*
X1504904Y1063770D03*
X1501203D03*
X1510453Y1060565D03*
X1508604Y1063770D03*
X1504904Y1076587D03*
Y1070178D03*
X1497504Y1076587D03*
X1497503Y1070178D03*
X1495654Y1073383D03*
X1499353Y1066974D03*
X1499354Y1079791D03*
X1510453Y1066974D03*
Y1079791D03*
X1499353Y1086200D03*
X1497503Y1089404D03*
X1495653Y1092608D03*
X1504904Y1089404D03*
Y1082995D03*
X1501203D03*
X1508604Y1082996D03*
X1510453Y1086200D03*
X1504903Y1095813D03*
X1503053Y1105426D03*
X1497503Y1102221D03*
X1495653Y1105426D03*
X1495654Y1099017D03*
X1508603Y1108630D03*
X1506754Y1111834D03*
X1499353D03*
X1503053Y1099017D03*
X1510453D03*
X1508602Y1102221D03*
X1497504Y1108630D03*
X1501204D03*
X1510453Y1111834D03*
X1499353Y1105426D03*
X1510453D03*
X1504904Y1108630D03*
X1495653Y1111834D03*
X1503053D03*
X1506753Y1124651D03*
Y1118243D03*
X1504904Y1121447D03*
X1499353Y1118243D03*
X1497503Y1115039D03*
X1495653Y1118243D03*
X1508603Y1115039D03*
X1504904Y1127856D03*
X1497503D03*
X1501204Y1115039D03*
X1504904D03*
X1506754Y1137469D03*
X1506753Y1131060D03*
X1503053D03*
X1499353D03*
X1495653D03*
X1504904Y1134264D03*
X1497503Y1140973D03*
X1510453Y1131060D03*
X1511871Y844671D03*
X1513722Y848176D03*
X1511871Y851380D03*
X1521121Y860993D03*
Y854584D03*
X1515570Y864197D03*
X1513721Y854584D03*
Y860993D03*
X1521121Y867401D03*
X1517421D03*
X1513721D03*
X1511871Y870606D03*
X1522971D03*
X1517421Y873810D03*
X1511871Y883423D03*
X1517421Y880219D03*
X1522971Y883423D03*
X1511871Y889832D03*
X1513721Y893036D03*
X1517421Y886627D03*
X1521121D03*
X1513721D03*
X1526671Y889832D03*
X1513721Y899445D03*
X1524821Y912262D03*
X1511871Y909057D03*
Y902649D03*
X1513721Y912262D03*
X1515571Y909057D03*
X1524821Y905853D03*
X1513721D03*
X1519271Y909057D03*
X1511871Y921875D03*
X1513721Y918670D03*
X1524820Y931488D03*
X1513720D03*
X1511871Y941100D03*
X1513721Y937896D03*
X1511871Y947509D03*
X1519271D03*
X1515571D03*
X1511871Y960326D03*
X1513721Y957122D03*
Y950713D03*
X1511871Y966735D03*
X1513721Y963530D03*
X1515571Y979552D03*
X1513721Y982756D03*
X1511871Y973143D03*
X1517421Y969939D03*
X1515571Y973143D03*
X1516004Y1006092D03*
X1516003Y999684D03*
X1512303D03*
Y1006093D03*
X1519705Y1006092D03*
X1525396Y1000648D03*
X1512303Y1012501D03*
Y1025318D03*
X1516003Y1018910D03*
X1517854Y1015705D03*
X1525254D03*
X1521554D03*
X1514154D03*
X1512303Y1018910D03*
Y1031727D03*
X1525254Y1034931D03*
X1521554D03*
X1516004Y1044544D03*
X1516003Y1038136D03*
X1517853Y1034931D03*
X1514153D03*
X1512303Y1038136D03*
X1517853Y1054157D03*
X1514153D03*
X1512303Y1057361D03*
X1521553Y1054157D03*
X1514153Y1060565D03*
X1512303Y1050952D03*
X1525564Y1064850D03*
X1523404Y1070178D03*
X1514153Y1066974D03*
X1517853Y1073383D03*
X1521553Y1066974D03*
X1516003Y1076587D03*
X1512303D03*
X1512304Y1070178D03*
X1514153Y1073383D03*
X1523404Y1082996D03*
X1512304D03*
X1514153Y1092608D03*
X1512303Y1089404D03*
X1521553Y1092608D03*
X1523403Y1095813D03*
X1519703D03*
X1512303D03*
X1521554Y1105426D03*
X1517853D03*
X1516003Y1108630D03*
Y1102221D03*
X1512303D03*
X1517853Y1111834D03*
X1521553D03*
X1514153Y1105426D03*
X1512303Y1108630D03*
X1514153Y1111834D03*
X1519703Y1108630D03*
X1521553Y1124651D03*
Y1118243D03*
X1519704Y1115039D03*
X1516004D03*
X1514153Y1124651D03*
X1512303Y1115039D03*
X1517854Y1131560D03*
X1512304Y1134264D03*
X1527571Y979057D03*
X1526843Y972608D03*
X1527103Y1031726D03*
X1665141Y1051247D03*
X1724541D03*
G54D44*
X333834Y1062790D03*
X329632Y1092168D03*
X335344Y1097289D03*
X549719Y962436D03*
X548146Y965640D03*
X543729Y984866D03*
X1309976Y1062790D03*
X1305774Y1092168D03*
X1311486Y1097289D03*
X1337102Y206675D03*
X1525861Y962436D03*
X1524288Y965640D03*
X1519871Y984866D03*
X1879155Y468898D03*
Y716798D03*
X1889155Y468898D03*
Y716798D03*
X1900275Y840758D03*
X1910275D03*
X1921395Y-19332D03*
X1931395D03*
X1942395Y593048D03*
X1952395D03*
X1963362Y-19190D03*
X1973362D03*
X1984482Y593020D03*
X1994482D03*
X2005452Y-19180D03*
X2015452D03*
X2026452Y593200D03*
X2047419Y-19038D03*
X2036452Y593200D03*
X2057419Y-19038D03*
X2068539Y593172D03*
X2078539D03*
G54D53*
X717313Y-27626D03*
Y-21471D03*
Y-17597D03*
X717298Y-15082D03*
X717313Y-11442D03*
X717298Y-25111D03*
X717313Y-7568D03*
X717298Y-5053D03*
X834273Y2374D03*
X834258Y4889D03*
X834273Y22432D03*
Y8529D03*
Y12403D03*
X834258Y14918D03*
X834273Y18558D03*
X834258Y24947D03*
X1026705Y-27695D03*
Y-38224D03*
X1023437Y-38210D03*
X1026690Y-35709D03*
X1023422Y-35695D03*
X1026705Y-32069D03*
Y-17666D03*
X1026690Y-15151D03*
X1026705Y-11511D03*
X1026690Y-25180D03*
X1026705Y-21540D03*
X1026690Y4907D03*
X1026705Y2392D03*
X1026690Y-5122D03*
X1026705Y-7637D03*
Y-1482D03*
Y22450D03*
Y18576D03*
Y8547D03*
X1026690Y14936D03*
X1026705Y12421D03*
X1026690Y24965D03*
X1336024Y-27695D03*
Y-32069D03*
X1332741Y-35695D03*
X1336009Y-35709D03*
X1332756Y-38210D03*
X1336024Y-38224D03*
Y-11511D03*
X1336009Y-15151D03*
X1336024Y-17666D03*
Y-21540D03*
X1336009Y-25180D03*
X1336024Y2392D03*
X1336009Y4907D03*
X1336024Y-1482D03*
Y-7637D03*
X1336009Y-5122D03*
X1336024Y18576D03*
Y22450D03*
Y12421D03*
X1336009Y14936D03*
X1336024Y8547D03*
X1336009Y24965D03*
G54D63*
X918780Y1684890D03*
Y1694890D03*
Y1714890D03*
X928780Y1684890D03*
X938780D03*
X928780Y1694890D03*
X938780D03*
X928780Y1704890D03*
X938780D03*
X928780Y1714890D03*
X938780D03*
G54D73*
X1879155Y354948D03*
Y458898D03*
Y478898D03*
Y582848D03*
Y602848D03*
Y706798D03*
Y726798D03*
Y830748D03*
X1900275Y-9342D03*
X1889155Y354948D03*
Y458898D03*
Y478898D03*
X1900275Y582858D03*
X1889155Y582848D03*
Y602848D03*
Y706798D03*
X1900275Y726808D03*
X1889155Y726798D03*
X1900275Y830758D03*
X1889155Y830748D03*
X1900275Y850758D03*
Y954708D03*
X1910275Y-9342D03*
Y582858D03*
Y726808D03*
Y830758D03*
Y850758D03*
Y954708D03*
X1921395Y-9332D03*
X1931395D03*
Y582868D03*
X1921395D03*
X1931395Y602868D03*
X1921395D03*
Y1195068D03*
X1931395D03*
X1942395Y-9152D03*
Y583048D03*
Y603048D03*
Y1195248D03*
X1963362Y-9190D03*
X1952395Y-9152D03*
X1963362Y583010D03*
X1952395Y583048D03*
X1963362Y603010D03*
X1952395Y603048D03*
X1963362Y1195210D03*
X1952395Y1195248D03*
X1973362Y-9190D03*
Y583010D03*
Y603010D03*
Y1195210D03*
X1994482Y-9180D03*
X1984482D03*
Y583020D03*
X1994482D03*
X1984482Y603020D03*
X1994482D03*
Y1195220D03*
X1984482D03*
X2005452Y-9180D03*
X2015452D03*
Y583020D03*
X2005452D03*
X2015452Y603020D03*
X2005452D03*
Y1195220D03*
X2015452D03*
X2026452Y-9000D03*
Y583200D03*
Y603200D03*
Y1195400D03*
X2047419Y-9038D03*
X2036452Y-9000D03*
X2047419Y583162D03*
X2036452Y583200D03*
X2047419Y603162D03*
X2036452Y603200D03*
X2047419Y1195362D03*
X2036452Y1195400D03*
X2057419Y-9038D03*
Y583162D03*
Y603162D03*
Y1195362D03*
X2068539Y603172D03*
X2078539D03*
Y1195372D03*
X2068539D03*
G54D74*
X1879155Y468898D03*
Y716798D03*
X1889155Y468898D03*
X1900275Y592858D03*
X1889155Y716798D03*
X1900275Y840758D03*
X1910275Y592858D03*
Y840758D03*
X1921395Y1205068D03*
X1931395D03*
X1942395Y593048D03*
X1952395D03*
X1963362Y1205210D03*
X1984482Y593020D03*
X1973362Y1205210D03*
X1994482Y593020D03*
X2005452Y1205220D03*
X2015452D03*
X2026452Y593200D03*
X2036452D03*
X2047419Y1205362D03*
X2057419D03*
G54D50*
X676508Y224606D03*
G54D24*
X36399Y960892D03*
Y957546D03*
Y967585D03*
X52541Y964239D03*
X66099Y816995D03*
Y810302D03*
Y833727D03*
Y823688D03*
Y827034D03*
Y840420D03*
Y960892D03*
Y957546D03*
Y967585D03*
Y1221916D03*
Y1215223D03*
Y1238648D03*
Y1228609D03*
Y1231955D03*
Y1245341D03*
X82241Y813648D03*
Y806955D03*
Y820341D03*
Y830381D03*
Y823688D03*
Y837074D03*
Y964239D03*
Y1218570D03*
Y1211877D03*
Y1225263D03*
Y1241995D03*
Y1235302D03*
Y1228609D03*
X95799Y960892D03*
Y957546D03*
Y967585D03*
Y1054593D03*
X125499Y780184D03*
Y773491D03*
Y786877D03*
Y803609D03*
Y796916D03*
Y790223D03*
Y816995D03*
Y810302D03*
Y833727D03*
Y823688D03*
Y827034D03*
Y847113D03*
Y840420D03*
Y853806D03*
Y860499D03*
Y863845D03*
Y883924D03*
Y877231D03*
Y870538D03*
Y890617D03*
Y897310D03*
Y900656D03*
Y914042D03*
Y907349D03*
Y927428D03*
Y920735D03*
Y934121D03*
Y944160D03*
Y937467D03*
Y960892D03*
Y950853D03*
X111941Y964239D03*
X125499Y957546D03*
Y980971D03*
Y974278D03*
Y967585D03*
Y994357D03*
Y987664D03*
X111941Y1021129D03*
Y1024475D03*
X125499Y1027822D03*
Y1021129D03*
Y1047900D03*
Y1041207D03*
Y1034515D03*
X111941Y1051247D03*
X125499Y1054593D03*
Y1074672D03*
Y1067979D03*
Y1091404D03*
Y1081365D03*
Y1084711D03*
Y1098097D03*
Y1111483D03*
Y1104790D03*
Y1128215D03*
Y1118176D03*
Y1121522D03*
Y1141601D03*
Y1134908D03*
Y1148294D03*
Y1154987D03*
Y1158333D03*
Y1171719D03*
Y1165026D03*
Y1185105D03*
Y1178412D03*
Y1191798D03*
Y1208530D03*
Y1201837D03*
Y1195144D03*
Y1221916D03*
Y1215223D03*
Y1238648D03*
Y1228609D03*
Y1231955D03*
Y1245341D03*
X141641Y770144D03*
Y776837D03*
Y786877D03*
Y783530D03*
Y800263D03*
Y793570D03*
Y813648D03*
Y806955D03*
Y820341D03*
Y830381D03*
Y823688D03*
Y850459D03*
Y843766D03*
Y837074D03*
Y867192D03*
Y860499D03*
Y857152D03*
Y873885D03*
Y880577D03*
Y887270D03*
Y897310D03*
Y893963D03*
Y917389D03*
Y910696D03*
Y904003D03*
Y924081D03*
Y934121D03*
Y930774D03*
Y947507D03*
Y940814D03*
Y964239D03*
Y977625D03*
Y970932D03*
Y991011D03*
Y984318D03*
Y1021129D03*
Y1024475D03*
Y1031168D03*
Y1044554D03*
Y1037861D03*
Y1051247D03*
Y1071326D03*
Y1064633D03*
Y1078018D03*
Y1094751D03*
Y1088058D03*
Y1081365D03*
Y1108137D03*
Y1101444D03*
Y1124869D03*
Y1118176D03*
Y1114829D03*
Y1144948D03*
Y1138255D03*
Y1131562D03*
Y1161680D03*
Y1154987D03*
Y1151641D03*
Y1175066D03*
Y1168373D03*
Y1181759D03*
Y1191798D03*
Y1188452D03*
Y1205184D03*
Y1198491D03*
Y1218570D03*
Y1211877D03*
Y1225263D03*
Y1241995D03*
Y1235302D03*
Y1228609D03*
X155199Y960892D03*
Y957546D03*
Y967585D03*
Y1054593D03*
X171341Y964239D03*
Y1021129D03*
Y1024475D03*
Y1051247D03*
X184899Y780184D03*
Y773491D03*
Y786877D03*
Y803609D03*
Y796916D03*
Y790223D03*
Y816995D03*
Y810302D03*
Y833727D03*
Y823688D03*
Y827034D03*
Y847113D03*
Y840420D03*
Y853806D03*
Y860499D03*
Y863845D03*
Y883924D03*
Y877231D03*
Y870538D03*
Y890617D03*
Y897310D03*
Y900656D03*
Y914042D03*
Y907349D03*
Y927428D03*
Y920735D03*
Y934121D03*
Y944160D03*
Y937467D03*
Y960892D03*
Y950853D03*
Y957546D03*
Y980971D03*
Y974278D03*
Y967585D03*
Y994357D03*
Y987664D03*
Y1027822D03*
Y1021129D03*
Y1047900D03*
Y1041207D03*
Y1034515D03*
Y1054593D03*
Y1074672D03*
Y1067979D03*
Y1091404D03*
Y1081365D03*
Y1084711D03*
Y1098097D03*
Y1111483D03*
Y1104790D03*
Y1128215D03*
Y1118176D03*
Y1121522D03*
Y1141601D03*
Y1134908D03*
Y1148294D03*
Y1154987D03*
Y1158333D03*
Y1171719D03*
Y1165026D03*
Y1185105D03*
Y1178412D03*
Y1191798D03*
Y1208530D03*
Y1201837D03*
Y1195144D03*
Y1221916D03*
Y1215223D03*
Y1238648D03*
Y1228609D03*
Y1231955D03*
Y1245341D03*
X201041Y770144D03*
Y776837D03*
Y786877D03*
Y783530D03*
Y800263D03*
Y793570D03*
Y813648D03*
Y806955D03*
Y820341D03*
Y830381D03*
Y823688D03*
Y850459D03*
Y843766D03*
Y837074D03*
Y867192D03*
Y860499D03*
Y857152D03*
Y873885D03*
Y880577D03*
Y887270D03*
Y897310D03*
Y893963D03*
Y917389D03*
Y910696D03*
Y904003D03*
Y924081D03*
Y934121D03*
Y930774D03*
Y947507D03*
Y940814D03*
Y964239D03*
Y977625D03*
Y970932D03*
Y991011D03*
Y984318D03*
X201141Y1021129D03*
Y1024475D03*
Y1031168D03*
Y1044554D03*
Y1037861D03*
Y1051247D03*
Y1071326D03*
Y1064633D03*
Y1078018D03*
Y1094752D03*
Y1088059D03*
Y1081366D03*
Y1108137D03*
Y1101444D03*
X201041Y1124869D03*
X201141Y1118177D03*
Y1114830D03*
Y1144948D03*
Y1138255D03*
X201041Y1131562D03*
X201141Y1161680D03*
Y1154988D03*
Y1151641D03*
Y1175066D03*
Y1168373D03*
Y1181759D03*
Y1191799D03*
Y1188452D03*
Y1205184D03*
Y1198491D03*
Y1218570D03*
Y1211877D03*
Y1225263D03*
Y1241995D03*
Y1235302D03*
Y1228609D03*
X214599Y960892D03*
Y957546D03*
X244299Y883924D03*
Y890617D03*
Y897310D03*
Y900656D03*
Y914042D03*
Y907349D03*
Y960892D03*
Y957546D03*
Y1185105D03*
Y1178412D03*
Y1191798D03*
Y1208530D03*
Y1201837D03*
Y1195144D03*
X260441Y880577D03*
Y887270D03*
Y897310D03*
Y893963D03*
Y910696D03*
Y904003D03*
Y1175066D03*
Y1181759D03*
Y1191798D03*
Y1188452D03*
Y1205184D03*
Y1198491D03*
X337779Y880219D03*
X335928Y883423D03*
X337779Y893036D03*
X335928Y889832D03*
X334079Y886627D03*
X337779D03*
X350727Y851380D03*
X354427Y844971D03*
X348878Y848176D03*
X352578D03*
X350729Y857789D03*
X352578Y860993D03*
X354429Y857789D03*
X341479Y880219D03*
X343329Y883423D03*
X348878Y899445D03*
Y893036D03*
X350729Y889832D03*
X354429D03*
X341478Y893036D03*
X343328Y889832D03*
X347029Y896240D03*
X354429D03*
X341479Y886627D03*
X350729Y896240D03*
X345179Y886627D03*
X348878Y912262D03*
X350729Y909057D03*
X354429D03*
X350729Y902649D03*
X354429D03*
X347029Y915466D03*
X354429D03*
X350729D03*
X348879Y931488D03*
X350729Y928283D03*
X354429D03*
Y921875D03*
X350729D03*
X348878Y918670D03*
X350729Y941100D03*
X348878Y937896D03*
X354429Y941100D03*
X347029Y934691D03*
X354429D03*
X350729D03*
Y947509D03*
X354429D03*
X348878Y950713D03*
X350729Y960326D03*
X348878Y957122D03*
X354429Y960326D03*
X350729Y966735D03*
X354429D03*
X350729Y953917D03*
X354429D03*
X347030D03*
X350729Y979552D03*
X354429D03*
X348878Y976347D03*
X347029Y973143D03*
X348878Y969939D03*
X347461Y1006093D03*
X349311Y1002888D03*
X351161Y999684D03*
X354861D03*
X351161Y1012501D03*
X349311Y1009297D03*
X354861Y1012501D03*
X351162Y1031727D03*
X349311Y1028523D03*
X354861Y1031727D03*
X349311Y1022114D03*
X351161Y1018910D03*
X354861D03*
X347461Y1025318D03*
X354862D03*
X351162D03*
X349311Y1047749D03*
Y1041340D03*
X351161Y1038136D03*
X354861D03*
X347461Y1044544D03*
X354861D03*
X351161D03*
X349311Y1060565D03*
X351161Y1057361D03*
X354861D03*
X347461Y1063770D03*
X351161D03*
X354861D03*
X351161Y1050952D03*
X354861D03*
Y1070178D03*
X351162D03*
X349311Y1066974D03*
Y1079791D03*
X351161Y1076587D03*
X354861D03*
X351161Y1089404D03*
X349311Y1086200D03*
X354861Y1089404D03*
X347461Y1082995D03*
X354861D03*
X351161D03*
X341911Y1105426D03*
X343762Y1108630D03*
X345611Y1111834D03*
X351161Y1102221D03*
X349312Y1111834D03*
X353011Y1105426D03*
X345611D03*
X341912Y1111834D03*
X354861Y1102221D03*
X353012Y1111834D03*
X351162Y1108630D03*
X353011Y1124651D03*
X354861Y1127856D03*
X347461Y1115039D03*
X349312Y1137469D03*
X351161Y1134264D03*
X356279Y841467D03*
X361827Y844971D03*
X363679Y841467D03*
X369227Y844971D03*
X371079Y841467D03*
X358127Y844971D03*
X359978Y848176D03*
X365527Y844971D03*
X367378Y848176D03*
X356278Y854584D03*
X358129Y857789D03*
X363678Y854584D03*
X365529Y857789D03*
X371078Y854584D03*
X359978Y860993D03*
X361829Y857789D03*
X367378Y860993D03*
X369229Y857789D03*
X356278Y899445D03*
Y893036D03*
X358129Y896240D03*
X363678Y899445D03*
X367378D03*
X371078Y893036D03*
X356278Y912262D03*
X358129Y915466D03*
X363678Y912262D03*
X361829Y909057D03*
X367378Y912262D03*
X369229Y909057D03*
X361829Y902649D03*
X369229D03*
X359978Y905853D03*
X367378D03*
X363678D03*
X371078D03*
X356278Y931488D03*
X363678D03*
X356278Y918670D03*
X361829Y928283D03*
X367378Y931488D03*
X369229Y928283D03*
X361829Y921875D03*
X363678Y918670D03*
X369229Y921875D03*
X367378Y918670D03*
X359978Y925079D03*
X367378D03*
X363678D03*
X371078D03*
X356278Y937896D03*
X358129Y934691D03*
X361829Y941100D03*
X363678Y937896D03*
X369229Y941100D03*
X367378Y937896D03*
X361829Y947509D03*
X369229D03*
X367378Y944304D03*
X359978D03*
X371078D03*
X363678D03*
X356278Y950713D03*
Y957122D03*
X358129Y953917D03*
X361829Y966735D03*
X369229D03*
X359978Y963530D03*
X363678Y950713D03*
X367378D03*
X361829Y960326D03*
X363678Y957122D03*
X369229Y960326D03*
X367378Y957122D03*
X371078Y963530D03*
X359978Y982756D03*
X367378D03*
X363678D03*
X371078D03*
X369229Y979552D03*
X367378Y976347D03*
X361829Y979552D03*
X363678Y976347D03*
X356278D03*
Y969939D03*
X358129Y973143D03*
X363678Y969939D03*
X367378D03*
X358562Y1006093D03*
X356711Y1002888D03*
Y1009297D03*
X362262Y1012501D03*
X369662D03*
X364111Y1009297D03*
X367811D03*
X364111Y1002888D03*
X362262Y999684D03*
X371511Y1002888D03*
X369662Y999684D03*
X356711Y1028523D03*
Y1022114D03*
X362262Y1031727D03*
X364111Y1028523D03*
X369662Y1031727D03*
X367811Y1028523D03*
X358562Y1025318D03*
X360411Y1015705D03*
X371511D03*
X364111Y1022114D03*
X362262Y1018910D03*
X367811Y1022114D03*
X369662Y1018910D03*
X356711Y1047749D03*
Y1041340D03*
X364111D03*
X362262Y1038136D03*
X367811Y1041340D03*
X369662Y1038136D03*
X360411Y1034931D03*
X371511D03*
X364111D03*
X358562Y1044544D03*
X367811Y1034931D03*
X364111Y1047749D03*
X367811D03*
X356711Y1060565D03*
X358562Y1063770D03*
X364111Y1060565D03*
X362262Y1057361D03*
X367811Y1060565D03*
X369662Y1057361D03*
X362262Y1050952D03*
X369662D03*
X360411Y1054157D03*
X371511D03*
X364111D03*
X367811D03*
X356711Y1066974D03*
X367811Y1079791D03*
X369662Y1076587D03*
X362262Y1070178D03*
X364111Y1066974D03*
X369662Y1070178D03*
X367811Y1066974D03*
X356711Y1079791D03*
X364111D03*
X362262Y1076587D03*
X360411Y1073383D03*
X371511D03*
X364111D03*
X367811D03*
X356711Y1086200D03*
X358562Y1082995D03*
X362262Y1095813D03*
X369662D03*
X362262Y1089404D03*
X364111Y1086200D03*
X369662Y1089404D03*
X367811Y1086200D03*
X360411Y1092608D03*
X367811D03*
X364111D03*
X371511D03*
X364111Y1099017D03*
X367811D03*
X358561Y1121447D03*
X360412Y1124651D03*
X364111D03*
X367811D03*
X371511D03*
X356712D03*
X362262Y1127856D03*
X365962Y1121447D03*
X369662Y1127856D03*
X358561Y1134264D03*
X362261Y1140973D03*
X365962Y1134264D03*
X369661Y1140973D03*
X356712Y1137469D03*
X360412D03*
X364112D03*
X367812D03*
X371512D03*
X387727Y844971D03*
X376627D03*
X380327D03*
X384027D03*
X385879Y841467D03*
X372927Y844971D03*
X374778Y848176D03*
X378479Y841467D03*
X382178Y848176D03*
X387729Y857789D03*
X372929D03*
X378478Y854584D03*
X380329Y857789D03*
X384029D03*
X374778Y860993D03*
X376629Y857789D03*
X382178Y860993D03*
X385878Y854584D03*
X374778Y899445D03*
X382178D03*
Y893036D03*
X374778D03*
X385878D03*
X372929Y896240D03*
X380329D03*
X376629D03*
X384029D03*
X376629Y902649D03*
X380329D03*
X374778Y912262D03*
X376629Y909057D03*
X382178Y912262D03*
X380329Y909057D03*
X372929Y915466D03*
X380329D03*
X376629D03*
X384029D03*
X374778Y931488D03*
X376629Y928283D03*
X382178Y931488D03*
X380329Y928283D03*
X376629Y921875D03*
X374778Y918670D03*
X380329Y921875D03*
X382178Y918670D03*
X380329Y941100D03*
X382178Y937896D03*
X376629Y947509D03*
X380329D03*
X376629Y941100D03*
X374778Y937896D03*
X372929Y934691D03*
X380329D03*
X376629D03*
X384029D03*
X376629Y960326D03*
X374778Y957122D03*
X380329Y960326D03*
X382178Y957122D03*
X374778Y950713D03*
X382178D03*
X372929Y953917D03*
X380329D03*
X376629D03*
X384029D03*
X380329Y966735D03*
X376629D03*
X374778Y969939D03*
X382178D03*
X373362Y1006093D03*
X380762D03*
X377062D03*
X384462D03*
X375211Y1002888D03*
X377062Y999684D03*
X382611Y1002888D03*
X380762Y999684D03*
X377062Y1012501D03*
X375211Y1009297D03*
X380762Y1012501D03*
X382611Y1009297D03*
X377062Y1031727D03*
X375211Y1028523D03*
X380762Y1031727D03*
X382611Y1028523D03*
X375211Y1022114D03*
X377062Y1018910D03*
X382611Y1022114D03*
X380762Y1018910D03*
X377062Y1025318D03*
X384462D03*
X373360D03*
X380760D03*
X375211Y1047749D03*
X382611D03*
X375211Y1041340D03*
X377062Y1038136D03*
X382611Y1041340D03*
X380762Y1038136D03*
X373362Y1044544D03*
X380762D03*
X377062D03*
X384462D03*
X375211Y1060565D03*
X377062Y1057361D03*
X382611Y1060565D03*
X380762Y1057361D03*
X377062Y1050952D03*
X380762D03*
X373362Y1063770D03*
X384462D03*
X377062D03*
X380762D03*
Y1070178D03*
X382611Y1066974D03*
X377062Y1070178D03*
X375211Y1066974D03*
Y1079791D03*
X377062Y1076587D03*
X382611Y1079791D03*
X380762Y1076587D03*
X377062Y1089404D03*
X375211Y1086200D03*
X380762Y1089404D03*
X382611Y1086200D03*
X373362Y1082995D03*
X384462D03*
X377062D03*
X380762D03*
X386311Y1105426D03*
X382611Y1111834D03*
X375211Y1105426D03*
X377062Y1108630D03*
X380762Y1102221D03*
X378911Y1111834D03*
X384462Y1108630D03*
X386311Y1111834D03*
X378912Y1105426D03*
X375211Y1111834D03*
X382611Y1105426D03*
X375211Y1124651D03*
X378911D03*
X382611D03*
X386311D03*
X373362Y1121447D03*
X377062Y1127856D03*
X380762Y1121447D03*
X384462Y1127856D03*
X380762Y1115039D03*
X373362Y1134264D03*
X377061Y1140973D03*
X380762Y1134264D03*
X384461Y1140973D03*
X375212Y1137469D03*
X378912D03*
X382612D03*
X386312D03*
X391427Y844971D03*
X395127D03*
X398827D03*
X400679Y841467D03*
X389578Y848176D03*
X393279Y841467D03*
X396978Y848176D03*
X402527Y844971D03*
X393278Y854584D03*
X395129Y857789D03*
X400678Y854584D03*
X402529Y857789D03*
X389578Y860993D03*
X391429Y857789D03*
X396978Y860993D03*
X398829Y857789D03*
Y973143D03*
X400678Y976347D03*
X402529Y979552D03*
Y973143D03*
X390011Y1002888D03*
X388162Y999684D03*
X393711Y1002888D03*
X395562Y999684D03*
X402962Y1082995D03*
X402961Y1089404D03*
X390011Y1124651D03*
X395562Y1121447D03*
X397411Y1124651D03*
X401111D03*
X391862Y1127856D03*
X393711Y1124651D03*
X399262Y1127856D03*
X402962Y1121447D03*
X388162D03*
X391861Y1140973D03*
X395562Y1134264D03*
X399261Y1140973D03*
X402962Y1134264D03*
X388162D03*
X390012Y1137469D03*
X393712D03*
X397412D03*
X401112D03*
X406227Y844971D03*
X409927D03*
X413627D03*
X417327D03*
X404378Y848176D03*
X408079Y841467D03*
X411778Y848176D03*
X415479Y841467D03*
X419178Y848176D03*
X408078Y854584D03*
X409929Y857789D03*
X415478Y854584D03*
X417329Y857789D03*
X404378Y860993D03*
X406229Y857789D03*
X411778Y860993D03*
X413629Y857789D03*
X419178Y860993D03*
X417329Y883423D03*
X415478Y880219D03*
X413629Y883423D03*
X419178Y886627D03*
X408511Y1079791D03*
X406662Y1089404D03*
X410362D03*
X404811Y1086200D03*
X419611D03*
X414062Y1082995D03*
X410362D03*
X406662D03*
X408511Y1092608D03*
X414062Y1089404D03*
X419611Y1092608D03*
X412211Y1086200D03*
X404811Y1124651D03*
X408511D03*
X406662Y1127856D03*
X410362Y1121447D03*
X406661Y1140973D03*
X410362Y1134264D03*
X404812Y1137469D03*
X408512D03*
X421027Y844971D03*
X424727D03*
X428427D03*
X433978Y848176D03*
X435829Y844671D03*
X422879Y841467D03*
X426578Y848176D03*
X430278D03*
X422878Y854584D03*
X424729Y857789D03*
X430278Y854584D03*
X433979Y860993D03*
X421029Y857789D03*
X426578Y860993D03*
X428429Y857789D03*
X432129D03*
X435829D03*
X432129Y883423D03*
X430278Y880219D03*
X424729Y883423D03*
X422878Y880219D03*
X428429Y883423D03*
X421029D03*
X435829D03*
X433978Y886627D03*
X426578D03*
X421462Y1089404D03*
X423311Y1092608D03*
X427011D03*
X430710Y1086200D03*
X425162Y1082995D03*
Y1095813D03*
X430711Y1092608D03*
X423311Y1086200D03*
X428861Y1089404D03*
X427012Y1086200D03*
X450628Y844971D03*
X446927Y844671D03*
X452479Y841467D03*
X448778Y848176D03*
X443227Y844671D03*
X437678Y848176D03*
X437679Y854584D03*
X452478D03*
X450629Y857789D03*
X445078Y854584D03*
X443229Y857789D03*
X448779Y860993D03*
X446929Y857789D03*
X441378Y860993D03*
X452479Y880219D03*
X446929Y883423D03*
X445078Y880219D03*
X439529Y883423D03*
X437678Y880219D03*
X450629Y883423D03*
X443229D03*
X448778Y886627D03*
X441378D03*
X467279Y841467D03*
X463578Y848176D03*
X459879Y841467D03*
X458027Y844971D03*
X454327D03*
X469127D03*
X465427D03*
X461727D03*
X456178Y848176D03*
X467278Y854584D03*
X465429Y857789D03*
X459878Y854584D03*
X458029Y857789D03*
X469129D03*
X463578Y860993D03*
X461729Y857789D03*
X456178Y860993D03*
X454329Y857789D03*
X469129Y883423D03*
X467278Y880219D03*
X461729Y883423D03*
X459878Y880219D03*
X454329Y883423D03*
X465429D03*
X458029D03*
X463578Y886627D03*
X456178D03*
X483927Y844971D03*
X480227D03*
X476527D03*
X470978Y848176D03*
X482079Y841467D03*
X478378Y848176D03*
X474679Y841467D03*
X472827Y844971D03*
X482078Y854584D03*
X480229Y857789D03*
X474678Y854584D03*
X472829Y857789D03*
X483929D03*
X478378Y860993D03*
X476529Y857789D03*
X470978Y860993D03*
Y886627D03*
X484362Y1121447D03*
X480662Y1127856D03*
X476962Y1121447D03*
X473262Y1127856D03*
X469562Y1121447D03*
X482511Y1124651D03*
X478811D03*
X475111D03*
X471411D03*
X484362Y1134264D03*
X482512Y1137469D03*
X476962Y1134264D03*
X475112Y1137469D03*
X480661Y1140973D03*
X478812Y1137469D03*
X473261Y1140973D03*
X493178Y848176D03*
X489478Y841467D03*
X487627Y844971D03*
X500578Y848176D03*
X496878Y841467D03*
X495027Y844971D03*
X491327D03*
X485778Y848176D03*
X498727Y844971D03*
X489478Y854584D03*
X487629Y857789D03*
X500578Y860993D03*
X498729Y857789D03*
X495029D03*
X491329D03*
X485778Y860993D03*
X496878Y854584D03*
X493178Y860993D03*
X500578Y899445D03*
Y912262D03*
X498729Y909057D03*
Y902649D03*
X500578Y905853D03*
X496878D03*
X500578Y931488D03*
X498729Y921875D03*
X500578Y918670D03*
X498729Y928283D03*
X496878Y925079D03*
X500578D03*
X498729Y947509D03*
Y941100D03*
X500578Y937896D03*
X496878Y944304D03*
X500578D03*
Y950713D03*
Y957122D03*
X498729Y960326D03*
X487629Y979552D03*
X485778Y976347D03*
X491329Y979552D03*
X493178Y976347D03*
X500578Y982756D03*
X496878D03*
X498729Y979552D03*
X500578Y976347D03*
X501011Y1002888D03*
X499162Y999684D03*
Y1012501D03*
X501011Y1009297D03*
X497311Y1015705D03*
X499162Y1031727D03*
X501011Y1028523D03*
Y1022114D03*
X499162Y1018910D03*
X501011Y1041340D03*
X499162Y1038136D03*
X501011Y1047749D03*
Y1034931D03*
X497311D03*
X501011Y1060565D03*
X499162Y1057361D03*
Y1050952D03*
X501011Y1054157D03*
X497311D03*
X499162Y1070178D03*
X501011Y1066974D03*
Y1079791D03*
X499162Y1076587D03*
X497311Y1073383D03*
X501011D03*
X499162Y1089404D03*
X501011Y1086200D03*
X497311Y1092608D03*
X501011D03*
X488062Y1127856D03*
X499162Y1121447D03*
X495462Y1127856D03*
X491762Y1121447D03*
X489911Y1124651D03*
X486211D03*
X501011D03*
X497311D03*
X493611D03*
X493612Y1137469D03*
X488061Y1140973D03*
X501012Y1137469D03*
X495461Y1140973D03*
X491762Y1134264D03*
X489912Y1137469D03*
X486212D03*
X499162Y1134264D03*
X497312Y1137469D03*
X517227Y844971D03*
X511679Y841467D03*
X509827Y844971D03*
X504279Y841467D03*
X515378Y848176D03*
X513527Y844971D03*
X507978Y848176D03*
X506127Y844971D03*
X502427D03*
X517229Y857789D03*
X513529D03*
X509829D03*
X506129D03*
X515378Y860993D03*
X511678Y854584D03*
X507978Y860993D03*
X504278Y854584D03*
X502429Y857789D03*
X511678Y899445D03*
Y893036D03*
X507978D03*
X509829Y896240D03*
X517229D03*
X513529D03*
X504278Y899445D03*
X513529Y902649D03*
X517229D03*
X511678Y912262D03*
X513529Y909057D03*
X517229D03*
X513529Y915466D03*
X509829D03*
X517229D03*
X504278Y912262D03*
X506129Y909057D03*
Y902649D03*
X507978Y905853D03*
X504278D03*
X511678Y931488D03*
X513529Y928283D03*
X517229D03*
X506129D03*
Y921875D03*
X504278Y918670D03*
X513529Y921875D03*
X511678Y918670D03*
X517229Y921875D03*
X504278Y931488D03*
Y925079D03*
X507978D03*
X513529Y941100D03*
X511678Y937896D03*
X517229Y941100D03*
X513529Y934691D03*
X509829D03*
X517229D03*
X513529Y947509D03*
X517229D03*
X506129D03*
Y941100D03*
X504278Y937896D03*
X507978Y944304D03*
X504278D03*
X511678Y950713D03*
X513529Y960326D03*
X511678Y957122D03*
X517229Y960326D03*
Y966735D03*
X513529D03*
X504278Y950713D03*
X513529Y953917D03*
X517229D03*
X509829D03*
X504278Y957122D03*
X506129Y960326D03*
X507978Y982756D03*
X504278D03*
Y976347D03*
X506129Y979552D03*
X513529D03*
X517229D03*
X511678Y976347D03*
X509829Y973143D03*
X511678Y969939D03*
X517662Y1006093D03*
X513962D03*
X510262D03*
X517662Y1012501D03*
X504711Y1002888D03*
X506561Y999684D03*
X513962Y1012501D03*
X512111Y1009297D03*
X506562Y1012501D03*
X504711Y1009297D03*
X517661Y999684D03*
X512111Y1002888D03*
X513962Y999684D03*
Y1031727D03*
X512111Y1028523D03*
X517662Y1031727D03*
X512111Y1022114D03*
X513962Y1018910D03*
X517662D03*
X513962Y1025318D03*
X510262D03*
X517662D03*
X508411Y1015705D03*
X506562Y1031727D03*
X504711Y1028523D03*
Y1022114D03*
X506562Y1018910D03*
X504711Y1041340D03*
X506562Y1038136D03*
X512111Y1047749D03*
Y1041340D03*
X513962Y1038136D03*
X517662D03*
X504711Y1047749D03*
X510262Y1044544D03*
X508411Y1034931D03*
X513962Y1044544D03*
X517662D03*
X504711Y1034931D03*
X512111Y1060565D03*
X513962Y1057361D03*
X517662D03*
X510262Y1063770D03*
X513962D03*
X517662D03*
X513962Y1050952D03*
X517662D03*
X504711Y1060565D03*
X506562Y1057361D03*
Y1050952D03*
X508411Y1054157D03*
X504711D03*
X517662Y1070178D03*
X513962D03*
X512111Y1066974D03*
X504711Y1079791D03*
X506562Y1076587D03*
Y1070178D03*
X504711Y1066974D03*
X512111Y1079791D03*
X513962Y1076587D03*
X517662D03*
X508411Y1073383D03*
X504711D03*
X513962Y1089404D03*
X512111Y1086200D03*
X517662Y1089404D03*
X513962Y1082995D03*
X510262D03*
X517662D03*
X510262Y1095813D03*
X506561D03*
X506562Y1089404D03*
X504711Y1086200D03*
X508411Y1092608D03*
X504711D03*
X517662Y1102221D03*
X515811Y1099017D03*
X517662Y1127856D03*
X513962Y1121447D03*
X510262Y1127856D03*
X506562Y1121447D03*
X502862Y1127856D03*
X515811Y1124651D03*
X512111D03*
X508411D03*
X504711D03*
X517661Y1140973D03*
X513962Y1134264D03*
X512112Y1137469D03*
X506562Y1134264D03*
X504712Y1137469D03*
X515812D03*
X510261Y1140973D03*
X508412Y1137469D03*
X502861Y1140973D03*
X532028Y844671D03*
X526478Y848176D03*
X524627Y844971D03*
X519079Y841467D03*
X533878Y848176D03*
X530178D03*
X522778D03*
X520927Y844971D03*
X532029Y864197D03*
X533879Y854584D03*
X528329Y857789D03*
X522778Y860993D03*
X520929Y857789D03*
X526478Y854584D03*
X524629Y857789D03*
X519078Y854584D03*
X526479Y899445D03*
X530178D03*
X519078D03*
Y893036D03*
X522778D03*
X520929Y896240D03*
X530179Y912262D03*
X532029Y909057D03*
X524629Y902649D03*
X532029D03*
X526479Y912262D03*
X524629Y909057D03*
X526479Y905853D03*
X533879D03*
X522778D03*
X530179D03*
X519078Y912262D03*
X520929Y915466D03*
X526479Y931488D03*
X524629Y928283D03*
X530179Y931488D03*
X532029Y928283D03*
X524629Y921875D03*
X526479Y918670D03*
X532029Y921875D03*
X530179Y918670D03*
X526479Y925079D03*
X533879D03*
X522778D03*
X530179D03*
X519078Y931488D03*
Y918670D03*
X524629Y941100D03*
X526479Y937896D03*
X532029Y941100D03*
X530179Y937896D03*
X524629Y947509D03*
X532029D03*
X519078Y937896D03*
X533879Y944304D03*
X520929Y934691D03*
X526479Y944304D03*
X530178D03*
X522778D03*
X524629Y966735D03*
X532029D03*
X522778Y963530D03*
X526479Y950713D03*
X530178D03*
X532029Y960326D03*
X530178Y957122D03*
X524629Y960326D03*
X526479Y957122D03*
X533879Y963530D03*
X519078Y950713D03*
Y957122D03*
X520929Y953917D03*
X526479Y969939D03*
X530179D03*
X519078Y976347D03*
Y969939D03*
X520929Y973143D03*
X521362Y1006093D03*
X525062Y1012501D03*
X532461D03*
X526911Y1009297D03*
X530611D03*
X519511D03*
X519513Y1002888D03*
X530611D03*
X532461Y999684D03*
X526911Y1002888D03*
X525062Y999684D03*
X523211Y1015705D03*
X534311D03*
X525062Y1031727D03*
X526911Y1028523D03*
X532461Y1031727D03*
X530611Y1028523D03*
Y1022114D03*
X532461Y1018910D03*
X526911Y1022114D03*
X525062Y1018910D03*
X519511Y1028523D03*
Y1022114D03*
X521362Y1025318D03*
X526911Y1041340D03*
X525062Y1038136D03*
X530611Y1041340D03*
X532461Y1038136D03*
X526911Y1047749D03*
X530611D03*
X526911Y1034931D03*
X534311D03*
X523211D03*
X530611D03*
X519511Y1047749D03*
Y1041340D03*
X521362Y1044544D03*
X519511Y1060565D03*
X526911D03*
X525062Y1057361D03*
X530611Y1060565D03*
X532462Y1057361D03*
X525061Y1050952D03*
X532462Y1050953D03*
X523211Y1054157D03*
X521362Y1063770D03*
X534311Y1054157D03*
X526911D03*
X530611D03*
Y1079791D03*
X532462Y1076587D03*
X525062Y1070178D03*
X526911Y1066974D03*
X532462Y1070178D03*
X530611Y1066974D03*
X526911Y1079791D03*
X525062Y1076587D03*
X523211Y1073383D03*
X534311D03*
X526911D03*
X530611D03*
X519511Y1066974D03*
Y1079791D03*
X521362Y1095813D03*
X532461D03*
X525062D03*
Y1089404D03*
X526911Y1086200D03*
X532462Y1089404D03*
X530611Y1086200D03*
X526911Y1092608D03*
X534310D03*
X523211D03*
X530611D03*
X519511Y1086200D03*
X521362Y1082995D03*
X530611Y1099017D03*
X526911Y1124651D03*
X521362Y1121447D03*
X525062Y1127856D03*
X523211Y1124651D03*
X519511D03*
X532462Y1134264D03*
X525061Y1140973D03*
X523212Y1137469D03*
X534312D03*
X526912D03*
X521362Y1134264D03*
X519512Y1137469D03*
X543129Y851380D03*
X539429D03*
X535729Y864197D03*
X543128D03*
X546828D03*
X535729Y857789D03*
X543130D03*
X539429D03*
X541279Y860993D03*
Y854584D03*
X539429Y883423D03*
X537578Y880219D03*
X543129Y883423D03*
X544979Y880219D03*
X537578Y873810D03*
X539429Y870606D03*
X544979Y873810D03*
X543129Y870606D03*
X539428Y877014D03*
X546828D03*
X535729D03*
X543129D03*
X620799Y883924D03*
Y890617D03*
Y897310D03*
Y900656D03*
Y914042D03*
Y907349D03*
Y960892D03*
Y957546D03*
Y1185105D03*
Y1178412D03*
Y1191798D03*
Y1208530D03*
Y1201837D03*
Y1195144D03*
X636941Y880577D03*
Y887270D03*
Y897310D03*
Y893963D03*
Y910696D03*
Y904003D03*
Y1175066D03*
Y1181759D03*
Y1191798D03*
Y1188451D03*
Y1205184D03*
Y1198491D03*
X650499Y960892D03*
Y957546D03*
X680299Y780184D03*
Y773491D03*
Y786877D03*
Y803609D03*
Y796916D03*
Y790223D03*
Y816995D03*
Y810302D03*
Y833727D03*
Y823688D03*
Y827034D03*
Y847113D03*
Y840420D03*
Y853806D03*
Y860499D03*
Y863845D03*
Y883924D03*
Y877231D03*
Y870538D03*
Y890617D03*
Y897310D03*
Y900656D03*
Y914042D03*
Y907349D03*
Y927428D03*
Y920735D03*
Y934121D03*
Y944160D03*
Y937467D03*
Y960892D03*
Y950853D03*
Y957546D03*
Y980971D03*
Y974278D03*
Y967585D03*
Y994357D03*
Y987664D03*
X679999Y1027822D03*
X680299Y1021129D03*
X679999Y1047900D03*
Y1041207D03*
Y1034514D03*
Y1054593D03*
X680299Y1074672D03*
Y1067979D03*
Y1091404D03*
Y1081365D03*
Y1084711D03*
Y1098097D03*
Y1111483D03*
Y1104790D03*
Y1128215D03*
Y1118176D03*
Y1121522D03*
Y1141601D03*
Y1134908D03*
Y1148294D03*
Y1154987D03*
Y1158333D03*
Y1171719D03*
Y1165026D03*
Y1185105D03*
Y1178412D03*
Y1191798D03*
Y1208530D03*
Y1201837D03*
Y1195144D03*
Y1221916D03*
Y1215223D03*
Y1238648D03*
Y1228609D03*
Y1231955D03*
Y1245341D03*
X696441Y770144D03*
Y776837D03*
Y786877D03*
Y783530D03*
Y800263D03*
Y793570D03*
Y813648D03*
Y806955D03*
Y820341D03*
Y830381D03*
Y823688D03*
Y850459D03*
Y843766D03*
Y837074D03*
Y867192D03*
Y860499D03*
Y857152D03*
Y873885D03*
Y880577D03*
Y887270D03*
Y897310D03*
Y893963D03*
Y917389D03*
Y910696D03*
Y904003D03*
Y924081D03*
Y934121D03*
Y930774D03*
Y947507D03*
Y940814D03*
Y964239D03*
Y977625D03*
Y970932D03*
Y991011D03*
Y984318D03*
Y1021129D03*
Y1024475D03*
Y1031168D03*
X696141Y1044554D03*
Y1037861D03*
X696441Y1051247D03*
Y1071325D03*
Y1064633D03*
Y1078018D03*
Y1094751D03*
Y1088058D03*
Y1081365D03*
Y1108136D03*
Y1101444D03*
Y1124869D03*
Y1118176D03*
Y1114829D03*
Y1144947D03*
Y1138255D03*
Y1131562D03*
Y1161680D03*
Y1154987D03*
Y1151640D03*
Y1175066D03*
Y1168373D03*
Y1181758D03*
Y1191798D03*
Y1188451D03*
Y1205184D03*
Y1198491D03*
Y1218569D03*
Y1211877D03*
Y1225262D03*
Y1241995D03*
Y1235302D03*
Y1228609D03*
X709899Y960892D03*
Y957546D03*
X709999Y967585D03*
Y1054593D03*
X726141Y964239D03*
Y1021129D03*
Y1024475D03*
Y1051247D03*
X739699Y780184D03*
Y773491D03*
Y786877D03*
Y803609D03*
Y796916D03*
Y790223D03*
Y816995D03*
Y810302D03*
Y833727D03*
Y823688D03*
Y827034D03*
Y847113D03*
Y840420D03*
Y853806D03*
Y860499D03*
Y863845D03*
Y883924D03*
Y877231D03*
Y870538D03*
Y890617D03*
Y897310D03*
Y900656D03*
Y914042D03*
Y907349D03*
Y927428D03*
Y920735D03*
Y934121D03*
Y944160D03*
Y937467D03*
Y960892D03*
Y950853D03*
Y957546D03*
Y980971D03*
Y974278D03*
Y967585D03*
Y994357D03*
Y987664D03*
Y1027822D03*
Y1021129D03*
Y1047900D03*
Y1041207D03*
Y1034514D03*
Y1054593D03*
Y1074672D03*
Y1067979D03*
Y1091404D03*
Y1081365D03*
Y1084711D03*
Y1098097D03*
Y1111483D03*
Y1104790D03*
Y1128215D03*
Y1118176D03*
Y1121522D03*
Y1141601D03*
Y1134908D03*
Y1148294D03*
Y1154987D03*
Y1158333D03*
Y1171719D03*
Y1165026D03*
Y1185105D03*
Y1178412D03*
Y1191798D03*
Y1208530D03*
Y1201837D03*
Y1195144D03*
Y1221916D03*
Y1215223D03*
Y1238648D03*
Y1228609D03*
Y1231955D03*
Y1245341D03*
X755841Y770144D03*
Y776837D03*
Y786877D03*
Y783530D03*
Y800263D03*
Y793570D03*
Y813648D03*
Y806955D03*
Y820341D03*
Y830381D03*
Y823688D03*
Y850459D03*
Y843766D03*
Y837074D03*
Y867192D03*
Y860499D03*
Y857152D03*
Y873885D03*
Y880577D03*
Y887270D03*
Y897310D03*
Y893963D03*
Y917389D03*
Y910696D03*
Y904003D03*
Y924081D03*
Y934121D03*
Y930774D03*
Y947507D03*
Y940814D03*
Y964239D03*
Y977625D03*
X755741Y970932D03*
X755841Y991011D03*
Y984318D03*
Y1021129D03*
Y1024475D03*
Y1031168D03*
X755541Y1044554D03*
Y1037861D03*
X755841Y1051247D03*
X755676Y1071326D03*
X755741Y1064633D03*
X755841Y1078018D03*
Y1094751D03*
Y1088058D03*
Y1081365D03*
X755676Y1108137D03*
X755841Y1101444D03*
Y1124869D03*
Y1118176D03*
Y1114829D03*
Y1144947D03*
Y1138255D03*
Y1131562D03*
Y1161680D03*
Y1154987D03*
Y1151640D03*
Y1175066D03*
Y1168373D03*
X755676Y1181759D03*
X755841Y1191798D03*
X755676Y1188452D03*
X755841Y1205184D03*
Y1198491D03*
Y1218569D03*
Y1211877D03*
Y1225262D03*
Y1241995D03*
Y1235302D03*
Y1228609D03*
X769399Y960892D03*
Y957546D03*
Y967585D03*
Y1054593D03*
X785541Y964239D03*
Y1021129D03*
Y1024475D03*
Y1051247D03*
X799099Y816995D03*
Y810302D03*
Y833727D03*
Y823688D03*
Y827034D03*
Y840420D03*
Y960892D03*
Y957546D03*
Y967585D03*
Y1221916D03*
Y1215223D03*
Y1238648D03*
Y1228609D03*
Y1231955D03*
Y1245341D03*
X815241Y813648D03*
Y806955D03*
Y820341D03*
Y830381D03*
Y823688D03*
Y837074D03*
Y964239D03*
Y1218570D03*
Y1211877D03*
Y1225263D03*
Y1241995D03*
Y1235302D03*
Y1228609D03*
X828799Y960892D03*
Y957546D03*
Y967585D03*
X844941Y964239D03*
X1012541Y960892D03*
Y957546D03*
Y967585D03*
X1028683Y964239D03*
X1042241Y816995D03*
Y810302D03*
Y833727D03*
Y823688D03*
Y827034D03*
Y840420D03*
Y960892D03*
Y957546D03*
Y967585D03*
Y1221916D03*
Y1215223D03*
Y1238648D03*
Y1228609D03*
Y1231955D03*
Y1245341D03*
X1058383Y813648D03*
Y806955D03*
Y820341D03*
Y830381D03*
Y823688D03*
Y837074D03*
Y964239D03*
Y1218570D03*
Y1211877D03*
Y1225263D03*
Y1241995D03*
Y1235302D03*
Y1228609D03*
X1071941Y960892D03*
Y957546D03*
Y967585D03*
Y1054593D03*
X1101641Y780184D03*
Y773491D03*
Y786877D03*
Y803609D03*
Y796916D03*
Y790223D03*
Y816995D03*
Y810302D03*
Y833727D03*
Y823688D03*
Y827034D03*
Y847113D03*
Y840420D03*
Y853806D03*
Y860499D03*
Y863845D03*
Y883924D03*
Y877231D03*
Y870538D03*
Y890617D03*
Y897310D03*
Y900656D03*
Y914042D03*
Y907349D03*
Y927428D03*
Y920735D03*
Y934121D03*
Y944160D03*
Y937467D03*
Y960892D03*
Y950853D03*
X1088083Y964239D03*
X1101641Y957546D03*
Y980971D03*
Y974278D03*
Y967585D03*
Y994357D03*
Y987664D03*
X1088083Y1021129D03*
Y1024475D03*
X1101641Y1027822D03*
Y1021129D03*
Y1047900D03*
Y1041207D03*
Y1034515D03*
X1088083Y1051247D03*
X1101641Y1054593D03*
Y1074672D03*
Y1067979D03*
Y1091404D03*
Y1081365D03*
Y1084711D03*
Y1098097D03*
Y1111483D03*
Y1104790D03*
Y1128215D03*
Y1118176D03*
Y1121522D03*
Y1141601D03*
Y1134908D03*
Y1148294D03*
Y1154987D03*
Y1158333D03*
Y1171719D03*
Y1165026D03*
Y1185105D03*
Y1178412D03*
Y1191798D03*
Y1208530D03*
Y1201837D03*
Y1195144D03*
Y1221916D03*
Y1215223D03*
Y1238648D03*
Y1228609D03*
Y1231955D03*
Y1245341D03*
X1117783Y770144D03*
Y776837D03*
Y786877D03*
Y783530D03*
Y800263D03*
Y793570D03*
Y813648D03*
Y806955D03*
Y820341D03*
Y830381D03*
Y823688D03*
Y850459D03*
Y843766D03*
Y837074D03*
Y867192D03*
Y860499D03*
Y857152D03*
Y873885D03*
Y880577D03*
Y887270D03*
Y897310D03*
Y893963D03*
Y917389D03*
Y910696D03*
Y904003D03*
Y924081D03*
Y934121D03*
Y930774D03*
Y947507D03*
Y940814D03*
Y964239D03*
Y977625D03*
Y970932D03*
Y991011D03*
Y984318D03*
Y1021129D03*
Y1024475D03*
Y1031168D03*
Y1044554D03*
Y1037861D03*
Y1051247D03*
Y1071326D03*
Y1064633D03*
Y1078018D03*
Y1094751D03*
Y1088058D03*
Y1081365D03*
Y1108137D03*
Y1101444D03*
Y1124869D03*
Y1118176D03*
Y1114829D03*
Y1144948D03*
Y1138255D03*
Y1131562D03*
Y1161680D03*
Y1154987D03*
Y1151641D03*
Y1175066D03*
Y1168373D03*
Y1181759D03*
Y1191798D03*
Y1188452D03*
Y1205184D03*
Y1198491D03*
Y1218570D03*
Y1211877D03*
Y1225263D03*
Y1241995D03*
Y1235302D03*
Y1228609D03*
X1131341Y960892D03*
Y957546D03*
Y967585D03*
Y1054593D03*
X1147483Y964239D03*
Y1021129D03*
Y1024475D03*
Y1051247D03*
X1161041Y780184D03*
Y773491D03*
Y786877D03*
Y803609D03*
Y796916D03*
Y790223D03*
Y816995D03*
Y810302D03*
Y833727D03*
Y823688D03*
Y827034D03*
Y847113D03*
Y840420D03*
Y853806D03*
Y860499D03*
Y863845D03*
Y883924D03*
Y877231D03*
Y870538D03*
Y890617D03*
Y897310D03*
Y900656D03*
Y914042D03*
Y907349D03*
Y927428D03*
Y920735D03*
Y934121D03*
Y944160D03*
Y937467D03*
Y960892D03*
Y950853D03*
Y957546D03*
Y980971D03*
Y974278D03*
Y967585D03*
Y994357D03*
Y987664D03*
Y1027822D03*
Y1021129D03*
Y1047900D03*
Y1041207D03*
Y1034515D03*
Y1054593D03*
Y1074672D03*
Y1067979D03*
Y1091404D03*
Y1081365D03*
Y1084711D03*
Y1098097D03*
Y1111483D03*
Y1104790D03*
Y1128215D03*
Y1118176D03*
Y1121522D03*
Y1141601D03*
Y1134908D03*
Y1148294D03*
Y1154987D03*
Y1158333D03*
Y1171719D03*
Y1165026D03*
Y1185105D03*
Y1178412D03*
Y1191798D03*
Y1208530D03*
Y1201837D03*
Y1195144D03*
Y1221916D03*
Y1215223D03*
Y1238648D03*
Y1228609D03*
Y1231955D03*
Y1245341D03*
X1177183Y770144D03*
Y776837D03*
Y786877D03*
Y783530D03*
Y800263D03*
Y793570D03*
Y813648D03*
Y806955D03*
Y820341D03*
Y830381D03*
Y823688D03*
Y850459D03*
Y843766D03*
Y837074D03*
Y867192D03*
Y860499D03*
Y857152D03*
Y873885D03*
Y880577D03*
Y887270D03*
Y897310D03*
Y893963D03*
Y917389D03*
Y910696D03*
Y904003D03*
Y924081D03*
Y934121D03*
Y930774D03*
Y947507D03*
Y940814D03*
Y964239D03*
Y977625D03*
Y970932D03*
Y991011D03*
Y984318D03*
X1177283Y1021129D03*
Y1024475D03*
Y1031168D03*
Y1044554D03*
Y1037861D03*
Y1051247D03*
Y1071326D03*
Y1064633D03*
Y1078018D03*
Y1094752D03*
Y1088059D03*
Y1081366D03*
Y1108137D03*
Y1101444D03*
X1177183Y1124869D03*
X1177283Y1118177D03*
Y1114830D03*
Y1144948D03*
Y1138255D03*
X1177183Y1131562D03*
X1177283Y1161680D03*
Y1154988D03*
Y1151641D03*
Y1175066D03*
Y1168373D03*
Y1181759D03*
Y1191799D03*
Y1188452D03*
Y1205184D03*
Y1198491D03*
Y1218570D03*
Y1211877D03*
Y1225263D03*
X1177250Y1241995D03*
X1177283Y1235302D03*
Y1228609D03*
X1190741Y960892D03*
Y957546D03*
X1220441Y883924D03*
Y890617D03*
Y897310D03*
Y900656D03*
Y914042D03*
Y907349D03*
Y960892D03*
Y957546D03*
Y1185105D03*
Y1178412D03*
Y1191798D03*
Y1208530D03*
Y1201837D03*
Y1195144D03*
X1236583Y880577D03*
Y887270D03*
Y897310D03*
Y893963D03*
Y910696D03*
Y904003D03*
Y1175066D03*
Y1181759D03*
Y1191798D03*
Y1188452D03*
Y1205184D03*
Y1198491D03*
X1313921Y880219D03*
X1312070Y883423D03*
X1313921Y893036D03*
X1312070Y889832D03*
X1310221Y886627D03*
X1313921D03*
X1312503Y1121447D03*
X1326869Y851380D03*
X1330569Y844971D03*
X1325020Y848176D03*
X1328720D03*
X1326871Y857789D03*
X1328720Y860993D03*
X1330571Y857789D03*
X1317621Y880219D03*
X1319471Y883423D03*
X1325020Y899445D03*
Y893036D03*
X1326871Y889832D03*
X1330571D03*
X1317620Y893036D03*
X1319470Y889832D03*
X1323171Y896240D03*
X1330571D03*
X1317621Y886627D03*
X1326871Y896240D03*
X1321321Y886627D03*
X1325020Y912262D03*
X1326871Y909057D03*
X1330571D03*
X1326871Y902649D03*
X1330571D03*
X1323171Y915466D03*
X1330571D03*
X1326871D03*
X1325021Y931488D03*
X1326871Y928283D03*
X1330571D03*
Y921875D03*
X1326871D03*
X1325020Y918670D03*
X1326871Y941100D03*
X1325020Y937896D03*
X1330571Y941100D03*
X1323171Y934691D03*
X1330571D03*
X1326871D03*
Y947509D03*
X1330571D03*
X1325020Y950713D03*
X1326871Y960326D03*
X1325020Y957122D03*
X1330571Y960326D03*
X1326871Y966735D03*
X1330571D03*
X1326871Y953917D03*
X1330571D03*
X1323172D03*
X1326871Y979552D03*
X1330571D03*
X1325020Y976347D03*
X1323171Y973143D03*
X1325020Y969939D03*
X1323603Y1006093D03*
X1325453Y1002888D03*
X1327303Y999684D03*
X1331003D03*
X1327303Y1012501D03*
X1325453Y1009297D03*
X1331003Y1012501D03*
X1327304Y1031727D03*
X1325453Y1028523D03*
X1331003Y1031727D03*
X1325453Y1022114D03*
X1327303Y1018910D03*
X1331003D03*
X1323603Y1025318D03*
X1331004D03*
X1327304D03*
X1325453Y1047749D03*
Y1041340D03*
X1327303Y1038136D03*
X1331003D03*
X1323603Y1044544D03*
X1331003D03*
X1327303D03*
X1325453Y1060565D03*
X1327303Y1057361D03*
X1331003D03*
X1323603Y1063770D03*
X1327303D03*
X1331003D03*
X1327303Y1050952D03*
X1331003D03*
Y1070178D03*
X1327304D03*
X1325453Y1066974D03*
Y1079791D03*
X1327303Y1076587D03*
X1331003D03*
X1327303Y1089404D03*
X1325453Y1086200D03*
X1331003Y1089404D03*
X1323603Y1082995D03*
X1331003D03*
X1327303D03*
X1329153Y1124651D03*
X1331003Y1127856D03*
X1323603Y1121447D03*
X1319903Y1127856D03*
X1316203D03*
X1318054Y1118243D03*
X1321753Y1124651D03*
X1323603Y1127856D03*
X1319903Y1121447D03*
X1316203D03*
X1325452Y1137469D03*
X1327303Y1134264D03*
X1318053Y1131060D03*
X1346137Y179649D03*
X1332421Y841467D03*
X1337969Y844971D03*
X1339821Y841467D03*
X1345369Y844971D03*
X1347221Y841467D03*
X1334269Y844971D03*
X1336120Y848176D03*
X1341669Y844971D03*
X1343520Y848176D03*
X1332420Y854584D03*
X1334271Y857789D03*
X1337971D03*
X1341671D03*
X1345371D03*
X1336120Y860993D03*
X1339820Y854584D03*
X1343520Y860993D03*
X1347220Y854584D03*
X1332420Y899445D03*
Y893036D03*
X1334271Y896240D03*
X1339820Y899445D03*
X1343520D03*
X1347220Y893036D03*
X1332420Y912262D03*
X1334271Y915466D03*
X1339820Y912262D03*
X1337971Y909057D03*
X1343520Y912262D03*
X1345371Y909057D03*
X1337971Y902649D03*
X1345371D03*
X1336120Y905853D03*
X1343520D03*
X1339820D03*
X1347220D03*
X1332420Y931488D03*
X1339820D03*
X1332420Y918670D03*
X1337971Y928283D03*
X1343520Y931488D03*
X1345371Y928283D03*
X1337971Y921875D03*
X1339820Y918670D03*
X1345371Y921875D03*
X1343520Y918670D03*
X1336120Y925079D03*
X1343520D03*
X1339820D03*
X1347220D03*
X1332420Y937896D03*
X1334271Y934691D03*
X1337971Y941100D03*
X1339820Y937896D03*
X1345371Y941100D03*
X1343520Y937896D03*
X1337971Y947509D03*
X1345371D03*
X1343520Y944304D03*
X1336120D03*
X1347220D03*
X1339820D03*
X1332420Y950713D03*
Y957122D03*
X1334271Y953917D03*
X1337971Y966735D03*
X1345371D03*
X1336120Y963530D03*
X1339820Y950713D03*
X1343520D03*
X1337971Y960326D03*
X1339820Y957122D03*
X1345371Y960326D03*
X1343520Y957122D03*
X1347220Y963530D03*
X1336120Y982756D03*
X1343520D03*
X1339820D03*
X1347220D03*
X1345371Y979552D03*
X1343520Y976347D03*
X1337971Y979552D03*
X1339820Y976347D03*
X1332420D03*
Y969939D03*
X1334271Y973143D03*
X1339820Y969939D03*
X1343520D03*
X1334704Y1006093D03*
X1332853Y1002888D03*
Y1009297D03*
X1338404Y1012501D03*
X1345804D03*
X1340253Y1009297D03*
X1343953D03*
X1340253Y1002888D03*
X1338404Y999684D03*
X1347653Y1002888D03*
X1345804Y999684D03*
X1332853Y1028523D03*
Y1022114D03*
X1338404Y1031727D03*
X1340253Y1028523D03*
X1345804Y1031727D03*
X1343953Y1028523D03*
X1334704Y1025318D03*
X1336553Y1015705D03*
X1347653D03*
X1340253Y1022114D03*
X1338404Y1018910D03*
X1343953Y1022114D03*
X1345804Y1018910D03*
X1332853Y1047749D03*
Y1041340D03*
X1340253D03*
X1338404Y1038136D03*
X1343953Y1041340D03*
X1345804Y1038136D03*
X1336553Y1034931D03*
X1347653D03*
X1340253D03*
X1334704Y1044544D03*
X1343953Y1034931D03*
X1340253Y1047749D03*
X1343953D03*
X1332853Y1060565D03*
X1334704Y1063770D03*
X1340253Y1060565D03*
X1338404Y1057361D03*
X1343953Y1060565D03*
X1345804Y1057361D03*
X1338404Y1050952D03*
X1345804D03*
X1336553Y1054157D03*
X1347653D03*
X1340253D03*
X1343953D03*
X1332853Y1066974D03*
X1343953Y1079791D03*
X1345804Y1076587D03*
X1338404Y1070178D03*
X1340253Y1066974D03*
X1345804Y1070178D03*
X1343953Y1066974D03*
X1332853Y1079791D03*
X1340253D03*
X1338404Y1076587D03*
X1336553Y1073383D03*
X1347653D03*
X1340253D03*
X1343953D03*
X1332853Y1086200D03*
X1334704Y1082995D03*
X1338404Y1095813D03*
X1345804D03*
X1338404Y1089404D03*
X1340253Y1086200D03*
X1345804Y1089404D03*
X1343953Y1086200D03*
X1336553Y1092608D03*
X1343953D03*
X1340253D03*
X1347653D03*
X1340253Y1099017D03*
X1343953D03*
X1345803Y1108630D03*
X1340254Y1105426D03*
X1336554Y1111834D03*
X1334703Y1108630D03*
X1343954Y1111834D03*
X1342103Y1108630D03*
X1338403D03*
X1334703Y1121447D03*
X1336554Y1124651D03*
X1340253D03*
X1343953D03*
X1347653D03*
X1332854D03*
X1338404Y1127856D03*
X1342104Y1121447D03*
X1345804Y1127856D03*
X1342103Y1115039D03*
X1345803D03*
X1334703D03*
Y1134264D03*
X1338403Y1140973D03*
X1342104Y1134264D03*
X1345803Y1140973D03*
X1332854Y1137469D03*
X1336554D03*
X1340254D03*
X1343954D03*
X1347654D03*
X1352557Y175948D03*
X1349351Y181498D03*
X1355761Y185198D03*
X1349351D03*
X1355761Y174098D03*
Y181498D03*
X1352557Y183348D03*
X1352561Y198148D03*
X1355771Y196298D03*
X1355765Y199999D03*
Y203699D03*
X1363869Y844971D03*
X1352769D03*
X1356469D03*
X1360169D03*
X1362021Y841467D03*
X1349069Y844971D03*
X1350920Y848176D03*
X1354621Y841467D03*
X1358320Y848176D03*
X1349071Y857789D03*
X1354620Y854584D03*
X1356471Y857789D03*
X1360171D03*
X1363871D03*
X1350920Y860993D03*
X1352771Y857789D03*
X1358320Y860993D03*
X1362020Y854584D03*
X1350920Y899445D03*
X1358320D03*
Y893036D03*
X1350920D03*
X1362020D03*
X1349071Y896240D03*
X1356471D03*
X1352771D03*
X1360171D03*
X1352771Y902649D03*
X1356471D03*
X1350920Y912262D03*
X1352771Y909057D03*
X1358320Y912262D03*
X1356471Y909057D03*
X1349071Y915466D03*
X1356471D03*
X1352771D03*
X1360171D03*
X1350920Y931488D03*
X1352771Y928283D03*
X1358320Y931488D03*
X1356471Y928283D03*
X1352771Y921875D03*
X1350920Y918670D03*
X1356471Y921875D03*
X1358320Y918670D03*
X1356471Y941100D03*
X1358320Y937896D03*
X1352771Y947509D03*
X1356471D03*
X1352771Y941100D03*
X1350920Y937896D03*
X1349071Y934691D03*
X1356471D03*
X1352771D03*
X1360171D03*
X1352771Y960326D03*
X1350920Y957122D03*
X1356471Y960326D03*
X1358320Y957122D03*
X1350920Y950713D03*
X1358320D03*
X1349071Y953917D03*
X1356471D03*
X1352771D03*
X1360171D03*
X1356471Y966735D03*
X1352771D03*
X1350920Y969939D03*
X1358320D03*
X1349504Y1006093D03*
X1356904D03*
X1353204D03*
X1360604D03*
X1351353Y1002888D03*
X1353204Y999684D03*
X1358753Y1002888D03*
X1356904Y999684D03*
X1353204Y1012501D03*
X1351353Y1009297D03*
X1356904Y1012501D03*
X1358753Y1009297D03*
X1353204Y1031727D03*
X1351353Y1028523D03*
X1356904Y1031727D03*
X1358753Y1028523D03*
X1351353Y1022114D03*
X1353204Y1018910D03*
X1358753Y1022114D03*
X1356904Y1018910D03*
X1353204Y1025318D03*
X1360604D03*
X1349502D03*
X1356902D03*
X1351353Y1047749D03*
X1358753D03*
X1351353Y1041340D03*
X1353204Y1038136D03*
X1358753Y1041340D03*
X1356904Y1038136D03*
X1349504Y1044544D03*
X1356904D03*
X1353204D03*
X1360604D03*
X1351353Y1060565D03*
X1353204Y1057361D03*
X1358753Y1060565D03*
X1356904Y1057361D03*
X1353204Y1050952D03*
X1356904D03*
X1349504Y1063770D03*
X1360604D03*
X1353204D03*
X1356904D03*
Y1070178D03*
X1358753Y1066974D03*
X1353204Y1070178D03*
X1351353Y1066974D03*
Y1079791D03*
X1353204Y1076587D03*
X1358753Y1079791D03*
X1356904Y1076587D03*
X1353204Y1089404D03*
X1351353Y1086200D03*
X1356904Y1089404D03*
X1358753Y1086200D03*
X1349504Y1082995D03*
X1360604D03*
X1353204D03*
X1356904D03*
X1351353Y1124651D03*
X1355053D03*
X1358753D03*
X1362453D03*
X1349504Y1121447D03*
X1353204Y1127856D03*
X1356904Y1121447D03*
X1360604Y1127856D03*
X1349504Y1134264D03*
X1353203Y1140973D03*
X1356904Y1134264D03*
X1360603Y1140973D03*
X1351354Y1137469D03*
X1355054D03*
X1358754D03*
X1362454D03*
X1367569Y844971D03*
X1369421Y841467D03*
X1373120Y848176D03*
X1376821Y841467D03*
X1365720Y848176D03*
X1371269Y844971D03*
X1374969D03*
X1378669D03*
X1365720Y860993D03*
X1367571Y857789D03*
X1373120Y860993D03*
X1374971Y857789D03*
X1369420Y854584D03*
X1371271Y857789D03*
X1376820Y854584D03*
X1378671Y857789D03*
X1374971Y973143D03*
X1376820Y976347D03*
X1378671Y979552D03*
Y973143D03*
X1366153Y1002888D03*
X1364304Y999684D03*
X1369853Y1002888D03*
X1371704Y999684D03*
X1369853Y1111834D03*
X1368004Y1108630D03*
X1377253Y1099017D03*
X1379104Y1108630D03*
X1373553Y1105426D03*
X1371704Y1108630D03*
X1379104Y1102221D03*
X1377253Y1111834D03*
X1375404Y1108630D03*
X1366153Y1124651D03*
X1371704Y1121447D03*
X1373553Y1124651D03*
X1377253D03*
X1368004Y1127856D03*
X1369853Y1124651D03*
X1375404Y1127856D03*
X1379104Y1121447D03*
X1364304D03*
X1375404Y1115039D03*
X1368004D03*
X1379104D03*
X1368003Y1140973D03*
X1371704Y1134264D03*
X1375403Y1140973D03*
X1379104Y1134264D03*
X1364304D03*
X1366154Y1137469D03*
X1369854D03*
X1373554D03*
X1377254D03*
X1380520Y848176D03*
X1386069Y844971D03*
X1389769D03*
X1393469D03*
X1382369D03*
X1384221Y841467D03*
X1387920Y848176D03*
X1391621Y841467D03*
X1395320Y848176D03*
X1380520Y860993D03*
X1382371Y857789D03*
X1387920Y860993D03*
X1389771Y857789D03*
X1395320Y860993D03*
X1384220Y854584D03*
X1386071Y857789D03*
X1391620Y854584D03*
X1393471Y857789D03*
Y883423D03*
X1391620Y880219D03*
X1389771Y883423D03*
X1386071Y896240D03*
X1389771D03*
X1393471D03*
X1387920Y899445D03*
X1391620Y893036D03*
X1395320Y899445D03*
Y886627D03*
X1380953Y1099017D03*
X1395753Y1105426D03*
X1393904Y1108630D03*
X1390204Y1102221D03*
X1392053Y1111834D03*
X1388353D03*
X1384653Y1105426D03*
Y1099017D03*
X1392053Y1105426D03*
X1395753Y1111834D03*
X1388353Y1105426D03*
X1384653Y1111834D03*
X1386504Y1108630D03*
X1380953Y1124651D03*
X1384653D03*
X1382804Y1127856D03*
X1386504Y1121447D03*
X1390204Y1115039D03*
X1382803Y1140973D03*
X1386504Y1134264D03*
X1380954Y1137469D03*
X1384654D03*
X1397169Y844971D03*
X1399021Y841467D03*
X1402720Y848176D03*
X1406420D03*
X1411969Y844971D03*
X1400869D03*
X1404569D03*
X1410120Y848176D03*
X1397171Y857789D03*
X1402720Y860993D03*
X1404571Y857789D03*
X1410121Y860993D03*
X1411971Y857789D03*
X1399020Y854584D03*
X1400871Y857789D03*
X1406420Y854584D03*
X1408271Y857789D03*
Y883423D03*
X1406420Y880219D03*
X1400871Y883423D03*
X1399020Y880219D03*
X1404571Y883423D03*
X1397171D03*
X1411971D03*
X1397171Y896240D03*
X1402720Y899445D03*
X1404571Y896240D03*
X1410120Y899445D03*
X1399020Y893036D03*
X1400871Y896240D03*
X1406420Y893036D03*
X1408271Y896240D03*
X1411971D03*
X1410120Y886627D03*
X1402720D03*
X1405003Y1076587D03*
X1406853Y1079791D03*
X1413820Y848176D03*
X1424921Y860993D03*
X1421220Y854584D03*
X1417520Y860993D03*
X1428620Y854584D03*
X1426771Y857789D03*
X1423071D03*
X1419371D03*
X1413821Y854584D03*
X1428621Y880219D03*
X1423071Y883423D03*
X1421220Y880219D03*
X1415671Y883423D03*
X1413820Y880219D03*
X1426771Y883423D03*
X1419371D03*
X1413820Y893036D03*
X1421220Y899445D03*
X1419371Y896240D03*
X1424920Y899445D03*
X1426772Y896240D03*
X1417520Y899445D03*
X1421220Y893036D03*
X1423071Y896240D03*
X1428621Y893036D03*
X1424920Y886627D03*
X1417520D03*
X1445271Y857789D03*
X1439720Y860993D03*
X1437871Y857789D03*
X1432320Y860993D03*
X1430471Y857789D03*
X1443420Y854584D03*
X1441571Y857789D03*
X1436020Y854584D03*
X1434171Y857789D03*
X1445271Y883423D03*
X1443420Y880219D03*
X1437871Y883423D03*
X1436020Y880219D03*
X1430471Y883423D03*
X1441571D03*
X1434171D03*
X1430471Y896240D03*
X1436020Y893036D03*
X1437871Y896240D03*
X1441571D03*
X1432320Y899445D03*
X1434171Y896240D03*
X1439720Y899445D03*
X1443420Y893036D03*
X1439720Y886627D03*
X1432320D03*
X1460071Y857789D03*
X1454520Y860993D03*
X1452671Y857789D03*
X1447120Y860993D03*
X1458220Y854584D03*
X1456371Y857789D03*
X1450820Y854584D03*
X1448971Y857789D03*
X1447120Y886627D03*
X1460504Y1121447D03*
X1456804Y1127856D03*
X1453104Y1121447D03*
X1449404Y1127856D03*
X1445704Y1121447D03*
X1458653Y1124651D03*
X1454953D03*
X1451253D03*
X1447553D03*
X1460504Y1134264D03*
X1458654Y1137469D03*
X1453104Y1134264D03*
X1451254Y1137469D03*
X1456803Y1140973D03*
X1454954Y1137469D03*
X1449403Y1140973D03*
X1467471Y857789D03*
X1461920Y860993D03*
X1476720D03*
X1474871Y857789D03*
X1471171D03*
X1465620Y854584D03*
X1463771Y857789D03*
X1473020Y854584D03*
X1469320Y860993D03*
X1476720Y899445D03*
Y912262D03*
X1474871Y909057D03*
Y902649D03*
X1476720Y905853D03*
X1473020D03*
X1476720Y931488D03*
X1474871Y921875D03*
X1476720Y918670D03*
X1474871Y928283D03*
X1473020Y925079D03*
X1476720D03*
X1474871Y947509D03*
Y941100D03*
X1476720Y937896D03*
X1473020Y944304D03*
X1476720D03*
Y950713D03*
Y957122D03*
X1474871Y960326D03*
X1463771Y979552D03*
X1461920Y976347D03*
X1467471Y979552D03*
X1469320Y976347D03*
X1476720Y982756D03*
X1473020D03*
X1474871Y979552D03*
X1476720Y976347D03*
X1477153Y1002888D03*
X1475304Y999684D03*
Y1012501D03*
X1477153Y1009297D03*
X1473453Y1015705D03*
X1475304Y1031727D03*
X1477153Y1028523D03*
Y1022114D03*
X1475304Y1018910D03*
X1477153Y1041340D03*
X1475304Y1038136D03*
X1477153Y1047749D03*
Y1034931D03*
X1473453D03*
X1477153Y1060565D03*
X1475304Y1057361D03*
Y1050952D03*
X1477153Y1054157D03*
X1473453D03*
X1475304Y1070178D03*
X1477153Y1066974D03*
Y1079791D03*
X1475304Y1076587D03*
X1473453Y1073383D03*
X1477153D03*
X1475304Y1089404D03*
X1477153Y1086200D03*
X1473453Y1092608D03*
X1477153D03*
X1464204Y1127856D03*
X1475304Y1121447D03*
X1471604Y1127856D03*
X1467904Y1121447D03*
X1466053Y1124651D03*
X1462353D03*
X1477153D03*
X1473453D03*
X1469753D03*
X1469754Y1137469D03*
X1464203Y1140973D03*
X1477154Y1137469D03*
X1471603Y1140973D03*
X1467904Y1134264D03*
X1466054Y1137469D03*
X1462354D03*
X1475304Y1134264D03*
X1473454Y1137469D03*
X1491520Y860993D03*
X1489671Y857789D03*
X1484120Y860993D03*
X1482271Y857789D03*
X1493371D03*
X1487820Y854584D03*
X1485971Y857789D03*
X1480420Y854584D03*
X1478571Y857789D03*
X1487820Y899445D03*
Y893036D03*
X1484120D03*
X1485971Y896240D03*
X1493371D03*
X1489671D03*
X1480420Y899445D03*
X1489671Y902649D03*
X1493371D03*
X1487820Y912262D03*
X1489671Y909057D03*
X1493371D03*
X1489671Y915466D03*
X1485971D03*
X1493371D03*
X1480420Y912262D03*
X1482271Y909057D03*
Y902649D03*
X1484120Y905853D03*
X1480420D03*
X1487820Y931488D03*
X1489671Y928283D03*
X1493371D03*
X1482271D03*
Y921875D03*
X1480420Y918670D03*
X1489671Y921875D03*
X1487820Y918670D03*
X1493371Y921875D03*
X1480420Y931488D03*
Y925079D03*
X1484120D03*
X1489671Y941100D03*
X1487820Y937896D03*
X1493371Y941100D03*
X1489671Y934691D03*
X1485971D03*
X1493371D03*
X1489671Y947509D03*
X1493371D03*
X1482271D03*
Y941100D03*
X1480420Y937896D03*
X1484120Y944304D03*
X1480420D03*
X1487820Y950713D03*
X1489671Y960326D03*
X1487820Y957122D03*
X1493371Y960326D03*
Y966735D03*
X1489671D03*
X1480420Y950713D03*
X1489671Y953917D03*
X1493371D03*
X1485971D03*
X1480420Y957122D03*
X1482271Y960326D03*
X1484120Y982756D03*
X1480420D03*
Y976347D03*
X1482271Y979552D03*
X1489671D03*
X1493371D03*
X1487820Y976347D03*
X1485971Y973143D03*
X1487820Y969939D03*
X1493804Y1006093D03*
X1490104D03*
X1486404D03*
X1493804Y1012501D03*
X1480853Y1002888D03*
X1482703Y999684D03*
X1490104Y1012501D03*
X1488253Y1009297D03*
X1482704Y1012501D03*
X1480853Y1009297D03*
X1493803Y999684D03*
X1488253Y1002888D03*
X1490104Y999684D03*
Y1031727D03*
X1488253Y1028523D03*
X1493804Y1031727D03*
X1488253Y1022114D03*
X1490104Y1018910D03*
X1493804D03*
X1490104Y1025318D03*
X1486404D03*
X1493804D03*
X1484553Y1015705D03*
X1482704Y1031727D03*
X1480853Y1028523D03*
Y1022114D03*
X1482704Y1018910D03*
X1480853Y1041340D03*
X1482704Y1038136D03*
X1488253Y1047749D03*
Y1041340D03*
X1490104Y1038136D03*
X1493804D03*
X1480853Y1047749D03*
X1486404Y1044544D03*
X1484553Y1034931D03*
X1490104Y1044544D03*
X1493804D03*
X1480853Y1034931D03*
X1488253Y1060565D03*
X1490104Y1057361D03*
X1493804D03*
X1486404Y1063770D03*
X1490104D03*
X1493804D03*
X1490104Y1050952D03*
X1493804D03*
X1480853Y1060565D03*
X1482704Y1057361D03*
Y1050952D03*
X1484553Y1054157D03*
X1480853D03*
X1493804Y1070178D03*
X1490104D03*
X1488253Y1066974D03*
X1480853Y1079791D03*
X1482704Y1076587D03*
Y1070178D03*
X1480853Y1066974D03*
X1488253Y1079791D03*
X1490104Y1076587D03*
X1493804D03*
X1484553Y1073383D03*
X1480853D03*
X1490104Y1089404D03*
X1488253Y1086200D03*
X1493804Y1089404D03*
X1490104Y1082995D03*
X1486404D03*
X1493804D03*
X1486404Y1095813D03*
X1482703D03*
X1482704Y1089404D03*
X1480853Y1086200D03*
X1484553Y1092608D03*
X1480853D03*
X1493804Y1102221D03*
X1491953Y1099017D03*
X1493804Y1127856D03*
X1490104Y1121447D03*
X1486404Y1127856D03*
X1482704Y1121447D03*
X1479004Y1127856D03*
X1491953Y1124651D03*
X1488253D03*
X1484553D03*
X1480853D03*
X1493803Y1140973D03*
X1490104Y1134264D03*
X1488254Y1137469D03*
X1482704Y1134264D03*
X1480854Y1137469D03*
X1491954D03*
X1486403Y1140973D03*
X1484554Y1137469D03*
X1479003Y1140973D03*
X1508171Y864197D03*
X1510021Y854584D03*
X1504471Y857789D03*
X1498920Y860993D03*
X1497071Y857789D03*
X1502620Y854584D03*
X1500771Y857789D03*
X1495220Y854584D03*
X1502621Y899445D03*
X1506320D03*
X1495220D03*
Y893036D03*
X1498920D03*
X1497071Y896240D03*
X1506321Y912262D03*
X1508171Y909057D03*
X1500771Y902649D03*
X1508171D03*
X1502621Y912262D03*
X1500771Y909057D03*
X1502621Y905853D03*
X1510021D03*
X1498920D03*
X1506321D03*
X1495220Y912262D03*
X1497071Y915466D03*
X1502621Y931488D03*
X1500771Y928283D03*
X1506321Y931488D03*
X1508171Y928283D03*
X1500771Y921875D03*
X1502621Y918670D03*
X1508171Y921875D03*
X1506321Y918670D03*
X1502621Y925079D03*
X1510021D03*
X1498920D03*
X1506321D03*
X1495220Y931488D03*
Y918670D03*
X1500771Y941100D03*
X1502621Y937896D03*
X1508171Y941100D03*
X1506321Y937896D03*
X1500771Y947509D03*
X1508171D03*
X1495220Y937896D03*
X1510021Y944304D03*
X1497071Y934691D03*
X1502621Y944304D03*
X1506320D03*
X1498920D03*
X1500771Y966735D03*
X1508171D03*
X1498920Y963530D03*
X1502621Y950713D03*
X1506320D03*
X1508171Y960326D03*
X1506320Y957122D03*
X1500771Y960326D03*
X1502621Y957122D03*
X1510021Y963530D03*
X1495220Y950713D03*
Y957122D03*
X1497071Y953917D03*
X1502621Y969939D03*
X1506321D03*
X1495220Y976347D03*
Y969939D03*
X1497071Y973143D03*
X1497504Y1006093D03*
X1501204Y1012501D03*
X1508603D03*
X1503053Y1009297D03*
X1506753D03*
X1495653D03*
X1495655Y1002888D03*
X1506753D03*
X1508603Y999684D03*
X1503053Y1002888D03*
X1501204Y999684D03*
X1499353Y1015705D03*
X1510453D03*
X1501204Y1031727D03*
X1503053Y1028523D03*
X1508603Y1031727D03*
X1506753Y1028523D03*
Y1022114D03*
X1508603Y1018910D03*
X1503053Y1022114D03*
X1501204Y1018910D03*
X1495653Y1028523D03*
Y1022114D03*
X1497504Y1025318D03*
X1503053Y1041340D03*
X1501204Y1038136D03*
X1506753Y1041340D03*
X1508603Y1038136D03*
X1503053Y1047749D03*
X1506753D03*
X1503053Y1034931D03*
X1510453D03*
X1499353D03*
X1506753D03*
X1495653Y1047749D03*
Y1041340D03*
X1497504Y1044544D03*
X1495653Y1060565D03*
X1503053D03*
X1501204Y1057361D03*
X1506753Y1060565D03*
X1508604Y1057361D03*
X1501203Y1050952D03*
X1508604Y1050953D03*
X1499353Y1054157D03*
X1497504Y1063770D03*
X1510453Y1054157D03*
X1503053D03*
X1506753D03*
Y1079791D03*
X1508604Y1076587D03*
X1501204Y1070178D03*
X1503053Y1066974D03*
X1508604Y1070178D03*
X1506753Y1066974D03*
X1503053Y1079791D03*
X1501204Y1076587D03*
X1499353Y1073383D03*
X1510453D03*
X1503053D03*
X1506753D03*
X1495653Y1066974D03*
Y1079791D03*
X1497504Y1095813D03*
X1508603D03*
X1501204D03*
Y1089404D03*
X1503053Y1086200D03*
X1508604Y1089404D03*
X1506753Y1086200D03*
X1503053Y1092608D03*
X1510452D03*
X1499353D03*
X1506753D03*
X1495653Y1086200D03*
X1497504Y1082995D03*
X1506753Y1099017D03*
X1503053Y1124651D03*
X1497504Y1121447D03*
X1501204Y1127856D03*
X1499353Y1124651D03*
X1495653D03*
X1508604Y1134264D03*
X1501203Y1140973D03*
X1499354Y1137469D03*
X1510454D03*
X1503054D03*
X1497504Y1134264D03*
X1495654Y1137469D03*
X1519271Y851380D03*
X1515571D03*
X1511871Y864197D03*
X1519270D03*
X1522970D03*
X1511871Y857789D03*
X1519271D03*
X1515571D03*
X1517421Y860993D03*
Y854584D03*
X1515571Y883423D03*
X1513720Y880219D03*
X1519271Y883423D03*
X1521121Y880219D03*
X1513720Y873810D03*
X1515571Y870606D03*
X1521121Y873810D03*
X1519271Y870606D03*
X1515570Y877014D03*
X1522970D03*
X1511871D03*
X1519271D03*
X1596941Y883924D03*
Y890617D03*
Y897310D03*
Y900656D03*
Y914042D03*
Y907349D03*
Y960892D03*
Y957546D03*
Y1185105D03*
Y1178412D03*
Y1191798D03*
Y1208530D03*
Y1201837D03*
Y1195144D03*
X1613083Y880577D03*
Y887270D03*
Y897310D03*
Y893963D03*
Y910696D03*
Y904003D03*
Y1175066D03*
Y1181759D03*
Y1191798D03*
Y1188451D03*
Y1205184D03*
Y1198491D03*
X1626641Y960892D03*
Y957546D03*
X1656441Y780184D03*
Y773491D03*
Y786877D03*
Y803609D03*
Y796916D03*
Y790223D03*
Y816995D03*
Y810302D03*
Y833727D03*
Y823688D03*
Y827034D03*
Y847113D03*
Y840420D03*
Y853806D03*
Y860499D03*
Y863845D03*
Y883924D03*
Y877231D03*
Y870538D03*
Y890617D03*
Y897310D03*
Y900656D03*
Y914042D03*
Y907349D03*
Y927428D03*
Y920735D03*
Y934121D03*
Y944160D03*
Y937467D03*
Y960892D03*
Y950853D03*
Y957546D03*
Y980971D03*
Y974278D03*
Y967585D03*
Y994357D03*
Y987664D03*
X1656141Y1027822D03*
X1656441Y1021129D03*
X1656141Y1047900D03*
Y1041207D03*
Y1034514D03*
Y1054593D03*
X1656441Y1074672D03*
Y1067979D03*
Y1091404D03*
Y1081365D03*
Y1084711D03*
Y1098097D03*
Y1111483D03*
Y1104790D03*
Y1128215D03*
Y1118176D03*
Y1121522D03*
Y1141601D03*
Y1134908D03*
Y1148294D03*
Y1154987D03*
Y1158333D03*
Y1171719D03*
Y1165026D03*
Y1185105D03*
Y1178412D03*
Y1191798D03*
Y1208530D03*
Y1201837D03*
Y1195144D03*
Y1221916D03*
Y1215223D03*
Y1238648D03*
Y1228609D03*
Y1231955D03*
Y1245341D03*
X1672583Y770144D03*
Y776837D03*
Y786877D03*
Y783530D03*
Y800263D03*
Y793570D03*
Y813648D03*
Y806955D03*
Y820341D03*
Y830381D03*
Y823688D03*
Y850459D03*
Y843766D03*
Y837074D03*
Y867192D03*
Y860499D03*
Y857152D03*
Y873885D03*
Y880577D03*
Y887270D03*
Y897310D03*
Y893963D03*
Y917389D03*
Y910696D03*
Y904003D03*
Y924081D03*
Y934121D03*
Y930774D03*
Y947507D03*
Y940814D03*
Y964239D03*
Y977625D03*
Y970932D03*
Y991011D03*
Y984318D03*
Y1021129D03*
Y1024475D03*
Y1031168D03*
X1672283Y1044554D03*
Y1037861D03*
X1672583Y1051247D03*
Y1071325D03*
Y1064633D03*
Y1078018D03*
Y1094751D03*
Y1088058D03*
Y1081365D03*
Y1108136D03*
Y1101444D03*
Y1124869D03*
Y1118176D03*
Y1114829D03*
Y1144947D03*
Y1138255D03*
Y1131562D03*
Y1161680D03*
Y1154987D03*
Y1151640D03*
Y1175066D03*
Y1168373D03*
Y1181758D03*
Y1191798D03*
Y1188451D03*
Y1205184D03*
Y1198491D03*
Y1218569D03*
Y1211877D03*
Y1225262D03*
Y1241995D03*
Y1235302D03*
Y1228609D03*
X1686041Y960892D03*
Y957546D03*
X1686141Y967585D03*
Y1054593D03*
X1702283Y964239D03*
Y1021129D03*
Y1024475D03*
Y1051247D03*
X1715841Y780184D03*
Y773491D03*
Y786877D03*
Y803609D03*
Y796916D03*
Y790223D03*
Y816995D03*
Y810302D03*
Y833727D03*
Y823688D03*
Y827034D03*
Y847113D03*
Y840420D03*
Y853806D03*
Y860499D03*
Y863845D03*
Y883924D03*
Y877231D03*
Y870538D03*
Y890617D03*
Y897310D03*
Y900656D03*
Y914042D03*
Y907349D03*
Y927428D03*
Y920735D03*
Y934121D03*
Y944160D03*
Y937467D03*
Y960892D03*
Y950853D03*
Y957546D03*
Y980971D03*
Y974278D03*
Y967585D03*
Y994357D03*
Y987664D03*
Y1027822D03*
Y1021129D03*
Y1047900D03*
Y1041207D03*
Y1034514D03*
Y1054593D03*
Y1074672D03*
Y1067979D03*
Y1091404D03*
Y1081365D03*
Y1084711D03*
Y1098097D03*
Y1111483D03*
Y1104790D03*
Y1128215D03*
Y1118176D03*
Y1121522D03*
Y1141601D03*
Y1134908D03*
Y1148294D03*
Y1154987D03*
Y1158333D03*
Y1171719D03*
Y1165026D03*
Y1185105D03*
Y1178412D03*
Y1191798D03*
Y1208530D03*
Y1201837D03*
Y1195144D03*
Y1221916D03*
Y1215223D03*
Y1238648D03*
Y1228609D03*
Y1231955D03*
Y1245341D03*
X1731983Y770144D03*
Y776837D03*
Y786877D03*
Y783530D03*
Y800263D03*
Y793570D03*
Y813648D03*
Y806955D03*
Y820341D03*
Y830381D03*
Y823688D03*
Y850459D03*
Y843766D03*
Y837074D03*
Y867192D03*
Y860499D03*
Y857152D03*
Y873885D03*
Y880577D03*
Y887270D03*
Y897310D03*
Y893963D03*
Y917389D03*
Y910696D03*
Y904003D03*
Y924081D03*
Y934121D03*
Y930774D03*
Y947507D03*
Y940814D03*
Y964239D03*
Y977625D03*
X1731883Y970932D03*
X1731983Y991011D03*
Y984318D03*
Y1021129D03*
Y1024475D03*
Y1031168D03*
X1731683Y1044554D03*
Y1037861D03*
X1731983Y1051247D03*
X1731818Y1071326D03*
X1731883Y1064633D03*
X1731983Y1078018D03*
Y1094751D03*
Y1088058D03*
Y1081365D03*
X1731818Y1108137D03*
X1731983Y1101444D03*
Y1124869D03*
Y1118176D03*
Y1114829D03*
Y1144947D03*
Y1138255D03*
Y1131562D03*
Y1161680D03*
Y1154987D03*
Y1151640D03*
Y1175066D03*
Y1168373D03*
X1731818Y1181759D03*
X1731983Y1191798D03*
X1731818Y1188452D03*
X1731983Y1205184D03*
Y1198491D03*
Y1218569D03*
Y1211877D03*
Y1225262D03*
Y1241995D03*
Y1235302D03*
Y1228609D03*
X1745541Y960892D03*
Y957546D03*
Y967585D03*
Y1054593D03*
X1761683Y964239D03*
Y1021129D03*
Y1024475D03*
Y1051247D03*
X1775241Y816995D03*
Y810302D03*
Y833727D03*
Y823688D03*
Y827034D03*
Y840420D03*
Y960892D03*
Y957546D03*
Y967585D03*
Y1221916D03*
Y1215223D03*
Y1238648D03*
Y1228609D03*
Y1231955D03*
Y1245341D03*
X1791383Y813648D03*
Y806955D03*
Y820341D03*
Y830381D03*
Y823688D03*
Y837074D03*
Y964239D03*
Y1218570D03*
Y1211877D03*
Y1225263D03*
Y1241995D03*
Y1235302D03*
Y1228609D03*
X1804941Y960892D03*
Y957546D03*
Y967585D03*
X1821083Y964239D03*
G54D49*
X676508Y145866D03*
G54D35*
X238780Y1643661D03*
X230906Y1649173D03*
X238780Y1653110D03*
Y1657834D03*
X230906Y1653897D03*
Y1663346D03*
X238780Y1667283D03*
Y1672007D03*
X230906Y1668070D03*
X238780Y1695629D03*
X230906Y1691692D03*
Y1696417D03*
X238780Y1700354D03*
Y1723976D03*
Y1728700D03*
X230906Y1720039D03*
Y1724763D03*
Y1734212D03*
X254528Y1643661D03*
X246654Y1649173D03*
X254528Y1653110D03*
Y1657834D03*
X246654Y1653897D03*
Y1663346D03*
X254528Y1667283D03*
Y1672007D03*
X246654Y1668070D03*
X254528Y1695629D03*
X246654Y1691692D03*
Y1696417D03*
X254528Y1700354D03*
Y1723976D03*
Y1728700D03*
X246654Y1720039D03*
Y1724763D03*
Y1734212D03*
X270276Y1643661D03*
X262402Y1649173D03*
X270276Y1653110D03*
Y1657834D03*
X262402Y1653897D03*
Y1663346D03*
X270276Y1667283D03*
Y1672007D03*
X262402Y1668070D03*
X270276Y1695629D03*
X262402Y1691692D03*
Y1696417D03*
X270276Y1700354D03*
Y1723976D03*
Y1728700D03*
X262402Y1720039D03*
Y1724763D03*
Y1734212D03*
X286024Y1643661D03*
X278150Y1649173D03*
X286024Y1653110D03*
Y1657834D03*
X278150Y1653897D03*
Y1663346D03*
X286024Y1667283D03*
Y1672007D03*
X278150Y1668070D03*
X286024Y1695629D03*
X278150Y1691692D03*
Y1696417D03*
X286024Y1700354D03*
Y1723976D03*
Y1728700D03*
X278150Y1720039D03*
Y1724763D03*
Y1734212D03*
X305709Y1672007D03*
X297835Y1691692D03*
Y1696417D03*
X305709Y1695629D03*
Y1700354D03*
X297835Y1720039D03*
Y1724763D03*
X305709Y1723976D03*
Y1728700D03*
X297835Y1734212D03*
X321457Y1672007D03*
X313583Y1691692D03*
Y1696417D03*
X321457Y1695629D03*
Y1700354D03*
X313583Y1720039D03*
Y1724763D03*
X321457Y1723976D03*
Y1728700D03*
X313583Y1734212D03*
X337205Y1672007D03*
X329331Y1691692D03*
Y1696417D03*
X337205Y1695629D03*
Y1700354D03*
X329331Y1720039D03*
Y1724763D03*
X337205Y1723976D03*
Y1728700D03*
X329331Y1734212D03*
X352953Y1672007D03*
X345079Y1691692D03*
Y1696417D03*
X352953Y1695629D03*
Y1700354D03*
X345079Y1720039D03*
Y1724763D03*
X352953Y1723976D03*
Y1728700D03*
X345079Y1734212D03*
X495079Y1677519D03*
Y1682244D03*
Y1705866D03*
Y1710590D03*
Y1734212D03*
X502953Y1672007D03*
X510827Y1677519D03*
X502953Y1681456D03*
X510827Y1682244D03*
X502953Y1686180D03*
X510827Y1705866D03*
X502953Y1709803D03*
X510827Y1710590D03*
X502953Y1714527D03*
X510827Y1734212D03*
X518701Y1672007D03*
X534449D03*
X526575Y1677519D03*
X518701Y1681456D03*
X526575Y1682244D03*
X534449Y1681456D03*
X518701Y1686180D03*
X534449D03*
X526575Y1705866D03*
X518701Y1709803D03*
X526575Y1710590D03*
X534449Y1709803D03*
X518701Y1714527D03*
X534449D03*
X526575Y1734212D03*
X550197Y1672007D03*
X542323Y1677519D03*
Y1682244D03*
X550197Y1681456D03*
Y1686180D03*
X542323Y1705866D03*
Y1710590D03*
X550197Y1709803D03*
Y1714527D03*
X542323Y1734212D03*
X562008Y1677519D03*
Y1682244D03*
Y1705866D03*
Y1710590D03*
Y1734212D03*
X569882Y1672007D03*
X577756Y1677519D03*
X569882Y1681456D03*
X577756Y1682244D03*
X569882Y1686180D03*
X577756Y1705866D03*
X569882Y1709803D03*
X577756Y1710590D03*
X569882Y1714527D03*
X577756Y1734212D03*
X585630Y1672007D03*
X593504Y1677519D03*
X585630Y1681456D03*
X593504Y1682244D03*
X585630Y1686180D03*
X593504Y1705866D03*
X585630Y1709803D03*
X593504Y1710590D03*
X585630Y1714527D03*
X593504Y1734212D03*
X601378Y1672007D03*
X609252Y1677519D03*
X601378Y1681456D03*
X609252Y1682244D03*
X601378Y1686180D03*
X609252Y1705866D03*
X601378Y1709803D03*
X609252Y1710590D03*
X601378Y1714527D03*
X609252Y1734212D03*
X617126Y1672007D03*
Y1681456D03*
Y1686180D03*
Y1709803D03*
Y1714527D03*
X1246654Y1672007D03*
X1238780Y1691692D03*
Y1696417D03*
X1246654Y1695629D03*
Y1700354D03*
X1238780Y1720039D03*
Y1724763D03*
X1246654Y1723976D03*
Y1728700D03*
X1238780Y1734212D03*
X1262402Y1672007D03*
X1254528Y1691692D03*
Y1696417D03*
X1262402Y1695629D03*
Y1700354D03*
X1254528Y1720039D03*
Y1724763D03*
X1262402Y1723976D03*
Y1728700D03*
X1254528Y1734212D03*
X1278150Y1672007D03*
X1270276Y1691692D03*
Y1696417D03*
X1278150Y1695629D03*
Y1700354D03*
X1270276Y1720039D03*
Y1724763D03*
X1278150Y1723976D03*
Y1728700D03*
X1270276Y1734212D03*
X1293898Y1672007D03*
X1286024Y1691692D03*
Y1696417D03*
X1293898Y1695629D03*
Y1700354D03*
X1286024Y1720039D03*
Y1724763D03*
X1293898Y1723976D03*
Y1728700D03*
X1286024Y1734212D03*
X1313583Y1672007D03*
X1305709Y1691692D03*
Y1696417D03*
X1313583Y1695629D03*
Y1700354D03*
X1305709Y1720039D03*
Y1724763D03*
X1313583Y1723976D03*
Y1728700D03*
X1305709Y1734212D03*
X1329331Y1672007D03*
X1321457Y1691692D03*
Y1696417D03*
X1329331Y1695629D03*
Y1700354D03*
X1321457Y1720039D03*
Y1724763D03*
X1329331Y1723976D03*
Y1728700D03*
X1321457Y1734212D03*
X1345079Y1672007D03*
X1337205Y1691692D03*
Y1696417D03*
X1345079Y1695629D03*
Y1700354D03*
X1337205Y1720039D03*
Y1724763D03*
X1345079Y1723976D03*
Y1728700D03*
X1337205Y1734212D03*
X1360827Y1672007D03*
X1352953Y1691692D03*
Y1696417D03*
X1360827Y1695629D03*
Y1700354D03*
X1352953Y1720039D03*
Y1724763D03*
X1360827Y1723976D03*
Y1728700D03*
X1352953Y1734212D03*
X1510827Y1672007D03*
X1502953Y1677519D03*
Y1682244D03*
X1510827Y1681456D03*
Y1686180D03*
X1502953Y1705866D03*
Y1710590D03*
X1510827Y1709803D03*
Y1714527D03*
X1502953Y1734212D03*
X1526575Y1672007D03*
X1518701Y1677519D03*
Y1682244D03*
X1526575Y1681456D03*
Y1686180D03*
X1518701Y1705866D03*
Y1710590D03*
X1526575Y1709803D03*
Y1714527D03*
X1518701Y1734212D03*
X1542323Y1672007D03*
X1534449Y1677519D03*
Y1682244D03*
X1542323Y1681456D03*
Y1686180D03*
X1534449Y1705866D03*
Y1710590D03*
X1542323Y1709803D03*
Y1714527D03*
X1534449Y1734212D03*
X1558071Y1672007D03*
X1550197Y1677519D03*
Y1682244D03*
X1558071Y1681456D03*
Y1686180D03*
X1550197Y1705866D03*
Y1710590D03*
X1558071Y1709803D03*
Y1714527D03*
X1550197Y1734212D03*
X1569882Y1677519D03*
Y1682244D03*
Y1705866D03*
Y1710590D03*
Y1734212D03*
X1577756Y1672007D03*
X1585630Y1677519D03*
X1577756Y1681456D03*
X1585630Y1682244D03*
X1577756Y1686180D03*
X1585630Y1705866D03*
X1577756Y1709803D03*
X1585630Y1710590D03*
X1577756Y1714527D03*
X1585630Y1734212D03*
X1593504Y1672007D03*
X1601378Y1677519D03*
X1593504Y1681456D03*
X1601378Y1682244D03*
X1593504Y1686180D03*
X1601378Y1705866D03*
X1593504Y1709803D03*
X1601378Y1710590D03*
X1593504Y1714527D03*
X1601378Y1734212D03*
X1609252Y1672007D03*
X1617126Y1677519D03*
X1609252Y1681456D03*
X1617126Y1682244D03*
X1609252Y1686180D03*
X1617126Y1705866D03*
X1609252Y1709803D03*
X1617126Y1710590D03*
X1609252Y1714527D03*
X1617126Y1734212D03*
X1625000Y1672007D03*
Y1681456D03*
Y1686180D03*
Y1709803D03*
Y1714527D03*
G54D76*
X1886720Y1001463D03*
X1876720D03*
X1875836Y1303980D03*
X1885836D03*
X1886211Y1364167D03*
X1876211D03*
X1876165Y1669023D03*
X1886165D03*
X1897608Y1001506D03*
X1898086Y1305044D03*
X1897682Y1364479D03*
X1897402Y1670072D03*
X1907608Y1001506D03*
X1908086Y1305044D03*
X1907682Y1364479D03*
X1907402Y1670072D03*
X1935200Y1362732D03*
X1925200D03*
X1924695Y1670036D03*
X1934695D03*
X1946178Y1362781D03*
X1945484Y1670313D03*
X1967697Y1362790D03*
X1956178Y1362781D03*
X1966555Y1669946D03*
X1955484Y1670313D03*
X1977697Y1362790D03*
X1976555Y1669946D03*
X1988618Y1363081D03*
X1998618D03*
X1998147Y1669691D03*
X1988147D03*
G54D22*
X45812Y451602D03*
X61157Y69340D03*
X61470Y84622D03*
X62812Y412708D03*
X62813Y415750D03*
X49212Y451602D03*
X64557Y69340D03*
X72157Y75340D03*
X75557D03*
X64870Y84622D03*
X78120Y1515436D03*
Y1518836D03*
X64410Y1599102D03*
Y1602502D03*
X86557Y69340D03*
X83157D03*
X94157Y75340D03*
X90998Y1518937D03*
Y1515537D03*
X108557Y69340D03*
X105157D03*
X97557Y75340D03*
X127157Y69340D03*
X116157Y75340D03*
X119557D03*
X130557Y69340D03*
X138157Y75340D03*
X141557D03*
X152557Y69340D03*
X149157D03*
X175761D03*
X172361D03*
X161361Y75340D03*
X164761D03*
X183361D03*
X186761D03*
X197761Y69340D03*
X194361D03*
X205495Y75340D03*
X208895D03*
X194197Y1614292D03*
X197597D03*
X206257D03*
X194197Y1602380D03*
X197597D03*
X206257D03*
X219895Y69340D03*
X216495D03*
X209657Y1614292D03*
X218317D03*
X221717D03*
X209657Y1602380D03*
X218317D03*
X221717D03*
X227495Y75340D03*
X230895D03*
X230377Y1614292D03*
X233777D03*
X230377Y1602380D03*
X233777D03*
X242437Y1614292D03*
X254497D03*
X245837D03*
X242437Y1602380D03*
X254497D03*
X245837D03*
X266557Y1614292D03*
X257897D03*
X269957D03*
X266557Y1602380D03*
X257897D03*
X269957D03*
X278617Y1614292D03*
X282017D03*
X278617Y1602380D03*
X282017D03*
X290677Y1614292D03*
X302737D03*
X294077D03*
X306137D03*
X290677Y1602380D03*
X302737D03*
X294077D03*
X306137D03*
X314797Y1614292D03*
X318197D03*
X314797Y1602380D03*
X318197D03*
X330257Y1614292D03*
X338917D03*
X326857D03*
X330257Y1602380D03*
X338917D03*
X326857D03*
X350977Y1614292D03*
X342317D03*
X354377D03*
X350977Y1602380D03*
X342317D03*
X354377D03*
X363037Y1614292D03*
X366437D03*
X363037Y1602380D03*
X366437D03*
X375097Y1614292D03*
X378497D03*
X375097Y1602380D03*
X378497D03*
X478351Y1614292D03*
X481751D03*
X478351Y1602380D03*
X481751D03*
X490411Y1614292D03*
X493811D03*
X490411Y1602380D03*
X493811D03*
X514531Y1614292D03*
X502471D03*
X517931D03*
X505871D03*
X514531Y1602380D03*
X502471D03*
X517931D03*
X505871D03*
X519764Y40328D03*
X523164D03*
X519742Y71436D03*
X523142D03*
X526591Y1614292D03*
X529991D03*
X526591Y1602380D03*
X529991D03*
X538651Y1614292D03*
X542051D03*
X538651Y1602380D03*
X542051D03*
X555175Y71436D03*
X558575D03*
X562771Y1614292D03*
X550711D03*
X566171D03*
X554111D03*
X562771Y1602380D03*
X550711D03*
X566171D03*
X554111D03*
X574831Y1614292D03*
X578231D03*
X574831Y1602380D03*
X578231D03*
X598951Y1614292D03*
X586891D03*
X590291D03*
X598951Y1602380D03*
X586891D03*
X590291D03*
X613970Y188752D03*
X611011Y1614292D03*
X614411D03*
X602351D03*
X611011Y1602380D03*
X614411D03*
X602351D03*
X617370Y188752D03*
X630040D03*
X626640D03*
X623071Y1614292D03*
X626471D03*
X623071Y1602380D03*
X626471D03*
X647191Y1614292D03*
X635131D03*
X638531D03*
X647191Y1602380D03*
X635131D03*
X638531D03*
X656439Y47264D03*
X659839D03*
X662651Y1614292D03*
X659251D03*
X650591D03*
X662651Y1602380D03*
X659251D03*
X650591D03*
X723041Y-13200D03*
Y-9800D03*
Y-19800D03*
Y-23200D03*
X840001Y6800D03*
Y20200D03*
Y16800D03*
Y10200D03*
X902350Y208294D03*
X907470Y211980D03*
X902350Y204894D03*
X907470Y215380D03*
X902350Y219068D03*
X907470Y226154D03*
X902350Y222468D03*
X907470Y229554D03*
X953970Y208275D03*
X947496Y215397D03*
X953970Y204875D03*
X947496Y211997D03*
X957156Y227163D03*
X947496Y226135D03*
X957156Y230563D03*
X947496Y229535D03*
X980899Y-13200D03*
Y-9800D03*
Y-19800D03*
Y-23200D03*
Y6800D03*
Y20200D03*
Y16800D03*
Y10200D03*
X1032433Y-29811D03*
Y-33211D03*
Y-23211D03*
Y-19811D03*
Y-13211D03*
Y-9811D03*
Y-3211D03*
Y189D03*
X1156770Y638192D03*
X1153370D03*
X1161860Y642112D03*
X1165260D03*
X1173220Y636052D03*
X1169820D03*
X1183360Y642062D03*
X1186760D03*
X1196772Y1578182D03*
X1200172D03*
X1196772Y1590094D03*
X1200172D03*
X1212232Y1578182D03*
X1208832D03*
X1212232Y1590094D03*
X1208832D03*
X1220892Y1578182D03*
X1232952D03*
X1224292D03*
X1220892Y1590094D03*
X1232952D03*
X1224292D03*
X1245012Y1578182D03*
X1236352D03*
X1248412D03*
X1245012Y1590094D03*
X1236352D03*
X1248412D03*
X1257072Y1578182D03*
X1260472D03*
X1257072Y1590094D03*
X1260472D03*
X1269132Y1578182D03*
X1281192D03*
X1272532D03*
X1269132Y1590094D03*
X1281192D03*
X1272532D03*
X1290291Y-29811D03*
Y-33211D03*
Y-23211D03*
Y-19811D03*
Y-13211D03*
Y-9811D03*
Y-3211D03*
Y189D03*
X1293252Y1578182D03*
X1284592D03*
X1296652D03*
X1293252Y1590094D03*
X1284592D03*
X1296652D03*
X1305312Y1578182D03*
X1308712D03*
X1305312Y1590094D03*
X1308712D03*
X1317372Y1578182D03*
X1320772D03*
X1329432D03*
X1317372Y1590094D03*
X1320772D03*
X1329432D03*
X1341752Y-29811D03*
Y-33211D03*
Y-19811D03*
Y-23211D03*
Y-9811D03*
Y-13211D03*
Y189D03*
Y-3211D03*
X1344684Y280259D03*
X1332832Y1578182D03*
X1341492D03*
X1344892D03*
X1332832Y1590094D03*
X1341492D03*
X1344892D03*
X1348084Y280259D03*
X1358624Y284644D03*
X1355224D03*
X1353552Y1578182D03*
X1356952D03*
X1353552Y1590094D03*
X1356952D03*
X1380522Y260236D03*
Y263636D03*
X1368524Y282744D03*
X1365124D03*
X1378306Y657608D03*
X1374668Y659708D03*
X1378306Y669608D03*
X1374668Y671708D03*
Y683708D03*
X1378306Y681608D03*
X1374668Y695708D03*
X1378306Y693608D03*
Y705608D03*
X1374668Y707708D03*
Y719708D03*
X1378306Y717608D03*
X1365612Y1578182D03*
X1377672D03*
X1369012D03*
X1365612Y1590094D03*
X1377672D03*
X1369012D03*
X1384002Y197668D03*
X1389256D03*
X1380602D03*
X1392656D03*
X1380638Y245694D03*
X1386630Y238651D03*
X1380638Y249094D03*
X1386630Y242051D03*
X1388754Y253803D03*
Y257203D03*
X1386273Y268670D03*
Y272070D03*
X1393206Y664708D03*
X1389568Y662608D03*
X1393206Y679208D03*
X1389568Y677108D03*
X1393206Y693708D03*
X1389568Y691608D03*
Y706108D03*
X1393206Y708208D03*
X1393199Y722708D03*
X1389561Y720608D03*
X1385338Y735098D03*
X1388976Y737198D03*
X1381072Y1578182D03*
Y1590094D03*
X1412284Y171696D03*
X1398006Y197668D03*
X1406786D03*
X1401406D03*
X1410186D03*
X1407420Y220018D03*
X1410820D03*
X1404385Y240929D03*
X1400985D03*
X1415684Y171696D03*
X1436060Y220018D03*
X1432660D03*
X1457176Y656992D03*
X1460814Y654892D03*
Y666892D03*
X1457176Y668992D03*
X1460814Y678892D03*
X1457176Y680992D03*
X1460814Y690892D03*
X1457176Y704992D03*
Y692992D03*
X1460814Y702892D03*
X1457176Y716992D03*
X1460814Y714892D03*
X1472076Y657392D03*
Y671892D03*
X1475714Y659492D03*
Y673992D03*
X1472076Y686392D03*
X1475714Y688492D03*
X1472076Y700892D03*
X1475714Y702992D03*
X1472076Y715392D03*
X1475714Y717492D03*
X1468876Y728392D03*
X1472514Y730492D03*
X1467595Y1614292D03*
X1470995D03*
X1467595Y1602380D03*
X1470995D03*
X1482650Y-29811D03*
Y-33211D03*
Y-19811D03*
Y-23211D03*
Y-9811D03*
Y-13211D03*
Y189D03*
Y-3211D03*
X1491715Y1614292D03*
X1479655D03*
X1483055D03*
X1491715Y1602380D03*
X1479655D03*
X1483055D03*
X1503775Y1614292D03*
X1507175D03*
X1495115D03*
X1503775Y1602380D03*
X1507175D03*
X1495115D03*
X1515835Y1614292D03*
X1519235D03*
X1515835Y1602380D03*
X1519235D03*
X1538996Y69297D03*
X1535596D03*
X1527895Y1614292D03*
X1539955D03*
X1531295D03*
X1527895Y1602380D03*
X1539955D03*
X1531295D03*
X1557596Y69297D03*
X1546596Y75297D03*
X1549996D03*
X1552015Y1614292D03*
X1555415D03*
X1543355D03*
X1552015Y1602380D03*
X1555415D03*
X1543355D03*
X1560996Y69297D03*
X1568596Y75297D03*
X1571996D03*
X1564075Y1614292D03*
X1567475D03*
X1564075Y1602380D03*
X1567475D03*
X1582996Y69297D03*
X1579596D03*
X1590596Y75297D03*
X1588195Y1614292D03*
X1576135D03*
X1591595D03*
X1579535D03*
X1588195Y1602380D03*
X1576135D03*
X1591595D03*
X1579535D03*
X1604996Y69297D03*
X1601596D03*
X1593996Y75297D03*
X1600255Y1614292D03*
X1603655D03*
X1600255Y1602380D03*
X1603655D03*
X1623596Y69297D03*
X1612596Y75297D03*
X1615996D03*
X1612315Y1614292D03*
X1615715D03*
X1612315Y1602380D03*
X1615715D03*
X1626996Y69297D03*
X1635800Y75297D03*
X1639200D03*
X1636435Y1614292D03*
X1624375D03*
X1639835D03*
X1627775D03*
X1636435Y1602380D03*
X1624375D03*
X1639835D03*
X1627775D03*
X1650200Y69297D03*
X1646800D03*
X1651895Y1614292D03*
X1648495D03*
X1651895Y1602380D03*
X1648495D03*
X1672200Y69297D03*
X1668800D03*
X1657800Y75297D03*
X1661200D03*
X1679934D03*
X1683334D03*
X1694334Y69297D03*
X1690934D03*
X1705334Y75297D03*
X1701934D03*
G54D41*
X338042Y849978D03*
X331284Y978814D03*
X338211Y1118243D03*
X336361Y1121447D03*
X338211Y1131060D03*
X345178Y854584D03*
X348879Y860993D03*
X350729Y870606D03*
X354429D03*
X352578Y873810D03*
X354429Y883423D03*
X348879Y873810D03*
X347029Y877014D03*
X348878Y880219D03*
X343761Y999684D03*
X349311Y1105426D03*
X351162Y1127856D03*
X353011Y1118243D03*
X354861Y1121447D03*
X341912Y1118243D03*
X340061Y1127856D03*
X343761D03*
X347461Y1121447D03*
X340061D03*
X343761D03*
X347461Y1127856D03*
X345611Y1124651D03*
X347461Y1134264D03*
X354861D03*
X341911Y1131060D03*
X356278Y848176D03*
X371078D03*
X363678D03*
X371078Y867401D03*
X356278D03*
X363678D03*
X356278Y860993D03*
X371078D03*
X363678D03*
X358129Y870606D03*
X361829D03*
X365529D03*
X359978Y873810D03*
X367378D03*
X369229Y870606D03*
X356278Y880219D03*
X358129Y883423D03*
X363678Y880219D03*
X365529Y883423D03*
X371078Y880219D03*
X361829Y883423D03*
X369229D03*
X371078Y873810D03*
X356278D03*
X363678D03*
X363679Y893036D03*
X367379D03*
X359978Y886627D03*
X367378D03*
X363678D03*
X371078D03*
X367811Y1002888D03*
Y1105426D03*
X369661Y1102221D03*
X358562D03*
X360412Y1105426D03*
X358561Y1108630D03*
X360412Y1111834D03*
X364112Y1105426D03*
X369661Y1108630D03*
X362261D03*
X365961D03*
X367812Y1111834D03*
X369662Y1121447D03*
X362261D03*
X365961Y1115039D03*
X358561D03*
X369661D03*
X369662Y1134264D03*
X362262D03*
X385878Y848176D03*
X378478D03*
Y867401D03*
X385878D03*
X378478Y860993D03*
X385878D03*
X387729Y870606D03*
X372929D03*
X380329D03*
X374778Y873810D03*
X376629Y870606D03*
X382178Y873810D03*
X384029Y870606D03*
X372929Y883423D03*
X378478Y880219D03*
X380329Y883423D03*
X385878Y880219D03*
X387729Y883423D03*
X376629D03*
X384029D03*
X378478Y873810D03*
X385878D03*
X374778Y886627D03*
X382178D03*
X378478D03*
X385878D03*
X387729Y909057D03*
Y902649D03*
X385878Y905853D03*
X387729Y921875D03*
Y928283D03*
X385878Y925079D03*
X387729Y947509D03*
Y941100D03*
X385878Y944304D03*
X387729Y960326D03*
Y966735D03*
X385878Y963530D03*
Y982756D03*
X387729Y979552D03*
X376629D03*
X380329D03*
X374778Y976347D03*
X382178D03*
X372929Y973143D03*
X384029D03*
X386311Y1015705D03*
Y1034931D03*
Y1054157D03*
Y1073383D03*
Y1092608D03*
X375211Y1099017D03*
X380762Y1095813D03*
X382611Y1099017D03*
X384462Y1121447D03*
X377062D03*
X384462Y1134264D03*
X377062D03*
X400678Y848176D03*
X393278D03*
X400678Y867401D03*
X393278D03*
X400678Y860993D03*
X393278D03*
X391429Y870606D03*
X395129D03*
X402529D03*
X389578Y873810D03*
X396978D03*
X398829Y870606D03*
X393278Y880219D03*
X395129Y883423D03*
X400678Y880219D03*
X402529Y883423D03*
X391429D03*
X398829D03*
X393278Y873810D03*
X400678D03*
X402529Y896240D03*
X400678Y899445D03*
X389578D03*
X393278D03*
X393279Y893036D03*
X396979D03*
X396978Y886627D03*
X389578D03*
X398829Y896240D03*
X400678Y893036D03*
X393278Y886627D03*
X400678D03*
X404378Y899445D03*
X400678Y905853D03*
X402529Y915466D03*
Y909057D03*
X389578Y912262D03*
X393278D03*
X395129Y909057D03*
Y902649D03*
X393278Y905853D03*
X389578D03*
X396978D03*
X406229Y915466D03*
X400678Y912262D03*
X402529Y902649D03*
X400678Y931488D03*
X402529Y928283D03*
Y921875D03*
X393278Y931488D03*
X395129Y928283D03*
X389578Y918670D03*
X395129Y921875D03*
X393278Y918670D03*
X389578Y931488D03*
X393278Y925079D03*
X389578D03*
X396978D03*
X398829Y934691D03*
X402529D03*
X395129Y947509D03*
X389578Y937896D03*
X395129Y941100D03*
X393278Y937896D03*
Y944304D03*
X389578D03*
X396978D03*
X402529Y941100D03*
X400679Y944304D03*
X402529Y947509D03*
X389578Y957122D03*
X395129Y960326D03*
X393278Y957122D03*
X395129Y966735D03*
X389578Y950713D03*
X393278D03*
X396978Y963530D03*
X393278D03*
X389578D03*
X402529Y966735D03*
Y960326D03*
X398829Y953917D03*
X402529D03*
X400680Y950713D03*
X393278Y982756D03*
X389578D03*
X396978D03*
X393278Y976347D03*
X395129Y979552D03*
X389579Y976347D03*
X389578Y969939D03*
X393278D03*
X399262Y1006093D03*
X402962D03*
X399262Y999684D03*
X402962D03*
X388162Y1012501D03*
X395562D03*
X390011Y1009297D03*
X393711D03*
X401111D03*
X402962Y1012501D03*
Y1031727D03*
X397411Y1015705D03*
X388162Y1031727D03*
X390011Y1028523D03*
X395562Y1031727D03*
X393711Y1028523D03*
X390011Y1022114D03*
X388162Y1018910D03*
X393711Y1022114D03*
X395562Y1018910D03*
X401111Y1028523D03*
Y1022114D03*
X402960Y1018910D03*
X402962Y1025318D03*
X399262D03*
X401111Y1015705D03*
X390011Y1041340D03*
X388162Y1038136D03*
X393711Y1041340D03*
X395562Y1038136D03*
X390011Y1047749D03*
X393711D03*
Y1034931D03*
X390011D03*
X397411D03*
X401111Y1047749D03*
X399262Y1044544D03*
X402962D03*
X401111Y1041340D03*
X402962Y1038136D03*
X406662Y1057361D03*
X390011Y1060565D03*
X388162Y1057361D03*
X393711Y1060565D03*
X395562Y1057361D03*
X388162Y1050952D03*
X395562D03*
X393711Y1054157D03*
X390011D03*
X397411D03*
X402962Y1057361D03*
Y1063770D03*
X401113Y1060565D03*
X399262Y1063770D03*
X401111Y1054157D03*
X402962Y1050952D03*
Y1076587D03*
Y1070178D03*
X390011Y1079791D03*
X388162Y1076587D03*
X393711Y1079791D03*
X395562Y1076587D03*
X388162Y1070178D03*
X390011Y1066974D03*
X395562Y1070178D03*
X393711Y1066974D03*
Y1073383D03*
X390011D03*
X397411D03*
X401112Y1066974D03*
X395562Y1095813D03*
X388162Y1089404D03*
X390011Y1086200D03*
X395562Y1089404D03*
X393711Y1086200D03*
X388162Y1095813D03*
X393711Y1092608D03*
X390011D03*
X397411D03*
X399262Y1082995D03*
X393711Y1099017D03*
X390011D03*
X391862Y1102221D03*
X393711Y1105426D03*
X401111Y1099017D03*
X391862Y1108630D03*
X393711Y1111834D03*
X397411Y1105426D03*
X402962Y1108630D03*
Y1102221D03*
X395562Y1108630D03*
X399262D03*
X401111Y1111834D03*
X391862Y1121447D03*
X399262Y1115039D03*
X391862D03*
X402962D03*
X399262Y1121447D03*
X391862Y1134264D03*
X399262D03*
X408078Y848176D03*
X415478D03*
X408078Y867401D03*
X415478D03*
Y860993D03*
X408078D03*
X404378Y873810D03*
X406229Y870606D03*
X408078Y880219D03*
X409929Y883423D03*
X406229D03*
X419178Y873810D03*
X417329Y870606D03*
X411778Y873810D03*
X413629Y870606D03*
X415478Y873810D03*
X408078D03*
X404378Y886627D03*
X411778D03*
X404378Y893036D03*
X415478Y886627D03*
X408078D03*
X406229Y896240D03*
X408078Y899445D03*
X415478D03*
X409929Y896240D03*
X415478Y893036D03*
X417329Y896240D03*
X422878Y893036D03*
X411778Y899445D03*
X413629Y896240D03*
X419178Y899445D03*
X422878Y912262D03*
X417329Y909057D03*
X406229D03*
X413629D03*
Y915466D03*
X411778Y905853D03*
X408078D03*
Y912262D03*
X406229Y902649D03*
X415478Y905853D03*
X411778Y912262D03*
X415478D03*
X417329Y915466D03*
X411779Y918670D03*
X406229Y921875D03*
X408078Y918670D03*
X408569Y929108D03*
X406308Y928626D03*
X417329Y921875D03*
X411872Y925264D03*
X415479Y918670D03*
X407589Y942164D03*
X405289D03*
X409889D03*
X415185Y956620D03*
X411685D03*
X409385D03*
X417685D03*
X404785Y971100D03*
X407085D03*
X409385D03*
X411685D03*
X420205D03*
X412365Y985610D03*
X410065D03*
X420145Y985550D03*
X409385Y1014540D03*
X407085D03*
X411685D03*
X412385Y1000080D03*
X410085D03*
X420215Y1000040D03*
X420405Y1014470D03*
X414461Y1028855D03*
X411961D03*
X416961D03*
X419461D03*
X415911Y1047749D03*
X419611D03*
X406662Y1044544D03*
X410362D03*
X408511Y1047749D03*
X414062Y1044544D03*
X404811Y1041340D03*
X412211D03*
X415911D03*
X419611D03*
X406662Y1050952D03*
X414060D03*
X417762Y1057361D03*
X421462Y1050952D03*
X419611Y1054157D03*
X406662Y1063770D03*
X408511Y1060565D03*
X410362Y1063770D03*
X412211Y1054157D03*
X404811D03*
X414062Y1057361D03*
X410362D03*
X417762Y1063770D03*
X414062D03*
X419611Y1060565D03*
Y1079791D03*
X408511Y1073383D03*
X406662Y1070178D03*
X404811Y1073383D03*
X417762Y1076587D03*
X408511Y1066974D03*
X415911Y1079791D03*
X412211Y1073383D03*
X415911D03*
X414062Y1070178D03*
X417762D03*
X412211Y1066974D03*
X419611D03*
X419612Y1099017D03*
X404811Y1092608D03*
X417762Y1095813D03*
X414061D03*
X404811Y1099017D03*
X408511Y1105426D03*
X412211Y1111834D03*
X415911D03*
X414062Y1102221D03*
X417762Y1108630D03*
X419611Y1105426D03*
X408511Y1099017D03*
X410362Y1108630D03*
X408511Y1111834D03*
X412211Y1105426D03*
X419611Y1111834D03*
X415911Y1105426D03*
X415912Y1124651D03*
X419612D03*
Y1118243D03*
X417761Y1121447D03*
Y1127856D03*
X414062Y1115039D03*
X406661Y1121447D03*
X414062Y1127856D03*
X406662Y1134264D03*
X415912Y1137469D03*
Y1131060D03*
X414061Y1140973D03*
X419612Y1137469D03*
Y1131060D03*
X417761Y1134264D03*
Y1140973D03*
X412212Y1137469D03*
X422878Y848176D03*
X430278Y867401D03*
X422878D03*
X430278Y860993D03*
X422878D03*
X432129Y870606D03*
X426578Y873810D03*
X424729Y870606D03*
X433979Y873810D03*
X428429Y870606D03*
X421029D03*
X435829D03*
X422878Y873810D03*
X430278D03*
X422878Y886627D03*
X430278D03*
Y899445D03*
X422878D03*
X424729Y896240D03*
X430278Y893036D03*
X432129Y896240D03*
X437678Y893036D03*
X421029Y896240D03*
X426578Y899445D03*
X428429Y896240D03*
X433978Y899445D03*
X435829Y896240D03*
X424729Y915466D03*
X426578Y912262D03*
X430278D03*
X432129Y915466D03*
X421029Y909057D03*
X435829D03*
Y915466D03*
X432128Y909057D03*
X433978Y905853D03*
X424728Y909057D03*
X422878Y905853D03*
X430278D03*
X426578D03*
X421029Y915466D03*
X433979Y912262D03*
X430278Y918670D03*
X432129Y921875D03*
X433979Y918670D03*
X435829Y921875D03*
X424927Y927255D03*
X423176Y929465D03*
X422427Y927255D03*
X425676Y929465D03*
X424729Y921875D03*
X422878Y918670D03*
X421029Y921875D03*
X426578Y918670D03*
X430279Y925079D03*
X432130Y928283D03*
X430279Y931487D03*
X432130Y934692D03*
X435830Y928283D03*
X427875Y941930D03*
Y944230D03*
X430280Y944305D03*
X432130Y941101D03*
X435830D03*
X432129Y947510D03*
X435830D03*
Y934692D03*
X427875Y956373D03*
Y954073D03*
X422685Y956620D03*
X425185D03*
X430280Y957123D03*
X432129Y960327D03*
Y953918D03*
X430280Y950714D03*
X435830Y960327D03*
Y953918D03*
X432129Y966736D03*
X430280Y963531D03*
X435830Y966736D03*
X430268Y976348D03*
X432129Y973144D03*
X430280Y969940D03*
X427875Y971267D03*
X422685Y971100D03*
X427875Y968967D03*
X435830Y973144D03*
X430280Y982757D03*
X432129Y979553D03*
X427875Y983111D03*
X435830Y979553D03*
X422685Y985580D03*
X427875Y985411D03*
Y997521D03*
X430712Y1009298D03*
X427875Y1012152D03*
X430712Y1002889D03*
X427875Y999821D03*
X422685Y1000060D03*
X436263Y1006094D03*
Y999685D03*
X432562Y1006094D03*
Y999685D03*
X427875Y1014452D03*
X423015Y1014470D03*
X436263Y1012502D03*
X432562D03*
X421961Y1028855D03*
X430712Y1022115D03*
Y1015706D03*
X427875Y1026704D03*
X430712Y1028524D03*
X436263Y1018911D03*
X432562D03*
Y1025319D03*
X436263D03*
X427875Y1029004D03*
Y1031304D03*
X436263Y1031728D03*
X432562D03*
X427011Y1047749D03*
X427012Y1041340D03*
X423312D03*
X425162Y1044544D03*
X423285Y1036884D03*
X430711Y1041340D03*
X430712Y1034932D03*
X427875Y1033604D03*
X423285Y1032284D03*
Y1034584D03*
X436262Y1038137D03*
X436261Y1044544D03*
X432562Y1038137D03*
X434412Y1041340D03*
X432561Y1044544D03*
X434412Y1047749D03*
X421462Y1044544D03*
X427011Y1054157D03*
X430711D03*
X428861Y1057361D03*
X432561D03*
X421462D03*
X425162Y1050952D03*
X423311Y1054157D03*
X428862Y1050952D03*
X436262Y1057361D03*
Y1050952D03*
Y1063770D03*
X425162D03*
X423311Y1060565D03*
X427011D03*
X428861Y1063770D03*
X430711Y1060565D03*
X423311Y1073383D03*
X432560Y1070178D03*
X421462Y1076587D03*
X423311Y1079791D03*
X436262Y1070178D03*
Y1076587D03*
X421462Y1070178D03*
X425162D03*
X428862D03*
X430711Y1066974D03*
X428861Y1076587D03*
X430711Y1079791D03*
X436262Y1082995D03*
Y1089404D03*
X436261Y1095813D03*
X421462Y1102221D03*
X423311Y1099017D03*
X428861Y1108630D03*
X427012Y1105426D03*
X425162Y1108630D03*
X430711Y1105426D03*
Y1099017D03*
X428861Y1102221D03*
X436262Y1108630D03*
Y1102221D03*
X432561Y1108630D03*
Y1102221D03*
X434412Y1099017D03*
X430711Y1111834D03*
X427012D03*
X430711Y1124651D03*
X428861Y1121447D03*
X427012Y1124651D03*
X425162Y1121447D03*
X421461D03*
X430711Y1118243D03*
X428861Y1115039D03*
X427012Y1118243D03*
X425162Y1115039D03*
X436262Y1121447D03*
Y1115039D03*
X432561Y1121447D03*
Y1115039D03*
X428861Y1127856D03*
X425162D03*
X421461D03*
X436262D03*
X432561D03*
X430711Y1137769D03*
X427012Y1137569D03*
X430711Y1131060D03*
X428861Y1134264D03*
X427012Y1131060D03*
X425162Y1134264D03*
X421461D03*
X428861Y1140973D03*
X425161D03*
X421461D03*
X436261Y1134264D03*
X432561D03*
X452478Y867401D03*
X445078D03*
X437678D03*
X445078Y860993D03*
X452479D03*
X448779Y873810D03*
X446929Y870606D03*
X441378Y873810D03*
X439529Y870606D03*
X450629D03*
X443229D03*
X437679Y873810D03*
X452479D03*
X445078D03*
X452478Y886627D03*
X445078D03*
X452478Y899445D03*
X441378D03*
X445078Y893036D03*
X446929Y896240D03*
X452479Y893036D03*
X445078Y899445D03*
X443229Y896240D03*
X448778Y899445D03*
X450630Y896240D03*
X443229Y909057D03*
X439529Y915466D03*
X445079Y905853D03*
X441379D03*
X450630Y909057D03*
X452479Y905853D03*
X448779D03*
X448780Y912262D03*
X441380D03*
X439529Y909057D03*
X445080Y912262D03*
X443229Y915466D03*
X450629D03*
X452478Y912262D03*
X448779Y918670D03*
X454329Y915466D03*
X439529Y921875D03*
X441378Y918670D03*
X450629Y921875D03*
X445078Y918670D03*
X443229Y921875D03*
X452478Y918670D03*
X446930Y934692D03*
X443230Y928283D03*
X448780Y931487D03*
X437679D03*
X450630Y928283D03*
X448780Y925079D03*
X445079Y931487D03*
X439530Y934692D03*
X445079Y925079D03*
X439530Y928283D03*
X437679Y925079D03*
X437680Y944305D03*
X441380D03*
X443230Y941101D03*
X445079Y944305D03*
X439530Y941101D03*
X450630D03*
X448780Y944305D03*
X443229Y947510D03*
X439529D03*
X450630D03*
X443230Y934692D03*
X445079Y957123D03*
X437680D03*
X441380D03*
X439529Y960327D03*
X443229D03*
Y953918D03*
X439529D03*
X437680Y950714D03*
X441380D03*
X445079D03*
X448780Y957123D03*
X450630Y953918D03*
Y960327D03*
X448780Y950714D03*
X445079Y963531D03*
X437680D03*
X441380D03*
X439529Y966736D03*
X443229D03*
X448780Y963531D03*
X450630Y966736D03*
X445079Y976348D03*
Y969940D03*
X439529Y973144D03*
X443229D03*
X437680Y976348D03*
X441380D03*
X437680Y969940D03*
X441380D03*
X450630Y973144D03*
X448780Y976348D03*
Y969940D03*
X445079Y982757D03*
X437680D03*
X441380D03*
X439529Y979553D03*
X443229D03*
X448780Y982757D03*
X450630Y979553D03*
X439962Y1006094D03*
X443662D03*
X445511Y1009298D03*
X438113D03*
X441813D03*
X445512Y1002889D03*
X438113D03*
X441813D03*
X439962Y999685D03*
X443662D03*
X451062Y1006094D03*
X449213Y1009298D03*
Y1002889D03*
X451062Y999685D03*
X439962Y1012502D03*
X443662D03*
X451062D03*
X445511Y1022115D03*
X438113D03*
X441813D03*
X445512Y1015706D03*
X438113D03*
X439962Y1018911D03*
X441813Y1015706D03*
X443662Y1018911D03*
Y1025319D03*
X439962D03*
X445511Y1028524D03*
X441813D03*
X438113D03*
X449213Y1022115D03*
X451062Y1018911D03*
X449213Y1015706D03*
X451062Y1025319D03*
X449213Y1028524D03*
X439962Y1031728D03*
X443662D03*
X451062D03*
X452911Y1047749D03*
X439962Y1038137D03*
X443662D03*
X438112Y1041340D03*
X439961Y1044544D03*
X441812Y1041340D03*
X443661Y1044544D03*
X447361D03*
X445511Y1041340D03*
X445512Y1034932D03*
X438113D03*
X441813D03*
X451062Y1038137D03*
X449211Y1041340D03*
X449213Y1034932D03*
X445510Y1047749D03*
X441812D03*
X438112D03*
X449211Y1054157D03*
X449213Y1060565D03*
X438112D03*
Y1054157D03*
X439961Y1057361D03*
X441812Y1054157D03*
Y1060565D03*
X443661Y1057361D03*
X445511Y1060565D03*
Y1054157D03*
X439961Y1050952D03*
X443661D03*
X439961Y1063770D03*
X443661D03*
X451061D03*
X452911Y1054157D03*
X451062Y1050952D03*
X454762D03*
Y1057361D03*
X451062D03*
X451061Y1076587D03*
X452911Y1073383D03*
X439961Y1076587D03*
Y1070178D03*
X441812Y1073383D03*
X438112D03*
X443661Y1070178D03*
Y1076587D03*
X445511Y1073383D03*
X441812Y1066974D03*
X438112D03*
X445511D03*
X441812Y1079791D03*
X438112D03*
X445511D03*
X452911Y1066974D03*
X449211D03*
X451062Y1070178D03*
X452911Y1086200D03*
X443661Y1082995D03*
X439961D03*
X441812Y1086200D03*
X445511D03*
X439961Y1089404D03*
X441812Y1092608D03*
X438112D03*
X443661Y1089404D03*
X445511Y1092608D03*
X447361Y1089404D03*
X438112Y1086200D03*
X449211Y1092608D03*
X439961Y1095813D03*
X443661D03*
X447361D03*
X451060Y1082995D03*
X441812Y1105426D03*
X438112D03*
X439961Y1108630D03*
X443661D03*
X445511Y1105426D03*
X439961Y1102221D03*
X441812Y1099017D03*
X438112D03*
X443661Y1102221D03*
X445511Y1099017D03*
X452912Y1105426D03*
X451061Y1108630D03*
X449212Y1105426D03*
X451061Y1102221D03*
X449212Y1099017D03*
X441812Y1111834D03*
X438112D03*
X445511D03*
X452912D03*
X449212D03*
X438112Y1124651D03*
X439961Y1121447D03*
X441812Y1124651D03*
X445511D03*
X443661Y1121447D03*
X438112Y1118243D03*
X441812D03*
X439961Y1115039D03*
X445511Y1118243D03*
X443661Y1115039D03*
X452912Y1124651D03*
Y1118243D03*
X451061Y1121447D03*
X449212Y1124651D03*
Y1118243D03*
X451061Y1115039D03*
X439961Y1127856D03*
X443661D03*
X451061D03*
X441812Y1137769D03*
X438112D03*
X445511D03*
X443661Y1134264D03*
X441812Y1131060D03*
X439961Y1134264D03*
X438112Y1131060D03*
X445511D03*
X452912Y1137769D03*
Y1131060D03*
X449212Y1137769D03*
Y1131060D03*
X451061Y1134264D03*
X459878Y848176D03*
X467278D03*
Y867401D03*
X459878D03*
Y860993D03*
X467278D03*
X469129Y870606D03*
X463578Y873810D03*
X461729Y870606D03*
X456178Y873810D03*
X454329Y870606D03*
X465429D03*
X458029D03*
X467278Y873810D03*
X459878D03*
Y886627D03*
X467278D03*
X459878Y899445D03*
X467278D03*
X454329Y896240D03*
X459878Y893036D03*
X461729Y896240D03*
X467278Y893036D03*
X456178Y899445D03*
X458029Y896240D03*
X463578Y899445D03*
X465429Y896240D03*
X470978Y899445D03*
X463578Y905853D03*
X470980Y912262D03*
X469129Y902649D03*
X454329Y909057D03*
X470978Y918670D03*
X467278Y912262D03*
X469129Y915466D03*
X458029Y909057D03*
X459878Y905853D03*
X461729Y915466D03*
X467278Y905853D03*
X461729Y909057D03*
X458029Y915466D03*
X459878Y918670D03*
X463578Y912262D03*
X459878D03*
X469129Y909057D03*
X467278Y918670D03*
X454329Y921875D03*
X468236Y928349D03*
X465936D03*
X463636D03*
X461336D03*
X459036D03*
X469129Y921875D03*
X463578Y918670D03*
X465429Y921875D03*
X458029D03*
X469251Y942246D03*
X453585Y942238D03*
Y939938D03*
Y944538D03*
X453403Y956999D03*
X461424Y956620D03*
X458404D03*
X453403Y959299D03*
X468904Y956620D03*
Y971100D03*
X458404D03*
X461424Y971140D03*
X453403Y973099D03*
Y970799D03*
Y986899D03*
X461424Y985580D03*
X458404D03*
X453403Y984599D03*
X468904Y985580D03*
X453403Y998399D03*
Y1012199D03*
X458404Y1000080D03*
X461424D03*
X453403Y1000699D03*
X468904Y1000080D03*
X458404Y1014540D03*
X461295Y1014510D03*
X453403Y1014499D03*
X465680Y1028855D03*
X463180D03*
X460680D03*
X458180D03*
X457942Y1031909D03*
X467711Y1047750D03*
X460311D03*
X471411Y1041340D03*
X467711D03*
X454762Y1044544D03*
Y1038136D03*
X460971Y1037069D03*
X463271D03*
X458671D03*
X457942Y1034409D03*
X456611Y1041340D03*
X464011D03*
X462162Y1044544D03*
X458462D03*
X464011Y1054157D03*
X465860Y1050952D03*
X456611Y1060565D03*
X462161Y1057361D03*
Y1063770D03*
X460312Y1054157D03*
X458462Y1057361D03*
X467712Y1054157D03*
Y1060565D03*
X454761Y1063770D03*
X464012Y1060565D03*
X458460Y1050952D03*
X460311Y1060565D03*
Y1073383D03*
X458460Y1070178D03*
X460311Y1066974D03*
X464011D03*
X465860Y1070178D03*
X469560D03*
X464012Y1079791D03*
X460312D03*
X462162Y1076587D03*
X456611Y1066974D03*
X465862Y1076587D03*
X464011Y1073383D03*
X458462Y1076587D03*
X465862Y1082995D03*
X462162D03*
X462161Y1095812D03*
X458461D03*
X465861Y1089403D03*
X456612Y1092607D03*
X454761Y1089403D03*
X460311Y1086200D03*
X454760Y1082995D03*
X465861Y1095812D03*
X464012Y1092607D03*
X454761Y1095812D03*
X458461Y1089403D03*
X462161D03*
X467711Y1099017D03*
X462162Y1102221D03*
X458461Y1108630D03*
X456612Y1105426D03*
X454761Y1108630D03*
Y1102221D03*
X460312Y1111834D03*
X456611D03*
X460312Y1099016D03*
X464012Y1124651D03*
X462161Y1121447D03*
X460312Y1124651D03*
X456611D03*
X454761Y1121447D03*
X464011Y1118243D03*
X462161Y1115039D03*
X460312Y1118243D03*
X456611D03*
X454761Y1115039D03*
X462161Y1127856D03*
X454761D03*
X465861D03*
X464012Y1137469D03*
X460312D03*
X456612D03*
X464012Y1131060D03*
X462161Y1134264D03*
X460312Y1131060D03*
X456611D03*
X454761Y1134264D03*
X462161Y1140973D03*
X458461D03*
X454761D03*
X467712Y1137469D03*
X465861Y1134264D03*
X467712Y1131060D03*
X465861Y1140973D03*
X474678Y848176D03*
X482078D03*
X474678Y867401D03*
X482078D03*
X474678Y860993D03*
X482078D03*
X480229Y870606D03*
X476529D03*
X478378Y873810D03*
X483929Y870606D03*
X474678Y880219D03*
X476529Y883423D03*
X482078Y880219D03*
X483929Y883423D03*
X472829D03*
X480229D03*
X474678Y873810D03*
X482078D03*
X474678Y893036D03*
X472829Y896240D03*
X482078Y893036D03*
X483929Y896240D03*
X478378Y886627D03*
Y899445D03*
X474678Y886627D03*
X482078D03*
X476529Y896240D03*
Y915466D03*
X478380Y912262D03*
X478379Y918670D03*
X480229Y902649D03*
X483929Y915466D03*
X480229D03*
X472828D03*
X472829Y902649D03*
X480228Y909057D03*
X482078Y905853D03*
X476529Y902649D03*
X470978Y905853D03*
X478378D03*
X472829Y909057D03*
X476529D03*
X480229Y928283D03*
X478378Y931488D03*
Y925079D03*
X482078D03*
X472829Y921875D03*
X470536Y928349D03*
X478378Y937896D03*
X480229Y941100D03*
X483929Y934691D03*
X480229Y947509D03*
X471550Y942152D03*
X473851Y942246D03*
X478378Y963530D03*
X483929Y953917D03*
X480228Y960326D03*
X478378Y950713D03*
X480229Y953917D03*
X478378Y957122D03*
X471404Y956620D03*
X480229Y966735D03*
X482078Y963529D03*
X483929Y973143D03*
X482078Y982756D03*
X478379Y969939D03*
X476285Y973826D03*
Y971526D03*
X471404Y971100D03*
X473904D03*
X480229Y979552D03*
X478378Y982756D03*
X480229Y973143D03*
X478378Y976347D03*
X471404Y985580D03*
X480662Y999684D03*
X478811Y1002888D03*
Y1009297D03*
X480662Y1012501D03*
X484362Y1006093D03*
X471404Y1000080D03*
X484362Y1025318D03*
X480662Y1031727D03*
X482511Y1015705D03*
X480661Y1018910D03*
X478811Y1022114D03*
Y1028523D03*
Y1015705D03*
X476325Y1031795D03*
Y1027195D03*
Y1029495D03*
X470724Y1028827D03*
X480662Y1025318D03*
X484362Y1044544D03*
X475111Y1047749D03*
X469562Y1044544D03*
X478811Y1034931D03*
X480662Y1038136D03*
X478811Y1041340D03*
X480662Y1044544D03*
X473262D03*
X476962D03*
X478811Y1047749D03*
X484362Y1063770D03*
X473261Y1057361D03*
X471412Y1060565D03*
X475112Y1054157D03*
X469562Y1063770D03*
X469561Y1057361D03*
X473262Y1063770D03*
X469561Y1050952D03*
X473262D03*
X482511Y1054157D03*
X480662Y1063770D03*
X480661Y1057361D03*
X478812Y1060565D03*
X476962Y1063770D03*
Y1057361D03*
X478812Y1054157D03*
X476961Y1050952D03*
X478811Y1066974D03*
X471411D03*
X476962Y1076587D03*
X480662D03*
Y1070178D03*
X476962D03*
X473262Y1076587D03*
X469562D03*
X471411Y1073383D03*
Y1079791D03*
X475111Y1073383D03*
X482511D03*
X484362Y1082995D03*
X473262Y1095813D03*
X469562Y1082995D03*
X480662Y1089404D03*
X478812Y1092607D03*
X475112D03*
X473261Y1089403D03*
X471412Y1086199D03*
X476961Y1082994D03*
X482512Y1092607D03*
X476961Y1095812D03*
X471412Y1092607D03*
X475112Y1086199D03*
X478812D03*
X480662Y1102221D03*
X473262Y1121447D03*
X480662D03*
Y1134264D03*
X469561D03*
X489478Y848176D03*
X496878D03*
X489478Y867401D03*
X496878D03*
X489478Y860993D03*
X496878D03*
X487629Y870606D03*
X495029D03*
X485778Y873810D03*
X491329Y870606D03*
X493178Y873810D03*
X498729Y870606D03*
X500578Y873810D03*
X489478Y880219D03*
X491329Y883423D03*
X496878Y880219D03*
X498729Y883423D03*
X487629D03*
X495029D03*
X496878Y873810D03*
X489478D03*
X485778Y899445D03*
X493178D03*
Y893036D03*
X496878D03*
X485778D03*
X491329Y896240D03*
X487629D03*
X495029D03*
X485778Y886627D03*
X493178D03*
X500578D03*
X489478D03*
X496878D03*
X485778Y912262D03*
X487629Y909057D03*
X493178Y912262D03*
X491329Y909057D03*
X487629Y902649D03*
X491329D03*
X487629Y915466D03*
X495029D03*
X491329D03*
Y921875D03*
X493178Y918670D03*
X485778Y931488D03*
X491329Y928283D03*
X493178Y931488D03*
X487629Y928283D03*
Y921875D03*
X485778Y918670D03*
X487629Y947509D03*
X491329D03*
X487629Y941100D03*
X485778Y937896D03*
X491329Y941100D03*
X493178Y937896D03*
X487629Y934691D03*
X495029D03*
X491329D03*
X487629Y966735D03*
X491329D03*
X498729D03*
X496878Y963530D03*
X485778Y950713D03*
X493178D03*
X491329Y960326D03*
X493178Y957122D03*
X487629Y960326D03*
X485778Y957122D03*
X495029Y953917D03*
X487629D03*
X491329D03*
X495029Y973143D03*
X487629D03*
X491329D03*
X485778Y969939D03*
X493178D03*
X500578D03*
X495462Y1006093D03*
X486211Y1002888D03*
X493611D03*
X488062Y999684D03*
X491762D03*
X491761Y1012501D03*
X493611Y1009297D03*
X488062Y1012501D03*
X486211Y1009297D03*
X488062Y1031727D03*
X486211Y1028523D03*
X491762Y1031727D03*
X493611Y1028523D03*
X486211Y1022114D03*
X488062Y1018910D03*
X493611Y1022114D03*
X491762Y1018910D03*
X488062Y1025318D03*
X495462D03*
X491762D03*
X486211Y1047749D03*
X493611D03*
X486211Y1041340D03*
X488062Y1038136D03*
X493611Y1041340D03*
X491762Y1038136D03*
X488062Y1044544D03*
X495462D03*
X491762D03*
X486211Y1060565D03*
X488062Y1057361D03*
X493611Y1060565D03*
X491762Y1057361D03*
X488062Y1050952D03*
X491762D03*
X488062Y1063770D03*
X495462D03*
X491762D03*
X486211Y1079791D03*
X488062Y1076587D03*
X493611Y1079791D03*
X491762Y1076587D03*
X488062Y1070178D03*
X486211Y1066974D03*
X491762Y1070178D03*
X493611Y1066974D03*
X491762Y1089404D03*
X493611Y1086200D03*
X488062Y1089404D03*
X486211Y1086200D03*
X495462Y1082995D03*
X488062D03*
X491762D03*
X488062Y1095813D03*
X501012Y1105426D03*
Y1111833D03*
X488062Y1115039D03*
Y1121447D03*
X495462Y1134264D03*
X488062D03*
X511678Y848176D03*
X504278D03*
X511678Y867401D03*
X504278D03*
X511678Y860993D03*
X504278D03*
X517229Y870606D03*
X502429D03*
X509829D03*
X513529D03*
X515378Y873810D03*
X506129Y870606D03*
X507978Y873810D03*
X511678Y880219D03*
X513529Y883423D03*
X504278Y880219D03*
X506129Y883423D03*
X509829D03*
X517229D03*
X502429D03*
X511678Y873810D03*
X504278D03*
X515378Y886627D03*
X507978D03*
X511678D03*
X504278D03*
X506129Y966735D03*
X507978Y963530D03*
X504278Y969939D03*
X502862Y1006093D03*
X510262Y1102221D03*
X502861Y1108629D03*
X512112Y1105426D03*
X508412Y1111833D03*
X506561Y1102220D03*
X504712Y1111833D03*
Y1105426D03*
X510261Y1108630D03*
X512112Y1111833D03*
X508412Y1105426D03*
X502862Y1115039D03*
X510262Y1121447D03*
X502862D03*
X517662D03*
X506561Y1115038D03*
X510262Y1134264D03*
X502862D03*
X517662D03*
X519078Y848176D03*
Y867401D03*
X526479D03*
Y860993D03*
X519078D03*
X524629Y870606D03*
X532029D03*
X520929D03*
X522778Y873810D03*
X528329Y870606D03*
X530178Y873810D03*
X519078Y880219D03*
X520929Y883423D03*
X526479Y880219D03*
X528329Y883423D03*
X524629D03*
X526479Y873810D03*
X519078D03*
X530178Y893036D03*
X522778Y886627D03*
X530179D03*
X526479D03*
X519078D03*
X533879D03*
X528762Y1102221D03*
X525062D03*
X523212Y1099017D03*
X530611Y1105426D03*
X526911Y1118243D03*
X525062Y1121447D03*
X534311Y1118243D03*
X532461Y1121446D03*
X534311Y1124650D03*
X532461Y1127855D03*
X525062Y1134264D03*
X528761Y1140973D03*
X532461D03*
X541711Y1118243D03*
X538010Y1118242D03*
X543561Y1121446D03*
X539861Y1127855D03*
X536161D03*
Y1121446D03*
X539861D03*
X541711Y1124650D03*
X543561Y1127855D03*
X538012Y1131059D03*
X650599Y766798D03*
X918264Y506011D03*
X1030780Y1266532D03*
X1074480Y1263742D03*
X1181941Y766798D03*
X1297012Y157449D03*
X1293802Y159299D03*
Y166699D03*
X1293511Y179048D03*
X1296999Y183349D03*
X1297007Y172249D03*
X1296999Y175949D03*
X1293802Y170399D03*
X1294163Y175865D03*
X1296999Y179649D03*
Y194449D03*
Y198149D03*
Y190749D03*
Y187049D03*
Y201849D03*
X1293805Y211099D03*
X1293798Y205833D03*
X1296999Y216649D03*
X1293807Y218499D03*
Y214799D03*
X1296999Y212949D03*
Y205549D03*
X1294357Y224688D03*
X1296999Y224049D03*
X1293807Y222199D03*
X1300393Y235762D03*
X1303417Y164849D03*
X1300213Y162999D03*
X1300212Y166699D03*
X1306622D03*
X1309832Y157449D03*
X1306626Y162999D03*
Y159299D03*
X1313037Y162999D03*
X1309832Y164849D03*
X1313037Y159299D03*
X1303417Y157449D03*
X1300217Y159299D03*
X1313033Y166699D03*
X1300212Y170399D03*
X1306626D03*
X1303407Y183349D03*
X1309817Y175949D03*
X1300212Y174099D03*
X1313037Y170399D03*
X1306617Y185199D03*
X1309832Y172249D03*
X1313027Y181499D03*
Y185199D03*
X1303407Y175949D03*
Y179649D03*
X1306617Y177799D03*
X1309817Y179649D03*
X1300204Y181499D03*
X1309817Y194449D03*
X1306617Y188899D03*
X1303407Y194449D03*
X1306617Y196299D03*
X1300207D03*
X1303407Y190749D03*
Y187049D03*
X1300204Y188899D03*
X1313027Y192599D03*
X1309817Y190749D03*
X1313025Y188899D03*
X1309817Y198149D03*
X1303407D03*
X1300207Y203699D03*
Y207399D03*
X1309832Y209249D03*
X1313027Y203699D03*
X1300220Y218499D03*
X1309833Y220349D03*
X1303416Y205549D03*
X1306614Y203699D03*
X1306627Y214799D03*
X1316242Y209249D03*
X1300207Y211099D03*
X1303422Y220349D03*
X1300220Y222199D03*
X1313033D03*
X1303425Y224049D03*
X1300493Y238062D03*
X1314184Y849978D03*
X1307426Y978814D03*
X1314353Y1118243D03*
Y1131060D03*
X1319452Y162999D03*
X1316242Y168549D03*
X1319442Y159299D03*
X1316241Y157449D03*
X1316242Y164849D03*
X1322652D03*
X1329062D03*
X1326918Y161161D03*
X1329062Y157449D03*
X1322652D03*
X1325853Y174099D03*
X1331102Y179724D03*
Y182874D03*
Y186024D03*
X1325085Y176402D03*
X1324802Y179724D03*
Y186024D03*
Y182874D03*
X1315352Y186024D03*
Y179724D03*
X1319442Y174099D03*
X1332268D03*
X1324802Y195474D03*
X1327952D03*
X1318502D03*
X1321652D03*
X1327952Y201774D03*
X1321652D03*
X1331102Y189174D03*
X1315405Y189227D03*
X1329062Y212949D03*
X1325852Y211099D03*
X1319442D03*
X1324802Y204924D03*
X1327952D03*
X1318502D03*
X1315352D03*
X1322652Y209249D03*
X1325857Y218499D03*
X1322652Y216649D03*
X1329062Y220349D03*
X1325856Y222199D03*
X1322652Y224049D03*
Y220349D03*
X1321320Y854584D03*
X1325021Y860993D03*
X1326871Y870606D03*
X1330571D03*
X1328720Y873810D03*
X1330571Y883423D03*
X1325020Y873810D03*
X1323171Y877014D03*
X1325020Y880219D03*
X1319903Y999684D03*
X1325453Y1105426D03*
X1329153D03*
X1325454Y1111834D03*
X1327303Y1102221D03*
X1321753Y1111834D03*
X1318054D03*
X1318053Y1105426D03*
X1327304Y1108630D03*
X1329154Y1111834D03*
X1331003Y1102221D03*
X1319904Y1108630D03*
X1321753Y1105426D03*
X1327304Y1127856D03*
X1329153Y1118243D03*
X1331003Y1121447D03*
X1323603Y1115039D03*
X1331003Y1134264D03*
X1323603D03*
X1339727Y161149D03*
X1341992Y156897D03*
X1332268Y162999D03*
X1342903Y170399D03*
X1339727Y168549D03*
X1335472Y164849D03*
X1346140Y161149D03*
X1342937Y162999D03*
X1335472Y157449D03*
X1346140D03*
X1339727D03*
X1332268Y170399D03*
X1334252Y176574D03*
X1339727Y183349D03*
X1346137Y175949D03*
X1342937Y177799D03*
X1346137Y183349D03*
X1337901Y196035D03*
X1339727Y187049D03*
X1337345Y201831D03*
X1339727Y201849D03*
X1337402Y198624D03*
X1342937Y192599D03*
X1346137Y187049D03*
X1346147Y201849D03*
Y198149D03*
X1336527Y214799D03*
X1339727Y216649D03*
X1346147Y212949D03*
Y216649D03*
X1336527Y218499D03*
X1342937D03*
Y214799D03*
X1332262Y211099D03*
X1339686Y205478D03*
X1332262Y207399D03*
X1339727Y209249D03*
Y220349D03*
X1336527Y222199D03*
X1346147Y220349D03*
X1347220Y848176D03*
X1339820D03*
X1332420D03*
X1347220Y867401D03*
X1332420D03*
X1339820D03*
Y860993D03*
X1347220D03*
X1332420D03*
X1334271Y870606D03*
X1337971D03*
X1341671D03*
X1336120Y873810D03*
X1343520D03*
X1345371Y870606D03*
X1332420Y880219D03*
X1334271Y883423D03*
X1339820Y880219D03*
X1341671Y883423D03*
X1347220Y880219D03*
X1337971Y883423D03*
X1345371D03*
X1339820Y873810D03*
X1332420D03*
X1347220D03*
X1339821Y893036D03*
X1343521D03*
X1336120Y886627D03*
X1343520D03*
X1347220D03*
X1339820D03*
X1343953Y1002888D03*
X1334704Y1102221D03*
X1345803D03*
X1343953Y1105426D03*
X1336554D03*
X1345804Y1121447D03*
X1338403D03*
X1338404Y1134264D03*
X1345804D03*
X1352550Y157449D03*
X1355961Y155458D03*
X1352557Y168548D03*
X1355762Y166698D03*
X1349344Y162999D03*
X1348386Y156646D03*
X1352551Y161148D03*
X1352557Y172248D03*
X1349351Y177798D03*
Y170398D03*
Y174098D03*
Y192598D03*
X1352551Y187048D03*
X1355761Y188898D03*
X1349361Y199998D03*
X1352561Y201848D03*
X1355766Y214798D03*
X1349351Y218498D03*
X1352561Y216648D03*
X1355766Y218498D03*
X1352561Y220348D03*
X1355766Y222198D03*
X1360186Y226264D03*
X1362020Y848176D03*
X1354620D03*
Y867401D03*
X1362020D03*
Y860993D03*
X1354620D03*
X1363871Y870606D03*
X1349071D03*
X1356471D03*
X1350920Y873810D03*
X1352771Y870606D03*
X1358320Y873810D03*
X1360171Y870606D03*
X1349071Y883423D03*
X1354620Y880219D03*
X1356471Y883423D03*
X1362020Y880219D03*
X1363871Y883423D03*
X1352771D03*
X1360171D03*
X1354620Y873810D03*
X1362020D03*
X1350920Y886627D03*
X1358320D03*
X1354620D03*
X1362020D03*
X1363871Y909057D03*
Y902649D03*
X1362020Y905853D03*
X1363871Y921875D03*
Y928283D03*
X1362020Y925079D03*
X1363871Y947509D03*
Y941100D03*
X1362020Y944304D03*
X1363871Y960326D03*
Y966735D03*
X1362020Y963530D03*
Y982756D03*
X1363871Y979552D03*
X1352771D03*
X1356471D03*
X1350920Y976347D03*
X1358320D03*
X1349071Y973143D03*
X1360171D03*
X1362453Y1015705D03*
Y1034931D03*
Y1054157D03*
Y1073383D03*
Y1092608D03*
X1351354Y1099017D03*
X1356904Y1095813D03*
X1358753Y1099017D03*
X1362453Y1111834D03*
Y1105426D03*
X1358753D03*
X1351353Y1111834D03*
Y1105426D03*
X1358753Y1111834D03*
X1360604Y1108630D03*
X1355053Y1111834D03*
X1356904Y1102221D03*
X1353204Y1108630D03*
X1355054Y1105426D03*
X1360604Y1121447D03*
X1353204D03*
X1356904Y1115039D03*
X1353204Y1134264D03*
X1360604D03*
X1376820Y848176D03*
X1369420D03*
X1376820Y867401D03*
X1369420D03*
X1376820Y860993D03*
X1369420D03*
X1367571Y870606D03*
X1371271D03*
X1378671D03*
X1365720Y873810D03*
X1373120D03*
X1374971Y870606D03*
X1369420Y880219D03*
X1371271Y883423D03*
X1376820Y880219D03*
X1378671Y883423D03*
X1367571D03*
X1374971D03*
X1369420Y873810D03*
X1376820D03*
X1378671Y896240D03*
X1376820Y899445D03*
X1365720D03*
X1369420D03*
X1369421Y893036D03*
X1373121D03*
X1373120Y886627D03*
X1365720D03*
X1374971Y896240D03*
X1376820Y893036D03*
X1369420Y886627D03*
X1376820D03*
X1380520Y899445D03*
X1376820Y905853D03*
X1378671Y915466D03*
Y909057D03*
X1365720Y912262D03*
X1369420D03*
X1371271Y909057D03*
Y902649D03*
X1369420Y905853D03*
X1365720D03*
X1373120D03*
X1376820Y912262D03*
X1378671Y902649D03*
X1376820Y931488D03*
X1378671Y928283D03*
X1369420Y931488D03*
X1371271Y928283D03*
X1365720Y918670D03*
X1371271Y921875D03*
X1369420Y918670D03*
X1365720Y931488D03*
X1369420Y925079D03*
X1365720D03*
X1373120D03*
X1378671Y921875D03*
X1374971Y934691D03*
X1378671D03*
X1371271Y947509D03*
X1365720Y937896D03*
X1371271Y941100D03*
X1369420Y937896D03*
Y944304D03*
X1365720D03*
X1373120D03*
X1378671Y947509D03*
X1365720Y957122D03*
X1371271Y960326D03*
X1369420Y957122D03*
X1371271Y966735D03*
X1365720Y950713D03*
X1369420D03*
X1373120Y963530D03*
X1369420D03*
X1365720D03*
X1378671Y966735D03*
Y960326D03*
Y953917D03*
X1374971D03*
X1376822Y950713D03*
X1369420Y982756D03*
X1365720D03*
X1373120D03*
X1369420Y976347D03*
X1371271Y979552D03*
X1365721Y976347D03*
X1365720Y969939D03*
X1369420D03*
X1375404Y1006093D03*
X1379104D03*
X1375404Y999684D03*
X1379104D03*
X1364304Y1012501D03*
X1371704D03*
X1366153Y1009297D03*
X1369853D03*
X1377253D03*
X1379104Y1012501D03*
Y1031727D03*
X1373553Y1015705D03*
X1364304Y1031727D03*
X1366153Y1028523D03*
X1371704Y1031727D03*
X1369853Y1028523D03*
X1366153Y1022114D03*
X1364304Y1018910D03*
X1369853Y1022114D03*
X1371704Y1018910D03*
X1377253Y1028523D03*
X1375404Y1025318D03*
X1377253Y1022114D03*
X1379102Y1018910D03*
X1379104Y1025318D03*
X1377253Y1015705D03*
X1366153Y1041340D03*
X1364304Y1038136D03*
X1369853Y1041340D03*
X1371704Y1038136D03*
X1366153Y1047749D03*
X1369853D03*
Y1034931D03*
X1366153D03*
X1373553D03*
X1375404Y1044544D03*
X1377253Y1041340D03*
X1379104Y1044544D03*
Y1038136D03*
X1377253Y1047749D03*
X1366153Y1060565D03*
X1364304Y1057361D03*
X1369853Y1060565D03*
X1371704Y1057361D03*
X1364304Y1050952D03*
X1371704D03*
X1369853Y1054157D03*
X1366153D03*
X1373553D03*
X1379104Y1057361D03*
Y1063770D03*
X1377255Y1060565D03*
X1375404Y1063770D03*
X1377253Y1054157D03*
X1379104Y1050952D03*
X1380953Y1054157D03*
X1379104Y1076587D03*
Y1070178D03*
X1366153Y1079791D03*
X1364304Y1076587D03*
X1369853Y1079791D03*
X1371704Y1076587D03*
X1364304Y1070178D03*
X1366153Y1066974D03*
X1371704Y1070178D03*
X1369853Y1066974D03*
Y1073383D03*
X1366153D03*
X1373553D03*
X1377254Y1066974D03*
X1371704Y1095813D03*
X1364304Y1089404D03*
X1366153Y1086200D03*
X1371704Y1089404D03*
X1369853Y1086200D03*
X1364304Y1095813D03*
X1369853Y1092608D03*
X1366153D03*
X1373553D03*
X1375404Y1082995D03*
X1379104D03*
X1379103Y1089404D03*
X1369853Y1099017D03*
X1366153D03*
X1368004Y1102221D03*
X1369853Y1105426D03*
X1368004Y1121447D03*
X1375404D03*
X1368004Y1134264D03*
X1375404D03*
X1374847Y1153069D03*
X1391620Y848176D03*
X1384220D03*
Y867401D03*
X1391620D03*
X1384220Y860993D03*
X1391620D03*
X1380520Y873810D03*
X1382371Y870606D03*
X1384220Y880219D03*
X1386071Y883423D03*
X1382371D03*
X1395320Y873810D03*
X1393471Y870606D03*
X1387920Y873810D03*
X1389771Y870606D03*
X1391620Y873810D03*
X1384220D03*
X1380520Y886627D03*
X1387920D03*
X1380520Y893036D03*
X1382371Y896240D03*
X1384220Y886627D03*
X1391620D03*
Y899445D03*
X1384221Y899446D03*
X1393471Y909057D03*
X1382371D03*
X1389771D03*
Y915466D03*
X1399020Y905853D03*
X1382371Y915466D03*
X1384220Y918670D03*
X1387920Y905853D03*
X1384220D03*
Y912262D03*
X1382371Y902649D03*
X1391620Y905853D03*
X1387920Y912262D03*
X1391620D03*
X1393471Y915466D03*
X1391621Y918670D03*
X1382371Y921875D03*
X1382809Y927986D03*
X1385070Y928468D03*
X1393471Y921875D03*
X1391550Y925219D03*
X1387921Y918670D03*
X1386030Y942163D03*
X1383730D03*
X1381430D03*
X1392534Y942097D03*
X1394834D03*
X1393826Y956619D03*
X1387826D03*
X1391326D03*
X1385526D03*
X1380926Y971099D03*
X1383226D03*
X1387826D03*
X1385526D03*
X1396346D03*
X1396286Y985549D03*
X1388506Y985609D03*
X1386206D03*
X1385526Y1014539D03*
X1387826D03*
X1383226D03*
X1386226Y1000079D03*
X1396356Y1000039D03*
X1388526Y1000079D03*
X1396546Y1014469D03*
X1388102Y1028854D03*
X1390602D03*
X1393102D03*
X1395602D03*
X1380953Y1041340D03*
X1388353D03*
X1392053D03*
X1395753D03*
Y1047749D03*
X1392053D03*
X1382804Y1044544D03*
X1386504D03*
X1384653Y1047749D03*
X1390204Y1044544D03*
X1382804Y1050952D03*
Y1057361D03*
X1386504D03*
X1390204Y1050952D03*
X1393904Y1057361D03*
X1395753Y1054157D03*
X1382804Y1063770D03*
X1384653Y1060565D03*
X1386504Y1063770D03*
X1388353Y1054157D03*
X1390204Y1057361D03*
X1393904Y1063770D03*
X1390204D03*
X1395753Y1060565D03*
Y1079791D03*
X1384653Y1073383D03*
X1382804Y1070178D03*
X1380953Y1073383D03*
X1393904Y1076587D03*
X1392053Y1079791D03*
X1384653Y1066974D03*
X1388353Y1073383D03*
X1392053D03*
X1390204Y1070178D03*
X1393904D03*
X1388353Y1066974D03*
X1395753D03*
X1384653Y1079791D03*
X1395754Y1099017D03*
X1380953Y1092608D03*
X1393904Y1095813D03*
X1390203D03*
X1388353Y1086200D03*
X1386504Y1082995D03*
X1390204Y1089404D03*
X1382804D03*
X1390204Y1082995D03*
X1382804D03*
X1395753Y1086200D03*
Y1092608D03*
X1380953Y1086200D03*
X1386504Y1089404D03*
X1384653Y1092608D03*
X1392054Y1124651D03*
X1393903Y1121447D03*
Y1127856D03*
X1395754Y1118243D03*
Y1124651D03*
X1382803Y1121447D03*
X1390204Y1127856D03*
X1382804Y1134264D03*
X1390203Y1140973D03*
X1392054Y1131060D03*
Y1137469D03*
X1393903Y1134264D03*
Y1140973D03*
X1395754Y1131060D03*
Y1137469D03*
X1388354D03*
X1399020Y848176D03*
X1406420Y867401D03*
X1399020D03*
X1406420Y860993D03*
X1399020D03*
X1408271Y870606D03*
X1402720Y873810D03*
X1400871Y870606D03*
X1410121Y873810D03*
X1404571Y870606D03*
X1397171D03*
X1411971D03*
X1399020Y873810D03*
X1406420D03*
Y886627D03*
X1399020D03*
X1406420Y899445D03*
X1399020D03*
Y912262D03*
X1400871Y915466D03*
X1402720Y912262D03*
X1406420D03*
X1408271Y915466D03*
X1397171Y909057D03*
X1411971D03*
Y915466D03*
X1408270Y909057D03*
X1410120Y905853D03*
X1400870Y909057D03*
X1406420Y905853D03*
X1402720D03*
X1397171Y915466D03*
X1410121Y912262D03*
X1406420Y918670D03*
X1408271Y921875D03*
X1410121Y918670D03*
X1411971Y921875D03*
X1401528Y927155D03*
X1399028D03*
X1401817Y929464D03*
X1399317D03*
X1400871Y921875D03*
X1399020Y918670D03*
X1397171Y921875D03*
X1402720Y918670D03*
X1411971Y934691D03*
X1406420Y925079D03*
X1408271Y928283D03*
X1406420Y931488D03*
X1411971Y928283D03*
X1406421Y944304D03*
X1408271Y941100D03*
X1411971D03*
X1404016Y944229D03*
Y941929D03*
X1408270Y947509D03*
X1411971D03*
X1408271Y934691D03*
X1406421Y950713D03*
Y957122D03*
X1408270Y953917D03*
Y960326D03*
X1411971Y953917D03*
Y960326D03*
X1404016Y954072D03*
Y956372D03*
X1401326Y956619D03*
X1398826D03*
X1406421Y963530D03*
X1408270Y966735D03*
X1411971D03*
X1406421Y969939D03*
X1406409Y976347D03*
X1408270Y973143D03*
X1411971D03*
X1404016Y971266D03*
Y968966D03*
X1398826Y971099D03*
X1406421Y982756D03*
X1408270Y979552D03*
X1411971D03*
X1404016Y983110D03*
Y985410D03*
X1398826Y985579D03*
X1404016Y997520D03*
X1412404Y999684D03*
Y1006093D03*
Y1012501D03*
X1406853Y1002888D03*
Y1009297D03*
X1408703Y999684D03*
Y1006093D03*
Y1012501D03*
X1404016Y1012151D03*
Y999820D03*
X1398826Y1000059D03*
X1404016Y1014451D03*
X1399156Y1014469D03*
X1398102Y1028854D03*
X1406853Y1028523D03*
X1412404Y1018910D03*
X1406853Y1015705D03*
Y1022114D03*
X1408703Y1018910D03*
X1412404Y1025318D03*
X1408703D03*
X1404016Y1026703D03*
X1412404Y1031727D03*
X1408703D03*
X1404016Y1029003D03*
Y1031303D03*
X1403153Y1047749D03*
X1403154Y1041340D03*
X1399454D03*
X1401304Y1044544D03*
X1412403Y1038136D03*
Y1044544D03*
X1406853Y1034931D03*
Y1041340D03*
X1408703Y1038136D03*
Y1044544D03*
X1410554Y1041340D03*
X1404016Y1033603D03*
X1399426Y1036883D03*
Y1034583D03*
Y1032283D03*
X1410554Y1047749D03*
X1397604Y1044544D03*
X1403153Y1054157D03*
X1406853D03*
X1405003Y1057361D03*
X1408703D03*
Y1063770D03*
X1412404Y1050952D03*
Y1057361D03*
Y1063770D03*
X1397604Y1057361D03*
X1401304Y1050952D03*
X1399453Y1054157D03*
X1405004Y1050952D03*
X1397604D03*
X1401304Y1063770D03*
X1399453Y1060565D03*
X1403153D03*
X1405003Y1063770D03*
X1406853Y1060565D03*
X1397604Y1076587D03*
X1408702Y1070178D03*
X1399453Y1073383D03*
Y1079791D03*
X1412404Y1070178D03*
Y1076587D03*
X1397604Y1070178D03*
X1401304D03*
X1405004D03*
X1406853Y1066974D03*
X1412404Y1082995D03*
Y1089404D03*
X1412403Y1095813D03*
X1401304Y1082995D03*
X1405003Y1089404D03*
X1399453Y1086200D03*
X1406853Y1092608D03*
X1399453D03*
X1397604Y1089404D03*
X1403154Y1086200D03*
X1406852D03*
X1403153Y1092608D03*
X1401304Y1095813D03*
X1397604Y1102221D03*
X1399453Y1099017D03*
X1412404Y1102221D03*
Y1108630D03*
X1401304D03*
X1403154Y1105426D03*
Y1111834D03*
X1405003Y1102221D03*
Y1108630D03*
X1406853Y1099017D03*
Y1105426D03*
Y1111834D03*
X1408703Y1102221D03*
Y1108630D03*
X1410554Y1099017D03*
X1412404Y1115039D03*
Y1121447D03*
Y1127856D03*
X1397603Y1121447D03*
Y1127856D03*
X1401304Y1115039D03*
Y1121447D03*
Y1127856D03*
X1403154Y1118243D03*
Y1124651D03*
X1405003Y1115039D03*
Y1121447D03*
Y1127856D03*
X1406853Y1118243D03*
Y1124651D03*
X1408703Y1115039D03*
Y1121447D03*
Y1127856D03*
X1412403Y1134264D03*
X1397603D03*
Y1140973D03*
X1401304Y1134264D03*
X1401303Y1140973D03*
X1403154Y1131060D03*
Y1137569D03*
X1405003Y1134264D03*
Y1140973D03*
X1406853Y1131060D03*
Y1137769D03*
X1408703Y1134264D03*
X1428620Y867401D03*
X1421220D03*
X1413820D03*
X1421220Y860993D03*
X1428621D03*
X1424921Y873810D03*
X1423071Y870606D03*
X1417520Y873810D03*
X1415671Y870606D03*
X1426771D03*
X1419371D03*
X1413821Y873810D03*
X1428621D03*
X1421220D03*
X1428620Y899445D03*
Y886627D03*
X1421220D03*
X1419371Y909057D03*
X1415671Y915466D03*
X1421221Y905853D03*
X1417521D03*
X1430471Y909057D03*
X1426772D03*
X1428621Y905853D03*
X1424921D03*
X1424922Y912262D03*
X1417522D03*
X1415671Y909057D03*
X1421222Y912262D03*
X1419371Y915466D03*
X1426771D03*
X1428620Y912262D03*
X1424921Y918670D03*
X1430471Y915466D03*
X1415671Y921875D03*
X1417520Y918670D03*
X1426771Y921875D03*
X1421220Y918670D03*
X1419371Y921875D03*
X1428620Y918670D03*
X1424921Y931488D03*
X1419371Y928283D03*
X1413820Y931488D03*
X1424921Y925079D03*
X1419371Y934691D03*
X1421220Y931488D03*
Y925079D03*
X1415671Y928283D03*
X1413820Y925079D03*
X1426771Y928283D03*
X1413821Y944304D03*
X1415671Y941100D03*
X1417521Y944304D03*
X1419371Y941100D03*
X1421220Y944304D03*
X1424921D03*
X1426771Y941100D03*
X1415670Y947509D03*
X1419370D03*
X1426771D03*
X1423071Y934691D03*
X1415671D03*
X1413821Y950713D03*
Y957122D03*
X1415670Y953917D03*
Y960326D03*
X1417521Y950713D03*
Y957122D03*
X1419370Y953917D03*
Y960326D03*
X1421220Y950713D03*
Y957122D03*
X1424921Y950713D03*
Y957122D03*
X1426771Y953917D03*
Y960326D03*
X1413821Y963530D03*
X1415670Y966735D03*
X1417521Y963530D03*
X1419370Y966735D03*
X1421220Y963530D03*
X1424921D03*
X1426771Y966735D03*
X1413821Y969939D03*
Y976347D03*
X1415670Y973143D03*
X1417521Y969939D03*
Y976347D03*
X1419370Y973143D03*
X1421220Y969939D03*
Y976347D03*
X1424921Y969939D03*
Y976347D03*
X1426771Y973143D03*
X1413821Y982756D03*
X1415670Y979552D03*
X1417521Y982756D03*
X1419370Y979552D03*
X1421220Y982756D03*
X1424921D03*
X1426771Y979552D03*
X1414254Y1002888D03*
Y1009297D03*
X1416103Y999684D03*
Y1006093D03*
Y1012501D03*
X1417954Y1002888D03*
Y1009297D03*
X1419803Y999684D03*
Y1006093D03*
Y1012501D03*
X1421653Y1002888D03*
Y1009297D03*
X1425354Y1002888D03*
Y1009297D03*
X1427203Y999684D03*
Y1006093D03*
Y1012501D03*
X1421653Y1028523D03*
X1414254D03*
X1417954D03*
X1425354D03*
X1414254Y1015705D03*
Y1022114D03*
X1416103Y1018910D03*
X1417954Y1015705D03*
Y1022114D03*
X1419803Y1018910D03*
X1421653Y1015705D03*
Y1022114D03*
X1425354Y1015705D03*
Y1022114D03*
X1427203Y1018910D03*
X1416103Y1025318D03*
X1419803D03*
X1427203D03*
X1416103Y1031727D03*
X1419803D03*
X1427203D03*
X1429053Y1047749D03*
X1414254Y1034931D03*
Y1041340D03*
X1416103Y1038136D03*
Y1044544D03*
X1417954Y1034931D03*
Y1041340D03*
X1419803Y1038136D03*
Y1044544D03*
X1421653Y1034931D03*
Y1041340D03*
X1423503Y1044544D03*
X1425354Y1034931D03*
X1425353Y1041340D03*
X1427203Y1038136D03*
X1421653Y1047749D03*
X1414254D03*
X1417954D03*
X1425353Y1054157D03*
X1425355Y1060565D03*
X1414254Y1054157D03*
X1416103Y1050952D03*
X1417954Y1054157D03*
X1419803Y1050952D03*
X1421653Y1054157D03*
X1414254Y1060565D03*
X1416103Y1057361D03*
X1417954Y1060565D03*
X1419803Y1057361D03*
X1421653Y1060565D03*
X1416103Y1063770D03*
X1419803D03*
X1427203D03*
X1429053Y1054157D03*
X1427203Y1050952D03*
X1430903D03*
X1430904Y1057361D03*
X1427204D03*
X1429053Y1073383D03*
X1427203Y1076587D03*
X1414254Y1066974D03*
Y1073383D03*
X1416103Y1070178D03*
Y1076587D03*
X1417954Y1066974D03*
Y1073383D03*
X1419803Y1070178D03*
Y1076587D03*
X1421653Y1066974D03*
Y1073383D03*
X1414254Y1079791D03*
X1417954D03*
X1421653D03*
X1429053Y1066974D03*
X1425353D03*
X1427204Y1070178D03*
X1429053Y1086200D03*
X1416103Y1082995D03*
X1419803D03*
X1414254Y1086200D03*
Y1092608D03*
X1416103Y1089404D03*
Y1095813D03*
X1417954Y1086200D03*
Y1092608D03*
X1419803Y1089404D03*
Y1095813D03*
X1421653Y1086200D03*
Y1092608D03*
X1423503Y1089404D03*
Y1095813D03*
X1425353Y1092608D03*
X1427202Y1082995D03*
X1414254Y1099017D03*
Y1105426D03*
Y1111834D03*
X1416103Y1102221D03*
Y1108630D03*
X1417954Y1099017D03*
Y1105426D03*
Y1111834D03*
X1419803Y1102221D03*
Y1108630D03*
X1421653Y1099017D03*
Y1105426D03*
Y1111834D03*
X1425354Y1099017D03*
Y1105426D03*
Y1111834D03*
X1427203Y1102221D03*
Y1108630D03*
X1429054Y1105426D03*
Y1111834D03*
X1414254Y1118243D03*
Y1124651D03*
X1416103Y1115039D03*
Y1121447D03*
Y1127856D03*
X1417954Y1118243D03*
Y1124651D03*
X1419803Y1115039D03*
Y1121447D03*
Y1127856D03*
X1421653Y1118243D03*
Y1124651D03*
X1425354Y1118243D03*
Y1124651D03*
X1427203Y1115039D03*
Y1121447D03*
Y1127856D03*
X1429054Y1118243D03*
Y1124651D03*
X1414254Y1131060D03*
Y1137769D03*
X1416103Y1134264D03*
X1417954Y1131060D03*
Y1137769D03*
X1419803Y1134264D03*
X1421653Y1131060D03*
Y1137769D03*
X1425354Y1131060D03*
Y1137769D03*
X1427203Y1134264D03*
X1429054Y1131060D03*
Y1137769D03*
X1443420Y848176D03*
X1436020D03*
X1443420Y867401D03*
X1436020D03*
X1443420Y860993D03*
X1436020D03*
X1445271Y870606D03*
X1439720Y873810D03*
X1437871Y870606D03*
X1432320Y873810D03*
X1430471Y870606D03*
X1441571D03*
X1434171D03*
X1436020Y873810D03*
X1443420D03*
X1436020Y899445D03*
X1443420D03*
X1436020Y886627D03*
X1443420D03*
X1447120Y899445D03*
X1445271Y902649D03*
X1434171Y909057D03*
X1437871Y915466D03*
X1443420Y912262D03*
X1445271Y915466D03*
X1437871Y909057D03*
X1434171Y915466D03*
X1436020Y918670D03*
X1439720Y912262D03*
X1436020D03*
Y905853D03*
X1439720D03*
X1443420D03*
X1445271Y909057D03*
X1430471Y921875D03*
X1443420Y918670D03*
X1439777Y928348D03*
X1437477D03*
X1435177D03*
X1444377D03*
X1442077D03*
X1445271Y921875D03*
X1439720Y918670D03*
X1441571Y921875D03*
X1434171D03*
X1445392Y942195D03*
X1429726Y944537D03*
Y939937D03*
Y942237D03*
X1429544Y959298D03*
Y956998D03*
X1437565Y956619D03*
X1434545D03*
X1445045D03*
X1429544Y970798D03*
Y973098D03*
X1437565Y971139D03*
X1434545Y971099D03*
X1429544Y986898D03*
Y984598D03*
X1437565Y985579D03*
X1434545D03*
X1445045D03*
X1429544Y998398D03*
Y1012198D03*
Y1000698D03*
X1437565Y1000079D03*
X1434545D03*
X1445045D03*
X1429544Y1014498D03*
X1437436Y1014509D03*
X1434545Y1014539D03*
X1445036Y1014549D03*
X1439321Y1028854D03*
X1436821D03*
X1434321D03*
X1441821D03*
X1434083Y1031908D03*
X1447553Y1041340D03*
X1443853D03*
X1436453Y1047750D03*
X1443853D03*
X1430904Y1044544D03*
Y1038136D03*
X1434083Y1034408D03*
X1434813Y1037069D03*
X1439413D03*
X1437113D03*
X1432753Y1041340D03*
X1440153D03*
X1438304Y1044544D03*
X1434604D03*
X1432753Y1060565D03*
X1438303Y1057361D03*
Y1063770D03*
X1442002Y1050952D03*
X1440153Y1054157D03*
X1436454D03*
X1434604Y1057361D03*
X1443854Y1054157D03*
Y1060565D03*
X1430903Y1063770D03*
X1440154Y1060565D03*
X1434603Y1050952D03*
X1436453Y1060565D03*
Y1073383D03*
X1434602Y1070178D03*
X1436453Y1066974D03*
X1440153D03*
X1442002Y1070178D03*
X1447553Y1066974D03*
X1440154Y1079791D03*
X1436454D03*
X1438304Y1076587D03*
X1432753Y1066974D03*
X1442004Y1076587D03*
X1440153Y1073383D03*
X1434604Y1076587D03*
X1438304Y1082995D03*
X1442004D03*
X1438303Y1095812D03*
X1434603D03*
X1442003Y1089403D03*
X1432754Y1092607D03*
X1430903Y1089403D03*
X1436454Y1086199D03*
X1430902Y1082995D03*
X1442003Y1095812D03*
X1440154Y1092607D03*
X1430903Y1095812D03*
X1434603Y1089403D03*
X1438303D03*
X1438304Y1102221D03*
X1443853Y1099017D03*
X1430903Y1102221D03*
Y1108630D03*
X1432754Y1105426D03*
X1432753Y1111834D03*
X1434603Y1108630D03*
X1436454Y1111834D03*
Y1099016D03*
X1430903Y1115039D03*
Y1121447D03*
Y1127856D03*
X1432753Y1118243D03*
Y1124651D03*
X1436454Y1118243D03*
Y1124651D03*
X1438303Y1115039D03*
Y1121447D03*
Y1127856D03*
X1440153Y1118243D03*
X1440154Y1124651D03*
X1442003Y1127856D03*
X1443854Y1131060D03*
Y1137469D03*
X1430903Y1134264D03*
Y1140973D03*
X1432753Y1131060D03*
X1432754Y1137469D03*
X1434603Y1140973D03*
X1436454Y1131060D03*
Y1137469D03*
X1438303Y1134264D03*
Y1140973D03*
X1440154Y1131060D03*
Y1137469D03*
X1442003Y1134264D03*
Y1140973D03*
X1450820Y848176D03*
X1458220D03*
X1450820Y867401D03*
X1458220D03*
X1450820Y860993D03*
X1458220D03*
X1456371Y870606D03*
X1452671D03*
X1454520Y873810D03*
X1460071Y870606D03*
X1450820Y880219D03*
X1452671Y883423D03*
X1458220Y880219D03*
X1460071Y883423D03*
X1448971D03*
X1456371D03*
X1458220Y873810D03*
X1450820D03*
Y893036D03*
X1448971Y896240D03*
X1458220Y893036D03*
X1460071Y896240D03*
X1454520Y886627D03*
Y899445D03*
X1458220Y886627D03*
X1450820D03*
X1452671Y896240D03*
X1456371Y902649D03*
X1460071Y915466D03*
X1456371D03*
X1447122Y912262D03*
X1454521Y918670D03*
X1452671Y915466D03*
X1454522Y912262D03*
X1448971Y902649D03*
X1456370Y909057D03*
X1458220Y905853D03*
X1452671Y902649D03*
X1448970Y915466D03*
X1447120Y905853D03*
X1454520D03*
X1448971Y909057D03*
X1452671D03*
X1456371Y928283D03*
X1454522Y931488D03*
X1454520Y925079D03*
X1458220D03*
X1448971Y921875D03*
X1447120Y918670D03*
X1446677Y928348D03*
X1454520Y937896D03*
X1456371Y941100D03*
X1460071Y934691D03*
X1456371Y947509D03*
X1449992Y942195D03*
X1447692D03*
X1454520Y963530D03*
X1456371Y966735D03*
X1458220Y963529D03*
X1460071Y953917D03*
X1456370Y960326D03*
X1456371Y953917D03*
X1454520Y957122D03*
Y950713D03*
X1447545Y956619D03*
X1460071Y973143D03*
X1458220Y982756D03*
X1454521Y969939D03*
X1450045Y971099D03*
X1445445D03*
X1447745D03*
X1452426Y973825D03*
Y971525D03*
X1456371Y979552D03*
X1454520Y982756D03*
X1456371Y973143D03*
X1454520Y976347D03*
X1447545Y985579D03*
X1456804Y999684D03*
X1454953Y1002888D03*
Y1009297D03*
X1456804Y1012501D03*
X1460504Y1006093D03*
X1447545Y1000079D03*
X1447345Y1014539D03*
X1460504Y1025318D03*
X1456804Y1031727D03*
X1454953Y1028523D03*
Y1022114D03*
X1456803Y1018910D03*
X1454953Y1015705D03*
X1446934Y1028889D03*
X1452466Y1031794D03*
Y1029494D03*
Y1027194D03*
X1456804Y1025318D03*
X1458653Y1015705D03*
X1460504Y1044544D03*
X1451253Y1047749D03*
X1445704Y1044544D03*
X1454953Y1034931D03*
X1456804Y1038136D03*
X1454953Y1041340D03*
X1456804Y1044544D03*
X1449404D03*
X1454953Y1047749D03*
X1453104Y1044544D03*
X1460504Y1063770D03*
X1456804D03*
X1458653Y1054157D03*
X1454954D03*
X1453104Y1057361D03*
Y1063770D03*
X1454954Y1060565D03*
X1456803Y1057361D03*
X1453103Y1050952D03*
X1445703Y1057361D03*
X1445704Y1063770D03*
X1447554Y1060565D03*
X1449403Y1057361D03*
X1449404Y1063770D03*
X1451254Y1054157D03*
X1445703Y1050952D03*
X1449404D03*
X1454953Y1066974D03*
X1445702Y1070178D03*
X1453104Y1076587D03*
X1456804D03*
Y1070178D03*
X1453104D03*
X1447553Y1073383D03*
X1449404Y1076587D03*
X1445704D03*
X1447553Y1079791D03*
X1451253Y1073383D03*
X1458653D03*
X1460504Y1082995D03*
X1445704D03*
X1456804Y1089404D03*
X1449404Y1095813D03*
X1454954Y1092607D03*
X1451254D03*
X1449403Y1089403D03*
X1447554Y1086199D03*
X1453103Y1082994D03*
X1458654Y1092607D03*
X1453103Y1095812D03*
X1447554Y1092607D03*
X1451254Y1086199D03*
X1454954D03*
X1456804Y1102221D03*
Y1121447D03*
X1449404D03*
X1456804Y1134264D03*
X1445703D03*
X1465620Y848176D03*
X1473020D03*
X1465620Y867401D03*
X1473020D03*
X1465620Y860993D03*
X1473020D03*
X1463771Y870606D03*
X1471171D03*
X1461920Y873810D03*
X1467471Y870606D03*
X1469320Y873810D03*
X1474871Y870606D03*
X1476720Y873810D03*
X1465620Y880219D03*
X1467471Y883423D03*
X1473020Y880219D03*
X1474871Y883423D03*
X1463771D03*
X1471171D03*
X1473020Y873810D03*
X1465620D03*
X1461920Y899445D03*
X1469320D03*
Y893036D03*
X1473020D03*
X1461920D03*
X1467471Y896240D03*
X1463771D03*
X1471171D03*
X1461920Y886627D03*
X1469320D03*
X1476720D03*
X1473020D03*
X1465620D03*
X1461920Y912262D03*
X1463771Y909057D03*
X1469320Y912262D03*
X1467471Y909057D03*
X1463771Y902649D03*
X1467471D03*
X1463771Y915466D03*
X1471171D03*
X1467471D03*
Y921875D03*
X1469320Y918670D03*
X1461920Y931488D03*
X1467471Y928283D03*
X1469320Y931488D03*
X1463771Y928283D03*
Y921875D03*
X1461920Y918670D03*
X1463771Y947509D03*
X1467471D03*
X1463771Y941100D03*
X1461920Y937896D03*
X1467471Y941100D03*
X1469320Y937896D03*
X1463771Y934691D03*
X1471171D03*
X1467471D03*
X1463771Y966735D03*
X1467471D03*
X1474871D03*
X1473020Y963530D03*
X1461920Y950713D03*
X1469320D03*
X1467471Y960326D03*
X1469320Y957122D03*
X1463771Y960326D03*
X1461920Y957122D03*
X1471171Y953917D03*
X1463771D03*
X1467471D03*
X1471171Y973143D03*
X1463771D03*
X1467471D03*
X1461920Y969939D03*
X1469320D03*
X1476720D03*
X1471604Y1006093D03*
X1462353Y1002888D03*
X1469753D03*
X1464204Y999684D03*
X1467904D03*
X1467903Y1012501D03*
X1469753Y1009297D03*
X1464204Y1012501D03*
X1462353Y1009297D03*
X1464204Y1031727D03*
X1462353Y1028523D03*
X1467904Y1031727D03*
X1469753Y1028523D03*
X1462353Y1022114D03*
X1464204Y1018910D03*
X1469753Y1022114D03*
X1467904Y1018910D03*
X1464204Y1025318D03*
X1471604D03*
X1467904D03*
X1462353Y1047749D03*
X1469753D03*
X1462353Y1041340D03*
X1464204Y1038136D03*
X1469753Y1041340D03*
X1467904Y1038136D03*
X1464204Y1044544D03*
X1471604D03*
X1467904D03*
X1462353Y1060565D03*
X1464204Y1057361D03*
X1469753Y1060565D03*
X1467904Y1057361D03*
X1464204Y1050952D03*
X1467904D03*
X1464204Y1063770D03*
X1471604D03*
X1467904D03*
X1462353Y1079791D03*
X1464204Y1076587D03*
X1469753Y1079791D03*
X1467904Y1076587D03*
X1464204Y1070178D03*
X1462353Y1066974D03*
X1467904Y1070178D03*
X1469753Y1066974D03*
X1467904Y1089404D03*
X1469753Y1086200D03*
X1464204Y1089404D03*
X1462353Y1086200D03*
X1471604Y1082995D03*
X1464204D03*
X1467904D03*
X1464204Y1095813D03*
X1477154Y1105426D03*
Y1111833D03*
X1464204Y1115039D03*
Y1121447D03*
X1471604Y1134264D03*
X1464204D03*
X1487820Y848176D03*
X1480420D03*
X1487820Y867401D03*
X1480420D03*
X1487820Y860993D03*
X1480420D03*
X1493371Y870606D03*
X1478571D03*
X1485971D03*
X1489671D03*
X1491520Y873810D03*
X1482271Y870606D03*
X1484120Y873810D03*
X1487820Y880219D03*
X1489671Y883423D03*
X1480420Y880219D03*
X1482271Y883423D03*
X1485971D03*
X1493371D03*
X1478571D03*
X1487820Y873810D03*
X1480420D03*
X1491520Y886627D03*
X1484120D03*
X1480420D03*
X1487820D03*
X1482271Y966735D03*
X1484120Y963530D03*
X1480420Y969939D03*
X1479004Y1006093D03*
X1486404Y1102221D03*
X1479003Y1108629D03*
X1488254Y1105426D03*
X1484554Y1111833D03*
X1482703Y1102220D03*
X1480854Y1111833D03*
Y1105426D03*
X1486403Y1108630D03*
X1488254Y1111833D03*
X1484554Y1105426D03*
X1479004Y1115039D03*
Y1121447D03*
X1493804D03*
X1486404D03*
X1482703Y1115038D03*
X1479004Y1134264D03*
X1493804D03*
X1486404D03*
X1495220Y848176D03*
Y867401D03*
X1502621D03*
X1495220Y860993D03*
X1502621D03*
X1500771Y870606D03*
X1508171D03*
X1497071D03*
X1498920Y873810D03*
X1504471Y870606D03*
X1506321Y873810D03*
X1495220Y880219D03*
X1497071Y883423D03*
X1502621Y880219D03*
X1504471Y883423D03*
X1500771D03*
X1495220Y873810D03*
X1502621D03*
X1506320Y893036D03*
X1498920Y886627D03*
X1506321D03*
X1495220D03*
X1502621D03*
X1510021D03*
X1506753Y1105426D03*
X1504904Y1102221D03*
X1501204D03*
X1499354Y1099017D03*
X1503053Y1118243D03*
X1510453D03*
X1501204Y1121447D03*
X1508603Y1121446D03*
X1510453Y1124650D03*
X1508603Y1127855D03*
X1501204Y1134264D03*
X1508603Y1140973D03*
X1504903D03*
X1517853Y1118243D03*
X1519703Y1121446D03*
X1516003Y1127855D03*
X1512303D03*
Y1121446D03*
X1516003D03*
X1517853Y1124650D03*
X1519703Y1127855D03*
X1514154Y1131059D03*
X1611475Y1259227D03*
X1714440Y1255381D03*
X1821083Y1252034D03*
G54D40*
X322500Y1391830D03*
X537477Y1395413D03*
X1298642Y1391830D03*
X1513618Y1395413D03*
G54D10*
X27559Y87795D03*
X40708Y631890D03*
Y1368897D03*
X51181Y1714961D03*
X373622Y87795D03*
X395670Y1714961D03*
X661023Y631890D03*
X707677Y1714961D03*
X800787Y87795D03*
X931692Y757874D03*
Y1072834D03*
Y1387795D03*
X1045865Y87795D03*
X1155708Y1714961D03*
X1271260Y631890D03*
X1461805Y1714961D03*
X1499606Y87795D03*
X1816771Y631890D03*
Y1368897D03*
X1806299Y1714961D03*
X1829921Y87795D03*
G54D36*
X238780Y1681456D03*
X230906Y1677519D03*
Y1682244D03*
X238780Y1686180D03*
Y1709803D03*
Y1714527D03*
X230906Y1705866D03*
Y1710590D03*
X254528Y1681456D03*
X246654Y1677519D03*
Y1682244D03*
X254528Y1686180D03*
Y1709803D03*
Y1714527D03*
X246654Y1705866D03*
Y1710590D03*
X270276Y1681456D03*
X262402Y1677519D03*
Y1682244D03*
X270276Y1686180D03*
Y1709803D03*
Y1714527D03*
X262402Y1705866D03*
Y1710590D03*
X286024Y1681456D03*
X278150Y1677519D03*
Y1682244D03*
X286024Y1686180D03*
Y1709803D03*
Y1714527D03*
X278150Y1705866D03*
Y1710590D03*
X297835Y1677519D03*
Y1682244D03*
X305709Y1681456D03*
Y1686180D03*
X297835Y1705866D03*
Y1710590D03*
X305709Y1709803D03*
Y1714527D03*
X313583Y1677519D03*
Y1682244D03*
X321457Y1681456D03*
Y1686180D03*
X313583Y1705866D03*
Y1710590D03*
X321457Y1709803D03*
Y1714527D03*
X329331Y1677519D03*
Y1682244D03*
X337205Y1681456D03*
Y1686180D03*
X329331Y1705866D03*
Y1710590D03*
X337205Y1709803D03*
Y1714527D03*
X345079Y1677519D03*
Y1682244D03*
X352953Y1681456D03*
Y1686180D03*
X345079Y1705866D03*
Y1710590D03*
X352953Y1709803D03*
Y1714527D03*
X495079Y1691692D03*
Y1696417D03*
Y1720039D03*
Y1724763D03*
X510827Y1691692D03*
X502953Y1695629D03*
X510827Y1696417D03*
X502953Y1700354D03*
X510827Y1720039D03*
X502953Y1723976D03*
X510827Y1724763D03*
X502953Y1728700D03*
X526575Y1691692D03*
X518701Y1695629D03*
X526575Y1696417D03*
X534449Y1695629D03*
X518701Y1700354D03*
X534449D03*
X526575Y1720039D03*
X518701Y1723976D03*
X526575Y1724763D03*
X534449Y1723976D03*
X518701Y1728700D03*
X534449D03*
X542323Y1691692D03*
Y1696417D03*
X550197Y1695629D03*
Y1700354D03*
X542323Y1720039D03*
Y1724763D03*
X550197Y1723976D03*
Y1728700D03*
X562008Y1691692D03*
Y1696417D03*
Y1720039D03*
Y1724763D03*
X577756Y1691692D03*
X569882Y1695629D03*
X577756Y1696417D03*
X569882Y1700354D03*
X577756Y1720039D03*
X569882Y1723976D03*
X577756Y1724763D03*
X569882Y1728700D03*
X593504Y1691692D03*
X585630Y1695629D03*
X593504Y1696417D03*
X585630Y1700354D03*
X593504Y1720039D03*
X585630Y1723976D03*
X593504Y1724763D03*
X585630Y1728700D03*
X609252Y1691692D03*
X601378Y1695629D03*
X609252Y1696417D03*
X601378Y1700354D03*
X609252Y1720039D03*
X601378Y1723976D03*
X609252Y1724763D03*
X601378Y1728700D03*
X617126Y1695629D03*
Y1700354D03*
Y1723976D03*
Y1728700D03*
X1238780Y1677519D03*
Y1682244D03*
X1246654Y1681456D03*
Y1686180D03*
X1238780Y1705866D03*
Y1710590D03*
X1246654Y1709803D03*
Y1714527D03*
X1254528Y1677519D03*
Y1682244D03*
X1262402Y1681456D03*
Y1686180D03*
X1254528Y1705866D03*
Y1710590D03*
X1262402Y1709803D03*
Y1714527D03*
X1270276Y1677519D03*
Y1682244D03*
X1278150Y1681456D03*
Y1686180D03*
X1270276Y1705866D03*
Y1710590D03*
X1278150Y1709803D03*
Y1714527D03*
X1286024Y1677519D03*
Y1682244D03*
X1293898Y1681456D03*
Y1686180D03*
X1286024Y1705866D03*
Y1710590D03*
X1293898Y1709803D03*
Y1714527D03*
X1305709Y1677519D03*
Y1682244D03*
X1313583Y1681456D03*
Y1686180D03*
X1305709Y1705866D03*
Y1710590D03*
X1313583Y1709803D03*
Y1714527D03*
X1321457Y1677519D03*
Y1682244D03*
X1329331Y1681456D03*
Y1686180D03*
X1321457Y1705866D03*
Y1710590D03*
X1329331Y1709803D03*
Y1714527D03*
X1337205Y1677519D03*
Y1682244D03*
X1345079Y1681456D03*
Y1686180D03*
X1337205Y1705866D03*
Y1710590D03*
X1345079Y1709803D03*
Y1714527D03*
X1352953Y1677519D03*
Y1682244D03*
X1360827Y1681456D03*
Y1686180D03*
X1352953Y1705866D03*
Y1710590D03*
X1360827Y1709803D03*
Y1714527D03*
X1502953Y1691692D03*
Y1696417D03*
X1510827Y1695629D03*
Y1700354D03*
X1502953Y1720039D03*
Y1724763D03*
X1510827Y1723976D03*
Y1728700D03*
X1518701Y1691692D03*
Y1696417D03*
X1526575Y1695629D03*
Y1700354D03*
X1518701Y1720039D03*
Y1724763D03*
X1526575Y1723976D03*
Y1728700D03*
X1534449Y1691692D03*
Y1696417D03*
X1542323Y1695629D03*
Y1700354D03*
X1534449Y1720039D03*
Y1724763D03*
X1542323Y1723976D03*
Y1728700D03*
X1550197Y1691692D03*
Y1696417D03*
X1558071Y1695629D03*
Y1700354D03*
X1550197Y1720039D03*
Y1724763D03*
X1558071Y1723976D03*
Y1728700D03*
X1569882Y1691692D03*
Y1696417D03*
Y1720039D03*
Y1724763D03*
X1585630Y1691692D03*
X1577756Y1695629D03*
X1585630Y1696417D03*
X1577756Y1700354D03*
X1585630Y1720039D03*
X1577756Y1723976D03*
X1585630Y1724763D03*
X1577756Y1728700D03*
X1601378Y1691692D03*
X1593504Y1695629D03*
X1601378Y1696417D03*
X1593504Y1700354D03*
X1601378Y1720039D03*
X1593504Y1723976D03*
X1601378Y1724763D03*
X1593504Y1728700D03*
X1617126Y1691692D03*
X1609252Y1695629D03*
X1617126Y1696417D03*
X1609252Y1700354D03*
X1617126Y1720039D03*
X1609252Y1723976D03*
X1617126Y1724763D03*
X1609252Y1728700D03*
X1625000Y1695629D03*
Y1700354D03*
Y1723976D03*
Y1728700D03*
G54D37*
X277098Y185236D03*
X395208D03*
G54D32*
X205159Y1430034D03*
X393067Y1354446D03*
X422833D03*
X453169D03*
X468443Y1379662D03*
X482543Y1353962D03*
X718638Y1429579D03*
X1178470Y1466363D03*
X1369208Y1353946D03*
X1398974D03*
X1429310D03*
X1444043Y1379362D03*
X1459076Y1353946D03*
X1679944Y1463655D03*
X1836248Y269763D03*
Y299056D03*
G54D30*
X174685Y637367D03*
X174393Y668511D03*
X526478Y1439952D03*
X1502956Y1439530D03*
X1682882Y618174D03*
Y669109D03*
X1769790Y194789D03*
X1799350D03*
G54D48*
X493500Y246362D03*
X559236Y1441207D03*
G54D51*
X688500Y1601900D03*
X1041435Y153357D03*
X1056225Y153131D03*
X1099970Y1702570D03*
G54D66*
X1133779Y1653543D03*
G54D38*
X278126Y676260D03*
Y700414D03*
X395771Y1242785D03*
X420171D03*
X444493D03*
X468893D03*
X493293D03*
X1371912D03*
X1396312D03*
X1420634D03*
X1445034D03*
X1469434D03*
G54D28*
X159474Y1320753D03*
X183847Y1320778D03*
X208247D03*
X275289Y575702D03*
Y599861D03*
Y624015D03*
Y648169D03*
X673093Y1320778D03*
X697466Y1320803D03*
X721866D03*
X1100800Y251488D03*
X1100700Y275788D03*
X1131100Y1357088D03*
X1155500D03*
X1179900D03*
X1577000Y591888D03*
Y616388D03*
Y640888D03*
Y665288D03*
Y689788D03*
Y714288D03*
X1634259Y1354374D03*
X1658632Y1354399D03*
X1683032D03*
G54D78*
X1902608Y988322D03*
X1902682Y1351295D03*
X1951178Y1349597D03*
X1993618Y1349897D03*
G54D75*
X1881720Y988279D03*
X1881211Y1350983D03*
X1930200Y1349548D03*
X1972697Y1349606D03*
G54D23*
X40120Y744554D03*
Y1000853D03*
Y1287664D03*
X69820Y744554D03*
Y1000853D03*
Y1287664D03*
X99520Y744554D03*
Y1000853D03*
Y1287664D03*
X129220Y744554D03*
Y1000853D03*
Y1287664D03*
X158920Y744554D03*
Y1000853D03*
Y1287664D03*
X188620Y744554D03*
Y1000853D03*
Y1287664D03*
X218320Y744554D03*
Y1000853D03*
Y1287664D03*
X248020Y744554D03*
Y1000853D03*
Y1287664D03*
X633320Y744554D03*
Y1000853D03*
Y1287664D03*
X663020Y744554D03*
Y1000853D03*
Y1287664D03*
X692720Y744554D03*
Y1000853D03*
Y1287664D03*
X722420Y744554D03*
Y1000853D03*
Y1287664D03*
X752120Y744554D03*
Y1000853D03*
Y1287664D03*
X781820Y744554D03*
Y1000853D03*
Y1287664D03*
X811520Y744554D03*
Y1000853D03*
Y1287664D03*
X841220Y744554D03*
Y1000853D03*
Y1287664D03*
X1016262Y744554D03*
Y1000853D03*
Y1287664D03*
X1045962Y744554D03*
Y1000853D03*
Y1287664D03*
X1075662Y744554D03*
Y1000853D03*
Y1287664D03*
X1105362Y744554D03*
Y1000853D03*
Y1287664D03*
X1135062Y744554D03*
Y1000853D03*
Y1287664D03*
X1164762Y744554D03*
Y1000853D03*
Y1287664D03*
X1194462Y744554D03*
Y1000853D03*
Y1287664D03*
X1224162Y744554D03*
Y1000853D03*
Y1287664D03*
X1609462Y744554D03*
Y1000853D03*
Y1287664D03*
X1639162Y744554D03*
Y1000853D03*
Y1287664D03*
X1668862Y744554D03*
Y1000853D03*
Y1287664D03*
X1698562Y744554D03*
Y1000853D03*
Y1287664D03*
X1728262Y744554D03*
Y1000853D03*
Y1287664D03*
X1757962Y744554D03*
Y1000853D03*
Y1287664D03*
X1787662Y744554D03*
Y1000853D03*
Y1287664D03*
X1817362Y744554D03*
Y1000853D03*
Y1287664D03*
G54D61*
X928739Y321653D03*
G54D33*
X250326Y185236D03*
X368437D03*
G54D62*
X916545Y309459D03*
X911494Y321653D03*
X916545Y333847D03*
X940933Y309459D03*
X928739Y304408D03*
Y338898D03*
X940933Y333847D03*
X945984Y321653D03*
G54D68*
X1247638Y269488D03*
X1405118Y112008D03*
X1766929Y1714960D03*
G54D13*
X19685Y-29134D03*
Y1803261D03*
X1837795Y-29134D03*
Y1803261D03*
X2081889Y-29134D03*
Y1803261D03*
G54D69*
X1405876Y1453298D03*
X1430204Y1452014D03*
G54D18*
X38346Y1420330D03*
X117932Y605380D03*
X763601Y605413D03*
X1094074Y605380D03*
X1739706Y605455D03*
X1819208Y1420330D03*
G54D21*
X49280Y337402D03*
X41870Y1511291D03*
X441043Y1672205D03*
Y1718465D03*
X1416437Y1672204D03*
Y1718464D03*
X1808192Y1569255D03*
X1812980Y502472D03*
G54D39*
X306772Y991220D03*
X350099Y811121D03*
X356063Y1171318D03*
X531240Y811121D03*
X525276Y1171318D03*
X574567Y991220D03*
X1282914D03*
X1326240Y811121D03*
X1332205Y1171318D03*
X1507382Y811121D03*
X1501418Y1171318D03*
X1550709Y991220D03*
G54D54*
X791280Y1704890D03*
X1066280D03*
G54D34*
X238780Y1648385D03*
X230906Y1644448D03*
X238780Y1662558D03*
X230906Y1658621D03*
X238780Y1676732D03*
X230906Y1672795D03*
X238780Y1690905D03*
X230906Y1686968D03*
X238780Y1705078D03*
X230906Y1701141D03*
Y1715314D03*
X238780Y1719251D03*
X230906Y1729488D03*
X238780Y1733425D03*
X254528Y1648385D03*
X246654Y1644448D03*
X254528Y1662558D03*
X246654Y1658621D03*
X254528Y1676732D03*
X246654Y1672795D03*
X254528Y1690905D03*
X246654Y1686968D03*
X254528Y1705078D03*
X246654Y1701141D03*
Y1715314D03*
X254528Y1719251D03*
X246654Y1729488D03*
X254528Y1733425D03*
X270276Y1648385D03*
X262402Y1644448D03*
X270276Y1662558D03*
X262402Y1658621D03*
X270276Y1676732D03*
X262402Y1672795D03*
X270276Y1690905D03*
X262402Y1686968D03*
X270276Y1705078D03*
X262402Y1701141D03*
Y1715314D03*
X270276Y1719251D03*
X262402Y1729488D03*
X270276Y1733425D03*
X286024Y1648385D03*
X278150Y1644448D03*
X286024Y1662558D03*
X278150Y1658621D03*
X286024Y1676732D03*
X278150Y1672795D03*
X286024Y1690905D03*
X278150Y1686968D03*
X286024Y1705078D03*
X278150Y1701141D03*
Y1715314D03*
X286024Y1719251D03*
X278150Y1729488D03*
X286024Y1733425D03*
X297835Y1672795D03*
X305709Y1676732D03*
X297835Y1686968D03*
X305709Y1690905D03*
X297835Y1701141D03*
X305709Y1705078D03*
X297835Y1715314D03*
X305709Y1719251D03*
X297835Y1729488D03*
X305709Y1733425D03*
X313583Y1672795D03*
X321457Y1676732D03*
X313583Y1686968D03*
X321457Y1690905D03*
X313583Y1701141D03*
X321457Y1705078D03*
X313583Y1715314D03*
X321457Y1719251D03*
X313583Y1729488D03*
X321457Y1733425D03*
X329331Y1672795D03*
X337205Y1676732D03*
X329331Y1686968D03*
X337205Y1690905D03*
X329331Y1701141D03*
X337205Y1705078D03*
X329331Y1715314D03*
X337205Y1719251D03*
X329331Y1729488D03*
X337205Y1733425D03*
X345079Y1672795D03*
X352953Y1676732D03*
X345079Y1686968D03*
X352953Y1690905D03*
X345079Y1701141D03*
X352953Y1705078D03*
X345079Y1715314D03*
X352953Y1719251D03*
X345079Y1729488D03*
X352953Y1733425D03*
X495079Y1672795D03*
Y1686968D03*
Y1701141D03*
Y1715314D03*
Y1729488D03*
X510827Y1672795D03*
X502953Y1676732D03*
X518701D03*
X510827Y1686968D03*
X502953Y1690905D03*
X518701D03*
X510827Y1701141D03*
X502953Y1705078D03*
X518701D03*
X510827Y1715314D03*
X502953Y1719251D03*
X518701D03*
X510827Y1729488D03*
X502953Y1733425D03*
X518701D03*
X526575Y1672795D03*
X534449Y1676732D03*
X526575Y1686968D03*
X534449Y1690905D03*
X526575Y1701141D03*
X534449Y1705078D03*
X526575Y1715314D03*
X534449Y1719251D03*
X526575Y1729488D03*
X534449Y1733425D03*
X542323Y1672795D03*
X550197Y1676732D03*
X542323Y1686968D03*
X550197Y1690905D03*
X542323Y1701141D03*
X550197Y1705078D03*
X542323Y1715314D03*
X550197Y1719251D03*
X542323Y1729488D03*
X550197Y1733425D03*
X562008Y1672795D03*
Y1686968D03*
Y1701141D03*
Y1715314D03*
Y1729488D03*
X577756Y1672795D03*
X569882Y1676732D03*
X577756Y1686968D03*
X569882Y1690905D03*
X577756Y1701141D03*
X569882Y1705078D03*
X577756Y1715314D03*
X569882Y1719251D03*
X577756Y1729488D03*
X569882Y1733425D03*
X593504Y1672795D03*
X585630Y1676732D03*
X593504Y1686968D03*
X585630Y1690905D03*
X593504Y1701141D03*
X585630Y1705078D03*
X593504Y1715314D03*
X585630Y1719251D03*
X593504Y1729488D03*
X585630Y1733425D03*
X609252Y1672795D03*
X601378Y1676732D03*
X609252Y1686968D03*
X601378Y1690905D03*
X609252Y1701141D03*
X601378Y1705078D03*
X609252Y1715314D03*
X601378Y1719251D03*
X609252Y1729488D03*
X601378Y1733425D03*
X617126Y1676732D03*
Y1690905D03*
Y1705078D03*
Y1719251D03*
Y1733425D03*
X1238780Y1672795D03*
X1246654Y1676732D03*
X1238780Y1686968D03*
X1246654Y1690905D03*
X1238780Y1701141D03*
X1246654Y1705078D03*
X1238780Y1715314D03*
X1246654Y1719251D03*
X1238780Y1729488D03*
X1246654Y1733425D03*
X1254528Y1672795D03*
X1262402Y1676732D03*
X1254528Y1686968D03*
X1262402Y1690905D03*
X1254528Y1701141D03*
X1262402Y1705078D03*
X1254528Y1715314D03*
X1262402Y1719251D03*
X1254528Y1729488D03*
X1262402Y1733425D03*
X1270276Y1672795D03*
X1278150Y1676732D03*
X1270276Y1686968D03*
X1278150Y1690905D03*
X1270276Y1701141D03*
X1278150Y1705078D03*
X1270276Y1715314D03*
X1278150Y1719251D03*
X1270276Y1729488D03*
X1278150Y1733425D03*
X1286024Y1672795D03*
X1293898Y1676732D03*
X1286024Y1686968D03*
X1293898Y1690905D03*
X1286024Y1701141D03*
X1293898Y1705078D03*
X1286024Y1715314D03*
X1293898Y1719251D03*
X1286024Y1729488D03*
X1293898Y1733425D03*
X1305709Y1672795D03*
X1313583Y1676732D03*
X1305709Y1686968D03*
X1313583Y1690905D03*
X1305709Y1701141D03*
X1313583Y1705078D03*
X1305709Y1715314D03*
X1313583Y1719251D03*
X1305709Y1729488D03*
X1313583Y1733425D03*
X1321457Y1672795D03*
X1329331Y1676732D03*
X1321457Y1686968D03*
X1329331Y1690905D03*
X1321457Y1701141D03*
X1329331Y1705078D03*
X1321457Y1715314D03*
X1329331Y1719251D03*
X1321457Y1729488D03*
X1329331Y1733425D03*
X1337205Y1672795D03*
X1345079Y1676732D03*
X1337205Y1686968D03*
X1345079Y1690905D03*
X1337205Y1701141D03*
X1345079Y1705078D03*
X1337205Y1715314D03*
X1345079Y1719251D03*
X1337205Y1729488D03*
X1345079Y1733425D03*
X1352953Y1672795D03*
X1360827Y1676732D03*
X1352953Y1686968D03*
X1360827Y1690905D03*
X1352953Y1701141D03*
X1360827Y1705078D03*
X1352953Y1715314D03*
X1360827Y1719251D03*
X1352953Y1729488D03*
X1360827Y1733425D03*
X1502953Y1672795D03*
X1510827Y1676732D03*
X1502953Y1686968D03*
X1510827Y1690905D03*
X1502953Y1701141D03*
X1510827Y1705078D03*
X1502953Y1715314D03*
X1510827Y1719251D03*
X1502953Y1729488D03*
X1510827Y1733425D03*
X1518701Y1672795D03*
X1526575Y1676732D03*
X1518701Y1686968D03*
X1526575Y1690905D03*
X1518701Y1701141D03*
X1526575Y1705078D03*
X1518701Y1715314D03*
X1526575Y1719251D03*
X1518701Y1729488D03*
X1526575Y1733425D03*
X1534449Y1672795D03*
X1542323Y1676732D03*
X1534449Y1686968D03*
X1542323Y1690905D03*
X1534449Y1701141D03*
X1542323Y1705078D03*
X1534449Y1715314D03*
X1542323Y1719251D03*
X1534449Y1729488D03*
X1542323Y1733425D03*
X1550197Y1672795D03*
X1558071Y1676732D03*
X1550197Y1686968D03*
X1558071Y1690905D03*
X1550197Y1701141D03*
X1558071Y1705078D03*
X1550197Y1715314D03*
X1558071Y1719251D03*
X1550197Y1729488D03*
X1558071Y1733425D03*
X1569882Y1672795D03*
Y1686968D03*
Y1701141D03*
Y1715314D03*
Y1729488D03*
X1585630Y1672795D03*
X1577756Y1676732D03*
X1585630Y1686968D03*
X1577756Y1690905D03*
X1585630Y1701141D03*
X1577756Y1705078D03*
X1585630Y1715314D03*
X1577756Y1719251D03*
X1585630Y1729488D03*
X1577756Y1733425D03*
X1601378Y1672795D03*
X1593504Y1676732D03*
X1601378Y1686968D03*
X1593504Y1690905D03*
X1601378Y1701141D03*
X1593504Y1705078D03*
X1601378Y1715314D03*
X1593504Y1719251D03*
X1601378Y1729488D03*
X1593504Y1733425D03*
X1617126Y1672795D03*
X1609252Y1676732D03*
X1625000D03*
X1617126Y1686968D03*
X1609252Y1690905D03*
X1625000D03*
X1617126Y1701141D03*
X1609252Y1705078D03*
X1625000D03*
X1617126Y1715314D03*
X1609252Y1719251D03*
X1625000D03*
X1617126Y1729488D03*
X1609252Y1733425D03*
X1625000D03*
G54D45*
X441043Y1698268D03*
X1416437Y1698267D03*
G54D56*
X805690Y204724D03*
X1057658D03*
G54D20*
X41492Y290637D03*
X44833Y1659909D03*
X61340Y384362D03*
X61250Y396142D03*
X49250Y396332D03*
X49400Y384392D03*
X47618Y413113D03*
X47619Y421155D03*
X56799Y1524094D03*
Y1528094D03*
Y1532094D03*
Y1544094D03*
Y1548094D03*
Y1552094D03*
Y1556094D03*
X54333Y1604359D03*
X50900Y1677775D03*
X65881Y305426D03*
X72774Y1549669D03*
X66906Y1598324D03*
Y1603280D03*
X84274Y1517619D03*
X81038Y1536899D03*
X91538Y1539399D03*
X84700Y1627000D03*
X99274Y1526019D03*
X126225Y504368D03*
X120225D03*
Y510368D03*
X126225Y516368D03*
X120225D03*
X112749Y1524594D03*
Y1540594D03*
Y1544594D03*
Y1548594D03*
Y1536594D03*
Y1564594D03*
Y1560594D03*
X132225Y504368D03*
Y510368D03*
X132401Y516368D03*
X129670Y1563160D03*
X153271Y1540961D03*
X153138Y1549032D03*
X166986Y575918D03*
X161321Y1540858D03*
X161374Y1549073D03*
X189800Y705062D03*
X208312Y576125D03*
X196526Y567825D03*
X208312Y581085D03*
Y578605D03*
X197423Y601496D03*
X194059Y604901D03*
X208312Y615085D03*
Y610125D03*
Y612605D03*
X194059Y638901D03*
X197423Y635496D03*
X208312Y649085D03*
Y644125D03*
Y646605D03*
X213912Y576125D03*
X220668Y574131D03*
X223775D03*
X224064Y568113D03*
X221464D03*
X213912Y578605D03*
Y581085D03*
X217556Y590575D03*
X217561Y582131D03*
Y579531D03*
X223775Y587731D03*
X223759Y590675D03*
X220652D03*
X223775Y584531D03*
X220668Y576731D03*
Y579331D03*
X223775Y581931D03*
Y579331D03*
Y576731D03*
X220668Y581931D03*
Y608131D03*
X223775D03*
X224064Y602113D03*
X221464D03*
X223403Y596820D03*
Y594220D03*
X213912Y612605D03*
Y615085D03*
Y610125D03*
X217561Y616131D03*
Y613531D03*
X217556Y624575D03*
X223759Y624675D03*
X220652D03*
X223775Y618531D03*
X220668Y610731D03*
Y613331D03*
X223775Y615931D03*
Y613331D03*
Y610731D03*
X220668Y615931D03*
X223775Y621731D03*
X223403Y630820D03*
Y628220D03*
X224064Y636113D03*
X221464D03*
X213912Y646605D03*
Y649085D03*
Y644125D03*
X217561Y650131D03*
Y647531D03*
X223775Y655731D03*
Y652531D03*
X220668Y644731D03*
Y647331D03*
Y642131D03*
X223775Y649931D03*
Y647331D03*
Y644731D03*
Y642131D03*
X220668Y649931D03*
X217556Y658575D03*
X223403Y664820D03*
X223759Y658675D03*
X220652D03*
X217510Y668712D03*
X225167Y672006D03*
X222567D03*
X219967D03*
X217367D03*
X211348Y688087D03*
Y685287D03*
X214100Y687376D03*
Y690376D03*
Y684376D03*
Y681376D03*
Y678376D03*
X211348Y690787D03*
Y693587D03*
X214100Y693576D03*
X224506Y698138D03*
Y700738D03*
X221906Y698138D03*
Y700738D03*
X219306D03*
Y698138D03*
X231864Y568113D03*
X229264D03*
X226664D03*
X238393Y570490D03*
X240993D03*
X229264Y602113D03*
X226664D03*
X226003Y594220D03*
Y596820D03*
X228603Y594220D03*
Y596820D03*
X231864Y602113D03*
X233803Y594220D03*
Y596820D03*
X231203Y594220D03*
Y596820D03*
X238393Y604490D03*
X240993D03*
Y596820D03*
X238393D03*
X240993Y594220D03*
X238393D03*
X226003Y628220D03*
Y630820D03*
X228603Y628220D03*
Y630820D03*
X231864Y636113D03*
X233803Y628220D03*
Y630820D03*
X231203Y628220D03*
Y630820D03*
X229264Y636113D03*
X226664D03*
X238393Y638490D03*
X240993D03*
Y630820D03*
X238393D03*
X240993Y628220D03*
X238393D03*
X228603Y664820D03*
X233803D03*
X231203D03*
X226003D03*
X230367Y672006D03*
X227767D03*
X227106Y698138D03*
Y700738D03*
X246400Y563162D03*
X263580Y218627D03*
X318651Y22921D03*
X320825Y159062D03*
X410700Y1658460D03*
X435340Y125346D03*
X435240Y1609200D03*
X433383Y1602629D03*
X450380Y104647D03*
X440019Y1576809D03*
X442128Y1574879D03*
X441308Y1602654D03*
X505055Y1387601D03*
Y1382301D03*
Y1396001D03*
Y1398601D03*
Y1390201D03*
X563634Y1334315D03*
X561034D03*
X612670Y142872D03*
X612520Y154812D03*
X624610Y142842D03*
X624520Y154622D03*
X702975Y414864D03*
X739206Y608020D03*
Y603064D03*
X758830Y1674823D03*
X819114Y115223D03*
X824498Y145198D03*
X831114Y115223D03*
X829114Y150273D03*
X854577Y99651D03*
X876124Y66072D03*
Y86072D03*
Y106072D03*
Y126072D03*
X887869Y386618D03*
X881372Y920655D03*
X898062Y976652D03*
Y969716D03*
X942646Y400793D03*
X946865Y974077D03*
X953235Y972642D03*
X946938Y991162D03*
X943720Y985772D03*
X956022Y1620730D03*
X953022D03*
Y1632730D03*
X956022D03*
Y1629730D03*
X953022D03*
X956022Y1626730D03*
X953022D03*
Y1623730D03*
X956022D03*
X963610Y981292D03*
X959535Y990477D03*
X963780Y997496D03*
X966852Y1585920D03*
X969852D03*
X960852D03*
X963852D03*
X957852D03*
X962022Y1620730D03*
X959022D03*
Y1632730D03*
X962022D03*
Y1629730D03*
X959022D03*
X962022Y1626730D03*
X959022D03*
Y1623730D03*
X962022D03*
X978403Y-9022D03*
Y-13978D03*
Y-19022D03*
Y-23978D03*
Y6022D03*
Y10978D03*
Y20978D03*
Y16022D03*
X988835Y185443D03*
X989500Y376362D03*
X985672Y432961D03*
X987662Y1620870D03*
Y1629870D03*
Y1626870D03*
Y1623870D03*
Y1632870D03*
X1002500Y266862D03*
X991770Y418835D03*
X992608Y432961D03*
X1002640Y594692D03*
X1002782Y1585920D03*
X999782D03*
X996782D03*
X990782D03*
X993782D03*
X990662Y1620870D03*
X993662D03*
Y1629870D03*
X990662D03*
X993662Y1626870D03*
X990662D03*
Y1623870D03*
X993662D03*
X990662Y1632870D03*
X993662D03*
X1001810Y1662700D03*
Y1665200D03*
X1018000Y263862D03*
X1022000Y264362D03*
X1014500Y263862D03*
X1010500D03*
X1018000Y266862D03*
X1010500D03*
X1006500D03*
X1014500D03*
X1011611Y430038D03*
X1021942Y1586090D03*
X1019252Y1620870D03*
X1022252D03*
Y1623870D03*
Y1626870D03*
X1019252Y1623870D03*
Y1626870D03*
X1019910Y1662700D03*
Y1665200D03*
X1025000Y264362D03*
X1038220Y589862D03*
X1030980Y598722D03*
X1023740Y596152D03*
X1036480Y596272D03*
X1030942Y1586090D03*
X1033942D03*
X1024942D03*
X1027942D03*
X1025252Y1620870D03*
Y1623870D03*
Y1626870D03*
X1023580Y1662700D03*
Y1665200D03*
X1027370Y1662700D03*
Y1665200D03*
X1040924Y286073D03*
X1043720Y589362D03*
X1050200Y598062D03*
X1050390Y604172D03*
X1053200Y612162D03*
X1053612Y1586010D03*
X1050721Y1633043D03*
X1053721D03*
Y1624043D03*
Y1627043D03*
Y1630043D03*
X1050721Y1624043D03*
Y1627043D03*
Y1630043D03*
X1053721Y1621043D03*
X1050721D03*
X1044850Y1665050D03*
Y1662550D03*
X1067718Y288500D03*
X1070618D03*
X1056280Y601232D03*
X1062612Y1586010D03*
X1065612D03*
X1056612D03*
X1059612D03*
X1056721Y1633043D03*
Y1624043D03*
Y1627043D03*
Y1630043D03*
Y1621043D03*
X1092302Y1585650D03*
X1089302D03*
X1098302D03*
X1095302D03*
X1095900Y1646935D03*
X1095649Y1638875D03*
X1099457D03*
X1104457Y1675490D03*
X1120544Y312200D03*
X1129995Y301637D03*
X1150914Y197407D03*
X1148354Y222677D03*
X1150272Y638346D03*
X1160720Y180862D03*
X1165000Y190962D03*
X1162500D03*
X1164300Y197262D03*
X1163732Y204887D03*
X1160732D03*
X1158172Y230157D03*
X1159912Y638216D03*
X1166722Y636206D03*
X1158762Y642266D03*
X1168402Y642136D03*
X1159930Y1645632D03*
X1164830D03*
X1161613Y1669112D03*
X1173065Y194174D03*
X1172865Y210174D03*
X1172795Y222174D03*
X1180398Y289814D03*
X1171540Y310902D03*
X1176362Y636076D03*
X1180262Y642216D03*
X1181930Y1645632D03*
X1186830D03*
X1175830D03*
X1170930D03*
X1183613Y1669112D03*
X1172613D03*
X1189902Y642086D03*
X1192500Y1645942D03*
X1197400D03*
X1194183Y1669422D03*
X1192340Y1691422D03*
X1197240D03*
X1194023Y1714902D03*
X1206093Y120362D03*
X1214593Y168962D03*
X1208518Y174162D03*
X1203858Y185451D03*
X1208365Y271151D03*
X1210457Y1658415D03*
X1218810Y1691732D03*
X1213910D03*
X1203110Y1691467D03*
X1208010D03*
X1215593Y1715212D03*
X1204793Y1714947D03*
X1228704Y112122D03*
X1223100Y127300D03*
X1226093Y152792D03*
X1227500Y380400D03*
X1242520Y165362D03*
X1236593Y209562D03*
X1236584Y217462D03*
X1245614Y227462D03*
X1266093Y129962D03*
X1256093Y143462D03*
X1264685Y175506D03*
X1279485Y105752D03*
X1278949Y123567D03*
X1282293Y248962D03*
X1275557Y269477D03*
Y272436D03*
X1282653Y269446D03*
X1278557Y272436D03*
Y269477D03*
X1272557Y272436D03*
X1287795Y-29033D03*
Y-33989D03*
Y-9033D03*
Y-13989D03*
Y-19033D03*
Y-23989D03*
Y967D03*
Y-3989D03*
X1293430Y84072D03*
X1294354Y105912D03*
X1295053Y140181D03*
X1292293Y143162D03*
X1287943Y233748D03*
X1284437Y230280D03*
X1293893Y237962D03*
X1286611Y260908D03*
X1295887Y315571D03*
X1314741Y68652D03*
X1300454Y95302D03*
X1302964Y124633D03*
X1301993Y140462D03*
X1313950Y261612D03*
X1308790Y290172D03*
X1302450Y290072D03*
X1307798Y287561D03*
X1313246Y287631D03*
X1308220Y304262D03*
X1303120Y304162D03*
X1330102Y59025D03*
X1327920Y84418D03*
X1316478Y92970D03*
X1330273Y128373D03*
X1326493Y249562D03*
X1317893Y257462D03*
X1328393Y264262D03*
X1339280Y126175D03*
X1356223Y131569D03*
X1362793Y145262D03*
X1366124Y101529D03*
X1377597Y197604D03*
X1375300Y208422D03*
X1378452Y236055D03*
X1389609Y145291D03*
X1389443Y147859D03*
X1386780Y197668D03*
X1395321D03*
X1409558Y151948D03*
Y156904D03*
X1401240Y171672D03*
X1404071Y197668D03*
X1412851D03*
X1398700Y1597800D03*
X1436436Y300319D03*
X1456423Y209362D03*
X1453823Y205982D03*
X1445777Y362021D03*
X1449296Y410497D03*
X1451580Y1627990D03*
X1462777Y362021D03*
X1470877Y374496D03*
X1463277Y406446D03*
X1470954D03*
X1476570Y1657974D03*
X1480154Y-29033D03*
Y-33989D03*
Y-9033D03*
Y-13989D03*
Y-19033D03*
Y-23989D03*
Y967D03*
Y-3989D03*
X1481155Y1387742D03*
X1481255Y1382042D03*
X1481155Y1396342D03*
Y1398942D03*
Y1390342D03*
X1478724Y1637189D03*
X1505821Y215802D03*
X1524770Y195792D03*
X1521201Y215551D03*
X1531750Y199762D03*
X1529610Y211614D03*
X1532590Y225432D03*
X1561494Y584292D03*
X1604040Y219692D03*
X1604290Y242472D03*
X1636393Y181778D03*
X1632899Y213012D03*
X1670004Y537065D03*
Y543065D03*
Y531065D03*
X1683394Y469878D03*
X1683476Y473378D03*
X1684356Y476290D03*
X1681602Y485180D03*
X1684356Y485628D03*
X1677464Y491790D03*
X1682004Y537065D03*
X1682180Y543065D03*
X1676004D03*
X1682004Y531065D03*
X1676004D03*
X1697648Y463724D03*
X1693648D03*
X1692883Y703943D03*
X1709027Y655141D03*
X1725473Y474859D03*
X1754307Y262186D03*
X1751068Y262123D03*
X1754245Y269724D03*
X1751068Y266048D03*
X1754307Y266111D03*
X1754414Y275329D03*
X1752165Y273901D03*
X1749565D03*
X1751006Y269661D03*
X1749595Y276711D03*
X1752195D03*
X1748989Y380206D03*
X1764955Y301951D03*
X1768757Y380498D03*
X1793061Y24659D03*
X1828880Y1626595D03*
Y1646595D03*
Y1666595D03*
Y1686595D03*
X1840691Y329470D03*
Y349470D03*
Y369470D03*
Y389470D03*
Y409470D03*
Y429470D03*
Y449470D03*
Y469470D03*
Y489470D03*
Y509470D03*
Y529470D03*
Y549470D03*
Y569470D03*
Y589470D03*
Y669470D03*
Y1329470D03*
Y1409470D03*
Y1429470D03*
Y1449470D03*
Y1469470D03*
Y1489470D03*
Y1509470D03*
Y1529470D03*
Y1549470D03*
Y1569470D03*
Y1589470D03*
X1854470Y112379D03*
Y152379D03*
Y172379D03*
Y192379D03*
Y212379D03*
Y232379D03*
Y252379D03*
Y272379D03*
Y292379D03*
G54D60*
X922441Y154311D03*
Y243799D03*
G54D12*
X14092Y287115D03*
X17371Y49388D03*
X22223Y388057D03*
X29509Y398132D03*
X29962Y401000D03*
X24700Y765600D03*
X37371Y49388D03*
X36255Y304972D03*
X42809Y360862D03*
X39410Y384582D03*
X39226Y395346D03*
X33020Y382822D03*
X36524Y398013D03*
X30680Y438142D03*
X58379Y69340D03*
X60379Y66844D03*
Y71836D03*
X60692Y87118D03*
X54920Y185039D03*
Y177165D03*
X46834Y360862D03*
X55190D03*
X53825Y421746D03*
X54762Y444993D03*
X53800Y435451D03*
X58658Y754145D03*
X55177Y1322328D03*
X55277Y1326068D03*
X46994Y1663165D03*
X69058Y3010D03*
X79047Y23978D03*
X74091D03*
X72091Y25974D03*
X73020Y37106D03*
Y48720D03*
X67335Y69340D03*
X65335Y66844D03*
Y71836D03*
X65648Y87118D03*
X71379Y72844D03*
Y77836D03*
X76335Y72844D03*
Y77836D03*
X78335Y75340D03*
X69379D03*
X71772Y421746D03*
X75490Y432519D03*
X68365Y443677D03*
X64150Y434972D03*
X74340Y663422D03*
X76365Y699244D03*
X76565Y717949D03*
X72315Y717414D03*
X64325Y715674D03*
X75564Y1509952D03*
X78120Y1512936D03*
Y1521336D03*
X75922Y1564874D03*
Y1556474D03*
X73429Y1570008D03*
X78415D03*
X73832Y1689362D03*
X77833Y1689162D03*
X89058Y3010D03*
X81196Y17042D03*
Y22034D03*
X86152Y17042D03*
Y22034D03*
X95369Y17042D03*
Y22034D03*
X79196Y19538D03*
X88152D03*
X93369D03*
X88264Y23978D03*
X93220D03*
X86264Y25974D03*
X95220D03*
X81047D03*
X94279Y37106D03*
X87193D03*
X80106D03*
X94279Y48720D03*
X87193D03*
X80106D03*
X80379Y69340D03*
X89335D03*
X82379Y66844D03*
Y71836D03*
X87335Y66844D03*
Y71836D03*
X91379Y75340D03*
X93379Y72844D03*
Y77836D03*
X86490Y200787D03*
Y208661D03*
X85960Y224409D03*
X85788Y240157D03*
X90700Y282762D03*
Y300262D03*
X87654Y376026D03*
X87520Y386502D03*
X94811Y510173D03*
X80460Y655672D03*
X83100Y649762D03*
X82735Y717949D03*
X87865Y714394D03*
X85165D03*
X81225Y715854D03*
X79635Y717949D03*
X85835Y718049D03*
X93295Y762019D03*
X92071Y1492888D03*
X80649Y1509944D03*
X93544Y1510099D03*
X88459Y1510107D03*
X90998Y1513037D03*
Y1521437D03*
X84048Y1578008D03*
X90713Y1585852D03*
Y1589852D03*
Y1593867D03*
X90788Y1611821D03*
Y1605867D03*
Y1623821D03*
X90698Y1638362D03*
Y1634362D03*
X86245Y1690362D03*
X81833Y1689162D03*
X94220Y1686622D03*
X109058Y3010D03*
X100325Y17042D03*
Y22034D03*
X109542Y17042D03*
Y22034D03*
X102325Y19538D03*
X107542D03*
X102437Y23978D03*
X107393D03*
X100437Y25974D03*
X109393D03*
X108453Y37106D03*
X101366D03*
X108453Y48720D03*
X101366D03*
X102379Y69340D03*
X111335D03*
X104379Y66844D03*
Y71836D03*
X109335Y66844D03*
Y71836D03*
X98335Y72844D03*
Y77836D03*
X100335Y75340D03*
X101317Y431727D03*
X102060Y493578D03*
X111087Y520052D03*
X98134Y722501D03*
X99716Y1567878D03*
X99750Y1559478D03*
X96251Y1577532D03*
X107451Y1574704D03*
X100451D03*
X104318Y1592304D03*
Y1603690D03*
X110200Y1605200D03*
X104318Y1622380D03*
Y1641075D03*
X99980Y1685362D03*
Y1696052D03*
X114498Y17042D03*
Y22034D03*
X123716Y17042D03*
Y22034D03*
X116498Y19538D03*
X121716D03*
X121567Y23978D03*
X116611D03*
X114611Y25974D03*
X123567D03*
X122626Y37106D03*
X115539D03*
X122626Y48720D03*
X115539D03*
X124379Y69340D03*
X126379Y66844D03*
Y71836D03*
X115379Y72844D03*
Y77836D03*
X120335Y72844D03*
Y77836D03*
X122335Y75340D03*
X113379D03*
X114087Y285495D03*
Y302854D03*
X127206Y480216D03*
X123257Y547506D03*
X119087D03*
X115060D03*
X120267Y1327697D03*
X127366Y1535855D03*
Y1541874D03*
Y1547935D03*
X116798Y1586288D03*
Y1598572D03*
Y1635303D03*
X127195Y1670362D03*
X117795Y1698862D03*
X127195Y1688362D03*
Y1692362D03*
Y1708362D03*
X117255Y1730422D03*
X129058Y3010D03*
X128672Y17042D03*
Y22034D03*
X130672Y19538D03*
X129713Y37106D03*
Y48720D03*
X133335Y69340D03*
X131335Y66844D03*
Y71836D03*
X137379Y72844D03*
Y77836D03*
X142335Y72844D03*
Y77836D03*
X135379Y75340D03*
X130057Y636103D03*
X129600Y669400D03*
X132967Y760525D03*
X141470Y1359100D03*
X140104Y1560136D03*
X139080Y1731398D03*
X149058Y3010D03*
X159582Y17042D03*
Y22034D03*
X157582Y19538D03*
X152477Y23978D03*
X157433D03*
X150477Y25974D03*
X159433D03*
X158492Y37106D03*
X151405D03*
X158492Y48720D03*
X151405D03*
X146379Y69340D03*
X155335D03*
X148379Y66844D03*
Y71836D03*
X153335Y66844D03*
Y71836D03*
X158583Y75340D03*
X144335D03*
X149371Y423383D03*
Y419383D03*
Y427383D03*
Y439383D03*
Y431383D03*
Y435383D03*
Y443383D03*
X147141Y698811D03*
X147435Y690807D03*
X149861Y698831D03*
X150155Y690807D03*
X156685Y706836D03*
X153965Y706816D03*
X153879Y721660D03*
X156469D03*
X147031Y706835D03*
X149621D03*
X149669Y721660D03*
X147079D03*
X154477Y1360797D03*
X148663Y1378607D03*
X151163D03*
Y1383807D03*
Y1381207D03*
X158318Y1384286D03*
X155718D03*
X158318Y1387393D03*
X155718D03*
X148663Y1386407D03*
X151163D03*
X148663Y1383807D03*
Y1381207D03*
X160201Y1399732D03*
X157731D03*
Y1394132D03*
X160201D03*
X152806Y1414175D03*
X144748Y1514878D03*
X149728D03*
X154581Y1520981D03*
X158570D03*
X150502Y1572021D03*
X145522D03*
X159107Y1571364D03*
X144854Y1702389D03*
X154803Y1708532D03*
X155100Y1723262D03*
X169058Y3010D03*
X164538Y17042D03*
Y22034D03*
X173755Y17042D03*
Y22034D03*
X166538Y19538D03*
X171755D03*
X166650Y23978D03*
X171606D03*
X164650Y25974D03*
X173606D03*
X172665Y37106D03*
X165579D03*
X172665Y48720D03*
X165579D03*
X169583Y69340D03*
X171583Y66844D03*
Y71836D03*
X176539Y66844D03*
Y71836D03*
X165539Y72844D03*
X160583D03*
Y77836D03*
X165539D03*
X167539Y75340D03*
X174327Y230928D03*
X171180Y401885D03*
X163900Y409362D03*
X163132Y493299D03*
X162750Y512502D03*
X172807Y1360797D03*
X160918Y1384286D03*
X163518D03*
Y1387393D03*
X160918D03*
X169318Y1384286D03*
X166118D03*
X172262Y1384302D03*
Y1387409D03*
X174932Y1378797D03*
Y1381397D03*
X163718Y1390500D03*
X161118D03*
X162631Y1399732D03*
Y1394132D03*
X172231Y1390532D03*
X162693Y1411529D03*
X171262Y1443390D03*
X168900Y1520510D03*
X163920D03*
X166476Y1572464D03*
X171456D03*
X166529Y1707678D03*
X166661Y1721211D03*
X189058Y3010D03*
X178711Y17042D03*
Y22034D03*
X180711Y19538D03*
X179752Y37106D03*
Y48720D03*
X191583Y69340D03*
X178539D03*
X182583Y72844D03*
Y77836D03*
X187539Y72844D03*
Y77836D03*
X189539Y75340D03*
X180583D03*
X186457Y393071D03*
Y385071D03*
Y389071D03*
Y405071D03*
X192220Y408662D03*
Y412162D03*
X177871Y421383D03*
Y425383D03*
Y430883D03*
Y443383D03*
X187490Y568752D03*
X190977Y669718D03*
X191976Y684326D03*
X184215Y1361072D03*
X181403Y1361115D03*
X192620Y1360797D03*
X188233Y1387027D03*
Y1379227D03*
Y1381827D03*
Y1384427D03*
X183283Y1387987D03*
X185633Y1387027D03*
X180672Y1387987D03*
X185633Y1379227D03*
X180672Y1380187D03*
X183283D03*
X177532Y1378797D03*
X185633Y1384427D03*
Y1381827D03*
X180672Y1382787D03*
Y1385387D03*
X183283Y1382787D03*
Y1385387D03*
X177421Y1383997D03*
X177532Y1381397D03*
X182653Y1404535D03*
X192767Y1413725D03*
X185643Y1413945D03*
X185895Y1535462D03*
Y1539723D03*
Y1544029D03*
Y1548487D03*
Y1552875D03*
X176793Y1585173D03*
X188119Y1580678D03*
Y1575686D03*
Y1592590D03*
Y1587598D03*
X192529Y1728947D03*
X183822Y1720517D03*
X209058Y3010D03*
X203716Y17042D03*
Y22034D03*
X208672Y17042D03*
Y22034D03*
X201716Y19538D03*
X201567Y23978D03*
X196611D03*
X194611Y25974D03*
X203567D03*
X208784D03*
X202626Y37106D03*
X195539D03*
X202626Y48720D03*
X195539D03*
X200539Y69340D03*
X193583Y66844D03*
Y71836D03*
X198539Y66844D03*
Y71836D03*
X204717Y72844D03*
Y77836D03*
X202717Y75340D03*
X195888Y581071D03*
X194515Y583433D03*
X195888Y615071D03*
X194515Y617433D03*
Y651433D03*
X195888Y649071D03*
X205320Y667562D03*
X207856Y686443D03*
X203043Y686483D03*
X207824Y681560D03*
X203044Y684036D03*
X207834Y684006D03*
X203237Y681549D03*
X199720Y732862D03*
X206720Y731862D03*
X199220Y739362D03*
X207602Y756855D03*
X199602D03*
X201661Y1384286D03*
X193861D03*
X196461D03*
X199061D03*
X201661Y1387393D03*
X193861D03*
X196461D03*
X199061D03*
X204261Y1384286D03*
X207461D03*
X201861Y1390500D03*
X199261D03*
X195874Y1399732D03*
X198344D03*
X200774D03*
X195874Y1394132D03*
X198344D03*
X200774D03*
X201071Y1412173D03*
X193075Y1580678D03*
Y1575686D03*
X200179D03*
X205135D03*
X200179Y1580678D03*
X205135D03*
X193075Y1592590D03*
Y1587598D03*
X200179Y1592590D03*
X205135D03*
X200179Y1587598D03*
X205135D03*
X198375Y1599884D03*
X193419D03*
X205479D03*
X193419Y1616788D03*
Y1611796D03*
X198375D03*
X193419Y1604876D03*
X198375D03*
Y1616788D03*
X205479Y1611796D03*
Y1604876D03*
Y1616788D03*
X207229Y1631181D03*
X193410Y1711606D03*
X205582Y1700867D03*
X196443Y1722197D03*
X217889Y17042D03*
Y22034D03*
X222845Y17042D03*
Y22034D03*
X210672Y19538D03*
X215889D03*
X224845D03*
X215740Y23978D03*
X210784D03*
X217740Y25974D03*
X223886Y37106D03*
X216799D03*
X209713D03*
X223886Y48720D03*
X216799D03*
X209713D03*
X215717Y66844D03*
Y71836D03*
X220673Y66844D03*
Y71836D03*
X213717Y69340D03*
X222673D03*
X209673Y72844D03*
Y77836D03*
X211673Y75340D03*
X224717D03*
X209579Y457222D03*
Y462235D03*
X211220Y740362D03*
X215824Y1361199D03*
X211350Y1360797D03*
X218960Y1388312D03*
X210405Y1384302D03*
Y1387409D03*
X213075Y1381558D03*
X217133Y1384055D03*
X214425Y1384058D03*
X215675Y1381558D03*
X218175D03*
X213075Y1378958D03*
X215675D03*
X218175D03*
X210374Y1390532D03*
X212239Y1580678D03*
X217195D03*
Y1575686D03*
X212239D03*
X224299D03*
Y1580678D03*
X212239Y1587598D03*
X217195D03*
X212239Y1592590D03*
X217195D03*
X224299Y1587598D03*
Y1592590D03*
X210435Y1599884D03*
X222495D03*
X217539D03*
X210435Y1611796D03*
Y1604876D03*
Y1616788D03*
X222495D03*
X217539D03*
X222495Y1604876D03*
Y1611796D03*
X217539Y1604876D03*
Y1611796D03*
X212684Y1720307D03*
X229058Y3010D03*
X238063Y37162D03*
X230972Y37106D03*
Y48720D03*
X226717Y72844D03*
Y77836D03*
X231673Y72844D03*
Y77836D03*
X233673Y75340D03*
X233800Y162692D03*
X237539Y174266D03*
X228550Y420412D03*
X229255Y1575686D03*
Y1580678D03*
X236359D03*
Y1575686D03*
X241315Y1580678D03*
Y1575686D03*
X229255Y1587598D03*
Y1592590D03*
X236359D03*
Y1587598D03*
X241315Y1592590D03*
Y1587598D03*
X229599Y1599884D03*
X234555D03*
X229599Y1604876D03*
Y1611796D03*
X234555Y1604876D03*
Y1611796D03*
X229599Y1616788D03*
X234555D03*
X249058Y3010D03*
X243490Y23002D03*
X247720Y71862D03*
X244300Y59762D03*
X247720Y75862D03*
X251797Y100843D03*
X249735Y152694D03*
X242255Y162512D03*
X249300Y510362D03*
X253800Y515362D03*
X249860Y518222D03*
X248419Y1575686D03*
X253375D03*
X248419Y1580678D03*
X253375D03*
X248419Y1587598D03*
X253375D03*
X248419Y1592590D03*
X253375D03*
X246615Y1599884D03*
X241659D03*
X253719D03*
X241659Y1616788D03*
X246615D03*
Y1604876D03*
X241659D03*
X246615Y1611796D03*
X241659D03*
X253719Y1604876D03*
Y1611796D03*
Y1616788D03*
X269058Y3010D03*
X263280Y35312D03*
X272600Y27182D03*
X271600Y40162D03*
X272361Y120243D03*
X270364Y118415D03*
X261387Y133783D03*
X258257D03*
X264578Y155203D03*
Y159203D03*
X260700Y218662D03*
X268940Y217982D03*
X270745Y207562D03*
X265343Y244460D03*
X272029Y443735D03*
X274270Y746602D03*
X260479Y1580678D03*
X265435D03*
X260479Y1575592D03*
X265435D03*
X272539Y1575686D03*
Y1580678D03*
X260479Y1592590D03*
X265435D03*
X260479Y1587598D03*
X265435D03*
X272539D03*
Y1592590D03*
X258675Y1599884D03*
X270735Y1599790D03*
X265779D03*
X258675Y1604876D03*
Y1611796D03*
Y1616788D03*
X270735D03*
X265779D03*
X270735Y1611796D03*
Y1604876D03*
X265779D03*
Y1611796D03*
X289058Y3010D03*
X285900Y23962D03*
X287952Y39984D03*
X286071Y48720D03*
X286500Y52462D03*
X278984Y48720D03*
X287800Y60062D03*
X283953Y152503D03*
X288520Y157062D03*
X279740Y205962D03*
X276890Y249022D03*
X289920Y248652D03*
X286920D03*
X282420D03*
X287819Y691097D03*
X287820Y727962D03*
X278520Y738072D03*
X290077Y739735D03*
X289047Y760245D03*
X277495Y1575686D03*
Y1580678D03*
X284599D03*
X289555D03*
Y1575686D03*
X284599D03*
X277495Y1587598D03*
Y1592590D03*
X284599D03*
X289555D03*
X284599Y1587598D03*
X289555D03*
X282795Y1599884D03*
X277839D03*
X289899D03*
X282795Y1604876D03*
Y1611796D03*
X277839D03*
Y1604876D03*
X282795Y1616788D03*
X277839D03*
X289899D03*
Y1604876D03*
Y1611796D03*
X291520Y12762D03*
X291660Y21642D03*
X298720Y40017D03*
X306720Y39982D03*
X292942Y67513D03*
X293447Y78573D03*
X293452Y82483D03*
Y85983D03*
X303047Y79373D03*
X299947Y79273D03*
X299657Y92503D03*
X299628Y149203D03*
Y158703D03*
X294553Y153819D03*
X306087Y569718D03*
X294658Y637809D03*
X290680Y745312D03*
X299427Y768265D03*
X303831Y1318566D03*
X303807Y1342225D03*
X303831Y1344866D03*
X304047Y1368565D03*
X296659Y1575686D03*
X301615D03*
X296659Y1580678D03*
X301615D03*
X296659Y1587598D03*
X301615D03*
X296659Y1592590D03*
X301615D03*
X294855Y1599884D03*
X301959D03*
X294855Y1616788D03*
Y1604876D03*
Y1611796D03*
X301959Y1604876D03*
Y1611796D03*
Y1616788D03*
X309058Y3010D03*
X320057Y85803D03*
Y88803D03*
X314200Y585282D03*
X316080Y578262D03*
X320691Y602448D03*
X311820Y598762D03*
X316397Y776125D03*
X312301Y1345539D03*
Y1342432D03*
X309701Y1345539D03*
Y1342432D03*
X316655Y1352295D03*
X314175D03*
X311695D03*
X320101Y1342432D03*
X317701Y1348646D03*
X315101D03*
X314901Y1345539D03*
X317501D03*
X314901Y1342432D03*
X317501D03*
X316655Y1357895D03*
X311695D03*
X314175D03*
X317979Y1371248D03*
X315221Y1372445D03*
X308719Y1580678D03*
X313675D03*
X308719Y1575686D03*
X313675D03*
X320779D03*
Y1580678D03*
X308719Y1592590D03*
X313675D03*
X308719Y1587598D03*
X313675D03*
X320779D03*
Y1592590D03*
X306915Y1599884D03*
X318975D03*
X314019D03*
X306915Y1604876D03*
Y1611796D03*
Y1616788D03*
X318975D03*
X314019D03*
X318975Y1604876D03*
Y1611796D03*
X314019Y1604876D03*
Y1611796D03*
X329535Y49388D03*
X336240Y150738D03*
X330674Y368261D03*
X331760Y705882D03*
X328915Y1337104D03*
X331515D03*
X328915Y1331904D03*
X331515D03*
X328915Y1329304D03*
X331515D03*
X328915Y1334504D03*
X331515D03*
X328915Y1339704D03*
X326145Y1348651D03*
X326245Y1345555D03*
Y1342448D03*
X323301Y1342432D03*
X338917Y1349488D03*
X336347Y1348353D03*
X325735Y1575686D03*
Y1580678D03*
X332839D03*
X337795D03*
X332839Y1575686D03*
X337795D03*
X325735Y1587598D03*
Y1592590D03*
X332839D03*
X337795D03*
X332839Y1587598D03*
X337795D03*
X326079Y1599884D03*
X331035D03*
X338139D03*
X326079Y1604876D03*
Y1611796D03*
X331035Y1604876D03*
Y1611796D03*
X326079Y1616788D03*
X331035D03*
X338139D03*
Y1604876D03*
Y1611796D03*
X349535Y49388D03*
X343040Y122522D03*
X345869Y192716D03*
X353145Y228362D03*
X345164Y314234D03*
X349187Y715485D03*
X344446Y739434D03*
X348000Y755362D03*
X344429Y1322741D03*
X347029D03*
X341829D03*
X347029Y1319634D03*
X344429D03*
X341829D03*
X349629Y1322741D03*
Y1319634D03*
X352229D03*
X355429D03*
X346303Y1335097D03*
X343823D03*
Y1329497D03*
X346303D03*
X347229Y1325848D03*
X348783Y1329497D03*
X349829Y1325848D03*
X348783Y1335097D03*
X348804Y1346877D03*
X350470Y1349030D03*
X344899Y1575686D03*
X349855D03*
X344899Y1580678D03*
X349855D03*
X344899Y1587598D03*
X349855D03*
X344899Y1592590D03*
X349855D03*
X343095Y1599884D03*
X355155D03*
X350199D03*
X343095Y1616788D03*
Y1604876D03*
Y1611796D03*
X355155Y1604876D03*
Y1611796D03*
X350199Y1604876D03*
Y1611796D03*
X355155Y1616788D03*
X350199D03*
X366775Y127662D03*
X356250Y216342D03*
X358209Y208169D03*
X357764Y314234D03*
X363750Y369362D03*
X371370Y373622D03*
X364014Y382304D03*
X359930Y732985D03*
X360927Y757665D03*
X361043Y1306506D03*
X363643D03*
X367939Y1303319D03*
Y1305919D03*
Y1308519D03*
X358373Y1322757D03*
Y1319650D03*
X361043Y1314306D03*
Y1316906D03*
X362393Y1319406D03*
X361043Y1309106D03*
Y1311706D03*
X363643Y1316906D03*
Y1314306D03*
Y1309106D03*
Y1311706D03*
X358273Y1325853D03*
X370874Y1335876D03*
X367490Y1332568D03*
X356959Y1580678D03*
X361915D03*
X356959Y1575592D03*
X361915D03*
X369019Y1575686D03*
Y1580678D03*
X356959Y1592590D03*
X361915D03*
X356959Y1587598D03*
X361915D03*
X367215Y1599790D03*
X362259D03*
X369019Y1587598D03*
Y1592590D03*
X367215Y1616788D03*
X362259D03*
X367215Y1604876D03*
Y1611796D03*
X362259Y1604876D03*
Y1611796D03*
X376245Y212862D03*
Y217362D03*
Y221362D03*
Y225362D03*
X386120Y220322D03*
X385720Y323761D03*
X376500Y362736D03*
X373957Y1306208D03*
X381757D03*
X379157D03*
X376557D03*
X384357D03*
X387557D03*
X375951Y1321671D03*
X380911Y1316071D03*
X378431D03*
Y1321671D03*
X380911D03*
X373957Y1309315D03*
X381957Y1312422D03*
X381757Y1309315D03*
X379357Y1312422D03*
X379157Y1309315D03*
X376557D03*
X375951Y1316071D03*
X380842Y1334095D03*
X383549Y1333998D03*
X383127Y1395610D03*
X381060Y1433622D03*
X380930Y1531402D03*
X384210Y1534152D03*
X387152Y1582659D03*
X373975Y1575686D03*
Y1580678D03*
Y1587598D03*
Y1592590D03*
X379275Y1599884D03*
X374319D03*
X379275Y1604876D03*
Y1611796D03*
X374319Y1604876D03*
Y1611796D03*
X379275Y1616788D03*
X374319D03*
X374690Y1631700D03*
X375550Y1662052D03*
X386824Y1682866D03*
X387760Y1671092D03*
X393830Y62062D03*
X399800Y59662D03*
X403800D03*
X390830Y155833D03*
X388965Y209949D03*
X398720Y318643D03*
X403675Y363081D03*
X391195Y368199D03*
X391101Y380939D03*
X403581Y375880D03*
X390730Y394852D03*
X403570Y388874D03*
X395771Y1303480D03*
X393171D03*
X395771Y1300880D03*
X393171D03*
X395771Y1295680D03*
X393171D03*
X395771Y1298280D03*
X393171D03*
X394521Y1305980D03*
X390501Y1306224D03*
X400067Y1303319D03*
Y1300719D03*
Y1295519D03*
Y1298119D03*
Y1305919D03*
Y1308519D03*
X390401Y1312427D03*
X390501Y1309331D03*
X399673Y1332653D03*
X403130Y1335963D03*
X400919Y1411231D03*
X391370Y1424782D03*
X392108Y1582659D03*
X401812Y1616456D03*
X394910Y1632364D03*
Y1637320D03*
X402246Y1671745D03*
X409535Y49388D03*
X412930Y62572D03*
X413459Y129061D03*
X411434Y163662D03*
X407490Y216912D03*
X412820Y231922D03*
X405478Y236726D03*
X410090Y241932D03*
X420710Y242482D03*
X419023Y381760D03*
X418982Y407847D03*
X416485Y1306208D03*
X419685D03*
X413885D03*
X406085D03*
X411285D03*
X408685D03*
X414085Y1312422D03*
X413885Y1309315D03*
X411485Y1312422D03*
X408685Y1309315D03*
X406085D03*
X411285D03*
X413039Y1316071D03*
X408079D03*
X410559D03*
X413039Y1321671D03*
X408079D03*
X410559D03*
X416099Y1335568D03*
X414617Y1333473D03*
X412465Y1393878D03*
X419974Y1405289D03*
Y1412789D03*
X420474Y1420289D03*
X407125Y1424978D03*
X404475Y1552452D03*
X419002Y1600306D03*
X406526Y1591212D03*
Y1596168D03*
X406768Y1616456D03*
X408700Y1603500D03*
Y1614300D03*
X411910Y1629170D03*
Y1624214D03*
X410232Y1670244D03*
X429535Y49388D03*
X430655Y58677D03*
X433695Y214862D03*
X429395Y232562D03*
X426295Y227862D03*
X422210Y221452D03*
X429395Y236562D03*
Y240562D03*
X425249Y338061D03*
X431503Y376642D03*
X431462Y402729D03*
X422629Y1306224D03*
X432195Y1303319D03*
Y1305919D03*
X425299Y1303480D03*
X426649Y1305980D03*
X427899Y1303480D03*
X425299Y1295680D03*
X427899D03*
X432195Y1295519D03*
Y1298119D03*
X427899Y1298280D03*
X425299D03*
X432195Y1300719D03*
X427899Y1300880D03*
X425299D03*
X432195Y1308519D03*
X422529Y1312427D03*
X422629Y1309331D03*
X434983Y1335924D03*
X431578Y1332560D03*
X427474Y1405289D03*
X434974D03*
Y1412789D03*
X427474Y1420289D03*
X434974D03*
X423958Y1600306D03*
X428099Y1586282D03*
X428941Y1606441D03*
X449535Y49388D03*
X443678Y145710D03*
X445964Y314234D03*
X450400Y338812D03*
X442853Y542519D03*
Y547519D03*
X448613Y1306208D03*
X446013D03*
X443413D03*
X440813D03*
X438213D03*
X451813D03*
X443613Y1312422D03*
X443413Y1309315D03*
X440813D03*
X438213D03*
X446213Y1312422D03*
X446013Y1309315D03*
X440207Y1316071D03*
X445167D03*
X442687D03*
X440207Y1321671D03*
X445167D03*
X442687D03*
X446944Y1335928D03*
X445153Y1334095D03*
X446258Y1441606D03*
X449778D03*
X451910Y1643282D03*
X437562Y1649770D03*
X442518D03*
X469535Y49388D03*
X454568Y78782D03*
X466992Y145888D03*
X458264Y254862D03*
X460300Y303662D03*
X468490Y340572D03*
X469830Y366158D03*
X460323Y510183D03*
X458327Y1303980D03*
X460927D03*
X464427Y1305380D03*
X454757Y1306224D03*
X460927Y1306580D03*
X458327D03*
Y1301380D03*
X460927D03*
X464427Y1300180D03*
Y1302780D03*
X458327Y1296180D03*
X460927D03*
X464427D03*
X458327Y1298780D03*
X460927D03*
X464423Y1308519D03*
X454657Y1312427D03*
X454757Y1309331D03*
X464738Y1333085D03*
X467644Y1335981D03*
X455576Y1409125D03*
Y1417125D03*
Y1420625D03*
Y1427632D03*
Y1424125D03*
X454450Y1433580D03*
X464160Y1587122D03*
X458414Y1624994D03*
Y1629950D03*
X468040Y1654807D03*
X478240Y55935D03*
Y66575D03*
Y61129D03*
X484396Y161364D03*
X475500Y212685D03*
X472800Y299462D03*
X484800Y307362D03*
X476740Y309272D03*
X479740Y300202D03*
X482920Y398060D03*
X479379Y452445D03*
X480741Y1306208D03*
X478141D03*
X475541D03*
X472941D03*
X470341D03*
X483941D03*
X472941Y1309315D03*
X478141D03*
X470341D03*
X478341Y1312422D03*
X475741D03*
X475541Y1309315D03*
X472335Y1316071D03*
X477295D03*
X474815D03*
X472335Y1321671D03*
X477295D03*
X474815D03*
X477162Y1334095D03*
X478909Y1336038D03*
X485236Y1417844D03*
X482741Y1438698D03*
X482742Y1441312D03*
X484333Y1575686D03*
Y1580678D03*
X477229D03*
X472273D03*
Y1575686D03*
X477229D03*
X482529Y1599884D03*
X477573D03*
X484333Y1587598D03*
Y1592590D03*
X472273D03*
X477229D03*
Y1587598D03*
X472273D03*
X482529Y1616788D03*
X477573D03*
Y1611796D03*
X482529D03*
X477573Y1604876D03*
X482529D03*
X472210Y1618626D03*
X485150Y1624942D03*
X477905Y1667242D03*
X489535Y49347D03*
X497002Y88167D03*
X501540Y105152D03*
X498630Y140492D03*
X489980Y250512D03*
X492074Y300306D03*
X497568Y397632D03*
X494193Y550447D03*
X486885Y1306224D03*
X496451Y1306345D03*
X489555Y1303480D03*
X492155D03*
X490905Y1305980D03*
X492155Y1300880D03*
X489555D03*
X486785Y1312427D03*
X486885Y1309331D03*
X496220Y1322440D03*
X496451Y1316745D03*
Y1308945D03*
Y1314145D03*
Y1311545D03*
X499458Y1349468D03*
X499818Y1385027D03*
X499859Y1393027D03*
X490307Y1421499D03*
X491156Y1438713D03*
X499541Y1438698D03*
X491142Y1441312D03*
X499542D03*
X501349Y1580678D03*
X496393D03*
Y1575686D03*
X501349D03*
X489289D03*
Y1580678D03*
X501693Y1599884D03*
X494589D03*
X489633D03*
X501349Y1592590D03*
X496393D03*
X501349Y1587598D03*
X496393D03*
X489289D03*
Y1592590D03*
X501693Y1611796D03*
Y1604876D03*
Y1616788D03*
X489633Y1611796D03*
X494589Y1604876D03*
X489633D03*
X494589Y1611796D03*
X489633Y1616788D03*
X494589D03*
X487340Y1641352D03*
X517902Y69508D03*
X510815D03*
X503100Y78402D03*
X510030Y78412D03*
X504980Y101752D03*
X503290Y140492D03*
X507360D03*
X514850Y168443D03*
X504075Y231262D03*
X508000Y237862D03*
X505900Y311562D03*
X510740Y332592D03*
X513173Y408740D03*
X514425Y489112D03*
Y495112D03*
X509493Y539819D03*
X513025Y615742D03*
X516069Y1319634D03*
X502469D03*
Y1322741D03*
X512869Y1319634D03*
X510269D03*
X507669D03*
X505069D03*
X507669Y1322741D03*
X505069D03*
X510269D03*
X504463Y1329497D03*
Y1335097D03*
X509423Y1329497D03*
X506943D03*
X509423Y1335097D03*
X506943D03*
X510469Y1325848D03*
X507869D03*
X509382Y1347521D03*
X511149Y1349468D03*
X505018Y1385027D03*
X502418D03*
X505059Y1393027D03*
X502459D03*
X508001Y1438669D03*
X507942Y1441312D03*
X508453Y1575686D03*
X513409D03*
X508453Y1580678D03*
X513409D03*
X513753Y1599884D03*
X506649D03*
X508453Y1587598D03*
X513409D03*
X508453Y1592590D03*
X513409D03*
X513753Y1616788D03*
Y1604876D03*
Y1611796D03*
X506649D03*
Y1604876D03*
Y1616788D03*
X518606Y23797D03*
X532075Y69508D03*
Y57894D03*
X524988Y69508D03*
X529239Y99997D03*
Y92911D03*
X528400Y104225D03*
Y114275D03*
X527823Y131802D03*
Y149802D03*
X527278Y164726D03*
X529480Y183921D03*
X536127Y247652D03*
X523660Y323222D03*
X535220Y383552D03*
X528145Y408705D03*
X518735Y452442D03*
X526852Y511331D03*
X527042Y505830D03*
X526853Y516817D03*
X523033Y1319406D03*
X519013Y1319650D03*
Y1322757D03*
X527645Y1326076D03*
X528579Y1329143D03*
X528377Y1335982D03*
X518913Y1325853D03*
X528579Y1342143D03*
Y1344743D03*
X534597Y1345539D03*
Y1342432D03*
X528975Y1369724D03*
X532573Y1575686D03*
Y1580678D03*
X520513D03*
X525469D03*
X520513Y1575686D03*
X525469D03*
X525813Y1599884D03*
X530769D03*
X518709D03*
X532573Y1587598D03*
Y1592590D03*
X525469D03*
X520513D03*
Y1587598D03*
X525469D03*
X525813Y1611796D03*
X530769D03*
X525813Y1604876D03*
X530769D03*
Y1616788D03*
X525813D03*
X518709D03*
Y1604876D03*
Y1611796D03*
X548609Y32500D03*
X546248Y69508D03*
X539161D03*
Y57894D03*
X546234Y77443D03*
X542620Y103352D03*
X537360Y120522D03*
X550545Y147302D03*
X542798Y202646D03*
X535630Y306602D03*
X543035Y441005D03*
X538120Y463137D03*
X544813Y1322668D03*
X542213D03*
X538293D03*
X535693D03*
X548197Y1342432D03*
X539997Y1348646D03*
X542397Y1345539D03*
X542597Y1348646D03*
X537197Y1342432D03*
X539797D03*
X542397D03*
X544997D03*
X537197Y1345539D03*
X539797D03*
X539071Y1352295D03*
X536591D03*
X541551D03*
Y1357895D03*
X542256Y1369935D03*
X536591Y1357895D03*
X539071D03*
X549589Y1580678D03*
X544633D03*
X549589Y1575592D03*
X544633D03*
X537529Y1575686D03*
Y1580678D03*
X549933Y1599790D03*
X537873Y1599884D03*
X542829D03*
X549589Y1592590D03*
X544633D03*
X549589Y1587598D03*
X544633D03*
X537529D03*
Y1592590D03*
X549933Y1611796D03*
Y1604876D03*
Y1616788D03*
X542829D03*
X537873D03*
Y1604876D03*
X542829D03*
X537873Y1611796D03*
X542829D03*
X560421Y69508D03*
X553335D03*
X553320Y77443D03*
X564988Y118670D03*
X555545Y134340D03*
X565500Y145252D03*
X555220Y167937D03*
X553657Y193862D03*
X564944Y252173D03*
X553536Y307527D03*
X569080Y414002D03*
X559300Y422732D03*
X558933Y1323658D03*
Y1326258D03*
X556563Y1337918D03*
X553963D03*
X558933Y1328938D03*
X556563Y1335318D03*
Y1332718D03*
X558933Y1331538D03*
X553963Y1335318D03*
Y1332718D03*
X555313Y1340418D03*
X551141Y1345555D03*
X551041Y1348651D03*
X551141Y1342448D03*
X555372Y1343037D03*
X561070Y1346174D03*
X556693Y1575686D03*
X561649D03*
X556693Y1580678D03*
X561649D03*
X561993Y1599884D03*
X554889Y1599790D03*
X556693Y1587598D03*
X561649D03*
Y1592590D03*
X556693D03*
X561993Y1616788D03*
Y1604876D03*
Y1611796D03*
X554889D03*
Y1604876D03*
Y1616788D03*
X567673Y130542D03*
X581175Y164717D03*
X569965Y161232D03*
X579481Y202378D03*
Y210378D03*
X568149Y217916D03*
X580712Y215877D03*
X581645Y233362D03*
X569668Y229812D03*
X578711Y230109D03*
X578509Y265132D03*
X569880Y300992D03*
X580400Y302402D03*
X582436Y361032D03*
X570200Y372229D03*
X570760Y451710D03*
X571990Y501046D03*
X571700Y552200D03*
X580813Y1575686D03*
Y1580678D03*
X573709D03*
X568753D03*
Y1575686D03*
X573709D03*
X579009Y1599884D03*
X574053D03*
X566949D03*
X580813Y1587598D03*
Y1592590D03*
X573709D03*
X568753D03*
X573709Y1587598D03*
X568753D03*
X574053Y1616788D03*
X579009D03*
Y1611796D03*
X574053D03*
X579009Y1604876D03*
X574053D03*
X566949Y1616788D03*
Y1604876D03*
Y1611796D03*
X591395Y132142D03*
X595220Y140922D03*
X588000D03*
X592710Y156342D03*
X593248Y159480D03*
X598295Y171862D03*
X596581Y184849D03*
X590337Y177604D03*
X598760Y203712D03*
X593966Y229965D03*
X592039Y252202D03*
X588577Y285862D03*
X586820Y314662D03*
X597820Y317062D03*
X592920Y326362D03*
X591720Y430787D03*
X599220Y444362D03*
X593545Y488212D03*
X594090Y505107D03*
X589260Y519421D03*
X594240Y511953D03*
X593675Y534702D03*
X589989Y745475D03*
X597829Y1580678D03*
X592873D03*
X597829Y1575686D03*
X592873D03*
X585769D03*
Y1580678D03*
X598173Y1599884D03*
X586113D03*
X591069D03*
X597829Y1592590D03*
X592873D03*
X597829Y1587598D03*
X592873D03*
X585769D03*
Y1592590D03*
X598173Y1616788D03*
Y1611796D03*
Y1604876D03*
X586113D03*
X591069D03*
X586113Y1611796D03*
X591069D03*
Y1616788D03*
X586113D03*
X615185Y69508D03*
X603374D03*
X601050Y100008D03*
X610104Y119342D03*
X602306Y143077D03*
X602430Y153862D03*
X606260Y161652D03*
X615572Y173942D03*
X615573Y181984D03*
X614531Y200378D03*
X611030Y188372D03*
X603340Y208142D03*
X614531Y209878D03*
X609456Y204994D03*
X606719Y254966D03*
X609844Y330407D03*
X608830Y374302D03*
X605830Y402782D03*
X604779Y423862D03*
X600351Y461862D03*
X614220Y452862D03*
X610820Y472862D03*
X603779Y486922D03*
X606200Y514862D03*
X609520Y515162D03*
X614086Y537624D03*
X614000Y550800D03*
X603317Y738415D03*
X614660Y739553D03*
X602027Y761445D03*
X612407Y769485D03*
X609889Y1575686D03*
X604933D03*
X609889Y1580678D03*
X604933D03*
X615189Y1599884D03*
X610233D03*
X603129D03*
X609889Y1587598D03*
X604933D03*
X609889Y1592590D03*
X604933D03*
X615189Y1604876D03*
X610233D03*
X615189Y1611796D03*
X610233D03*
X615189Y1616788D03*
X610233D03*
X603129D03*
Y1611796D03*
Y1604876D03*
X631546Y85024D03*
X618460Y119342D03*
X631300Y167872D03*
X628195Y178414D03*
X628194Y170372D03*
X630818Y191248D03*
X625862D03*
X620030Y188782D03*
X627645Y236862D03*
X629564Y256277D03*
X623150Y273172D03*
X625800Y311912D03*
X628294Y317007D03*
X623580Y336429D03*
X629248Y436972D03*
X629220Y472862D03*
Y477862D03*
Y467862D03*
Y482862D03*
X626207Y747585D03*
X618114Y1258470D03*
X629053Y1575686D03*
Y1580678D03*
X621949D03*
X616993D03*
X621949Y1575686D03*
X616993D03*
X622293Y1599884D03*
X627249D03*
X629053Y1587598D03*
Y1592590D03*
X621949D03*
X616993D03*
X621949Y1587598D03*
X616993D03*
X627249Y1616788D03*
X622293D03*
Y1611796D03*
X627249D03*
X622293Y1604876D03*
X627249D03*
X646440Y43632D03*
X632463Y43302D03*
X645150Y69508D03*
X645350Y60612D03*
X632640Y107532D03*
X637500Y110362D03*
X642480Y184862D03*
X645876Y296231D03*
X633138Y296766D03*
X645528Y308623D03*
X645807Y304291D03*
X647200Y354300D03*
X643736Y457214D03*
X644245Y472862D03*
X644220Y467862D03*
X644245Y482862D03*
X636960Y516002D03*
X646069Y1580678D03*
X641113D03*
X646069Y1575592D03*
X641113D03*
X634009Y1575686D03*
Y1580678D03*
X646413Y1599790D03*
X639309Y1599884D03*
X634353D03*
X646069Y1592590D03*
X641113D03*
X646069Y1587598D03*
X641113D03*
X634009D03*
Y1592590D03*
X646413Y1616788D03*
Y1611796D03*
Y1604876D03*
X639309D03*
X634353D03*
X639309Y1611796D03*
X634353D03*
Y1616788D03*
X639309D03*
X641057Y1648659D03*
X645407Y1660425D03*
X639745Y1714362D03*
X648290Y1720052D03*
X639745Y1726362D03*
X661550Y45133D03*
X654464D03*
X652153Y98105D03*
X652680Y89712D03*
X651579Y102703D03*
X659000Y89262D03*
X651980Y133822D03*
X650790Y144982D03*
X660690Y408162D03*
X660720Y404362D03*
X653800Y498740D03*
X662282Y1386432D03*
X654606Y1431203D03*
X653173Y1575686D03*
X658129D03*
X653173Y1580678D03*
X658129D03*
X663429Y1599884D03*
X658473D03*
X651369Y1599790D03*
X653173Y1587598D03*
X658129D03*
X653173Y1592590D03*
X658129D03*
X663429Y1604876D03*
X658473D03*
X663429Y1611796D03*
X658473D03*
Y1616788D03*
X663429D03*
X651369D03*
Y1611796D03*
Y1604876D03*
X663043Y1647557D03*
X655307Y1647436D03*
X663118Y1659557D03*
X663145Y1664862D03*
Y1676862D03*
X656973Y1698727D03*
X652712Y1686275D03*
X672005Y44119D03*
X668800Y45262D03*
X666406Y69508D03*
X675225Y58108D03*
X673750Y77692D03*
X673690Y200672D03*
X673300Y211332D03*
X667020Y225762D03*
X680600Y375462D03*
X668329Y411714D03*
X677295Y404362D03*
X677195Y408262D03*
X674628Y414864D03*
Y443210D03*
X671479Y430612D03*
Y462108D03*
X668329Y481006D03*
X675220Y503837D03*
X680220D03*
X675220Y516852D03*
X671607Y742835D03*
X668096Y1360822D03*
X677137Y1384311D03*
X674537D03*
X671937D03*
X669337D03*
X677137Y1387418D03*
X674537D03*
X671937D03*
X669337D03*
X664782Y1383832D03*
Y1381232D03*
Y1378632D03*
Y1386432D03*
X679737Y1384311D03*
X677337Y1390525D03*
X674737D03*
X676250Y1399757D03*
X673820D03*
X671350D03*
X676250Y1394157D03*
X673820D03*
X671350D03*
X666425Y1414200D03*
X676312Y1411554D03*
X667926Y1547018D03*
X679192Y1564252D03*
X678515Y1573910D03*
X676648Y1657380D03*
X671620Y1670862D03*
X674195Y1708362D03*
X669120Y1718862D03*
X674195Y1732362D03*
X696838Y45112D03*
X686854Y43701D03*
X692380Y43532D03*
X682941Y69982D03*
X687050Y79212D03*
X685230Y76952D03*
X683820Y79192D03*
X682890Y72642D03*
X684953Y104968D03*
X694390Y133682D03*
X684520Y152482D03*
X688520D03*
X692520D03*
X686760Y222912D03*
X685600Y375462D03*
X690600D03*
X695600D03*
X688220Y388362D03*
X697220Y404362D03*
X697120Y408262D03*
X684077Y414864D03*
X680928Y424313D03*
X696676Y436911D03*
X693526Y443210D03*
Y440061D03*
Y436911D03*
X690376Y440061D03*
Y433761D03*
X693526Y452659D03*
Y449510D03*
X696676Y455809D03*
X693526D03*
X690376Y452659D03*
Y458959D03*
X696676Y477856D03*
X684077D03*
X680928Y468407D03*
X690220Y516852D03*
X684357Y742345D03*
X692784Y1298845D03*
X686426Y1360822D03*
X695022Y1361990D03*
X696462Y1386122D03*
X682937Y1384311D03*
X685881Y1384327D03*
Y1387434D03*
X691351Y1380922D03*
X688751D03*
X691240Y1383522D03*
X693851D03*
Y1378322D03*
Y1380922D03*
X691351Y1378322D03*
X688751D03*
X693851Y1386122D03*
X696462Y1378322D03*
Y1383522D03*
Y1380922D03*
X696272Y1404560D03*
X685850Y1390557D03*
X685015Y1438475D03*
X696940Y1437955D03*
X689875Y1577913D03*
X689128Y1652262D03*
X692595Y1670862D03*
X701838Y45112D03*
X700610Y57782D03*
X700741Y83050D03*
X706673Y122762D03*
X703520Y122540D03*
X704880Y133643D03*
X701926Y166535D03*
Y178346D03*
Y184252D03*
Y172441D03*
Y190157D03*
Y196063D03*
Y201968D03*
Y207874D03*
Y213779D03*
Y219685D03*
X700600Y375462D03*
X705600D03*
X706125Y421163D03*
X709274Y436911D03*
X706125Y440061D03*
Y436911D03*
X699825Y440061D03*
Y436911D03*
X712424Y443210D03*
Y440061D03*
Y436911D03*
Y455809D03*
X709274D03*
X706125D03*
Y452659D03*
X699825Y455809D03*
Y452659D03*
X712424D03*
Y449510D03*
X709274Y477856D03*
X699825Y468407D03*
X711220Y516852D03*
X705220D03*
X698600Y530700D03*
X701917Y742865D03*
X703755Y1290545D03*
X708795Y1303701D03*
X698094Y1361947D03*
X706239Y1360822D03*
X699062Y1380922D03*
Y1383522D03*
Y1378322D03*
X707480Y1384311D03*
X710080D03*
X707480Y1387418D03*
X710080D03*
X701662Y1380922D03*
Y1383522D03*
Y1378322D03*
X699062Y1386122D03*
X701662D03*
X712680Y1384311D03*
Y1387418D03*
X709493Y1399757D03*
Y1394157D03*
X712880Y1390525D03*
X711963Y1399757D03*
Y1394157D03*
X699262Y1413970D03*
X704568Y1414119D03*
X706680Y1437535D03*
X701730Y1437855D03*
X711440Y1436905D03*
X702112Y1583683D03*
X709111Y1618842D03*
X697595Y1658862D03*
X704433Y1657964D03*
X697770Y1680810D03*
X714015Y-27612D03*
X720308Y-26403D03*
X714015Y-21457D03*
Y-17583D03*
X714030Y-15068D03*
X714015Y-11428D03*
X714030Y-25097D03*
X720308Y-16374D03*
X714015Y-7554D03*
X714030Y-5039D03*
X720308Y-6345D03*
X728980Y39872D03*
X728028Y101968D03*
X728023Y98058D03*
X728028Y105468D03*
X727720Y356362D03*
X725220Y380787D03*
X715600Y375462D03*
X718220Y388362D03*
X715220Y404362D03*
X715120Y408262D03*
X725022Y414864D03*
X715574Y433761D03*
Y458959D03*
X728172Y449510D03*
X725022Y477856D03*
X722720Y521362D03*
X729200Y588952D03*
X713836Y1283689D03*
X724969Y1360822D03*
X729443Y1361224D03*
X726694Y1381583D03*
Y1378983D03*
X715280Y1384311D03*
X717880D03*
X715280Y1387418D03*
X721080Y1384311D03*
X724024Y1384327D03*
Y1387434D03*
X728044Y1384083D03*
X729294Y1381583D03*
Y1378983D03*
X715480Y1390525D03*
X723993Y1390557D03*
X714393Y1399757D03*
Y1394157D03*
X714455Y1411554D03*
X718230Y1600372D03*
X725378Y1614503D03*
X719770Y1614590D03*
X715780D03*
X722040Y1623970D03*
X713791Y1629816D03*
X721345Y1647300D03*
X716140Y1649895D03*
X726830Y1655380D03*
X724500Y1676500D03*
X744987Y49062D03*
X742840Y39832D03*
X736790D03*
X745130Y69508D03*
X738043D03*
X730957D03*
X731330Y60712D03*
X730820Y84062D03*
X737623Y98858D03*
X734523Y98758D03*
X735733Y111988D03*
X733220Y388362D03*
X737621Y411714D03*
X743720Y404362D03*
X743820Y408262D03*
X731322Y430612D03*
Y462108D03*
X737621Y481006D03*
X730070Y506212D03*
X744630Y506529D03*
X745220Y530362D03*
X737299Y766887D03*
X737784Y1360017D03*
X730752Y1384080D03*
X731794Y1381583D03*
Y1378983D03*
X732238Y1388343D03*
X738810Y1396665D03*
X741540Y1396585D03*
X739170Y1405655D03*
X741670Y1405675D03*
X738170Y1414185D03*
X740760Y1414165D03*
X741382Y1590691D03*
X758606Y23797D03*
X747487Y49062D03*
X752720Y59002D03*
X754219Y75707D03*
X754633Y108288D03*
Y105288D03*
X762172Y123898D03*
X754290Y286632D03*
X755200Y296062D03*
X759940Y438232D03*
X758420Y447662D03*
X751220Y530362D03*
X753137Y766625D03*
X757779Y1390645D03*
X757542Y1420684D03*
X761770Y1695347D03*
X765606Y44894D03*
X769474Y75360D03*
X765858Y87340D03*
X762368Y84088D03*
X769284Y103895D03*
X767061Y99959D03*
X767045Y95960D03*
X767028Y91490D03*
X776730Y117479D03*
X773943Y114633D03*
X771131Y111788D03*
X769775Y107977D03*
X766769Y140138D03*
X771774Y167518D03*
X773220Y296262D03*
X772866Y311558D03*
X776100Y375100D03*
X766195Y418212D03*
X765315Y464862D03*
Y488862D03*
X772220Y530362D03*
X775317Y764025D03*
X763747Y764335D03*
X768520Y1379962D03*
X768620Y1392762D03*
X767820Y1410262D03*
X785095Y49388D03*
X780617Y296345D03*
X779120Y306162D03*
X794600Y360600D03*
X787925Y387900D03*
X781195Y418212D03*
X791590Y417050D03*
X780020Y438287D03*
X781410Y431822D03*
X780340Y468982D03*
Y474862D03*
X793673Y512862D03*
X792720Y589862D03*
X789720Y581862D03*
X783100Y593582D03*
X788225Y1388683D03*
X805095Y49388D03*
X797443Y271469D03*
X806300Y279662D03*
X809700Y273562D03*
X795190Y298572D03*
X798620Y312773D03*
X809800Y360600D03*
X802200D03*
X806588Y351097D03*
X799800Y368700D03*
X802220Y393727D03*
X803150Y408512D03*
X795600Y402500D03*
X799458Y431217D03*
X795370Y474862D03*
X801567Y512942D03*
X798720Y585362D03*
X798220Y597362D03*
X808860Y603802D03*
X797720Y617862D03*
X799637Y763625D03*
X825095Y49388D03*
X821118Y134632D03*
X825698Y139062D03*
X813900Y269698D03*
X827403Y286625D03*
X816420Y287062D03*
X813855Y354008D03*
X820936Y356956D03*
X824980Y405260D03*
Y409260D03*
X821720Y428437D03*
X818500Y451700D03*
X816500Y476800D03*
X821720Y519082D03*
X815040Y590772D03*
X814800Y760922D03*
X822442Y762369D03*
X814234Y1340465D03*
X830975Y2388D03*
X830990Y4903D03*
X837268Y3597D03*
X830975Y22446D03*
Y8543D03*
Y12417D03*
X830990Y14932D03*
X830975Y18572D03*
X837268Y13626D03*
X830990Y24961D03*
X837268Y23655D03*
X836126Y62681D03*
X837791Y85186D03*
X831297Y104206D03*
X842864Y110296D03*
X830339Y228143D03*
X829680Y264580D03*
X836210Y272452D03*
X829720Y277562D03*
X829800Y271562D03*
X829320Y296762D03*
X834400Y283862D03*
X834900Y293462D03*
X828222Y359960D03*
X835471Y363003D03*
X843133Y366158D03*
X833300Y386500D03*
X838784Y392880D03*
X839200Y434300D03*
X841300Y446800D03*
X842600Y477200D03*
X842341Y474241D03*
X841795Y492862D03*
X829745Y498082D03*
X834635Y515447D03*
X830480Y527817D03*
X831700Y596962D03*
X836847Y762495D03*
X828799Y1336870D03*
X828910Y1331756D03*
Y1341725D03*
X845095Y49388D03*
X854107Y91232D03*
X850280Y113852D03*
X853828Y265057D03*
X854333Y276117D03*
X854338Y280027D03*
Y283527D03*
X852800Y288562D03*
X853200Y297462D03*
X856700Y304862D03*
X848000Y374622D03*
X851396Y369614D03*
X859734Y373032D03*
X857560Y417762D03*
X844200Y418800D03*
X847830Y443892D03*
X843810Y453322D03*
X846700Y473000D03*
X848710Y505641D03*
X860345Y522162D03*
X856698Y594011D03*
X853200Y751062D03*
X854687Y761685D03*
X865095Y49388D03*
X868187Y72006D03*
X860937Y71877D03*
X861350Y61672D03*
X871980Y199500D03*
X860833Y276817D03*
X863933Y276917D03*
X862043Y290047D03*
X867922Y376450D03*
X875922Y379793D03*
X870700Y382415D03*
Y390620D03*
Y394620D03*
X871320Y416752D03*
X862620Y503162D03*
Y499062D03*
X860345Y513062D03*
X892214Y141891D03*
X878220Y192055D03*
X880943Y283347D03*
Y286347D03*
X880473Y329370D03*
X883472Y382910D03*
X886362Y534380D03*
X886500Y739162D03*
X878152Y876760D03*
X889439Y1437938D03*
X903930Y202885D03*
X903980Y210355D03*
X903930Y217059D03*
X903980Y224529D03*
X893500Y339062D03*
X900061Y510962D03*
X906127Y496343D03*
X900061Y517898D03*
X893298Y534380D03*
X899462Y533380D03*
X906398D03*
X897000Y891895D03*
X894375Y913692D03*
X912214Y141891D03*
X917680Y174999D03*
Y177999D03*
Y171999D03*
X909386Y195925D03*
Y203011D03*
Y210098D03*
Y217185D03*
Y224271D03*
Y231358D03*
X919279Y461244D03*
X920682Y494586D03*
X920980Y503393D03*
X911720Y511662D03*
X911626Y523430D03*
X918562D03*
X924647Y526808D03*
Y533744D03*
X924600Y824262D03*
X922320Y1660953D03*
X932214Y141891D03*
X927133Y189386D03*
X925320Y203399D03*
X940709Y460438D03*
X938437Y455454D03*
X932724Y455538D03*
X926215Y461244D03*
X929234Y494915D03*
X938588Y485197D03*
X929698Y503595D03*
X928231Y530479D03*
X936273Y530478D03*
X927200Y811462D03*
X931496Y962082D03*
X929221Y1014664D03*
X927122Y1661380D03*
X938220Y1661062D03*
X952214Y141891D03*
X949710Y198289D03*
X941634Y199051D03*
Y193451D03*
X951354Y209437D03*
Y203837D03*
X944880Y210959D03*
Y216559D03*
Y230697D03*
Y225097D03*
X954874Y232071D03*
X954904Y225741D03*
X942827Y422743D03*
Y429679D03*
X945800Y432463D03*
Y439399D03*
X946492Y460410D03*
X956188Y495384D03*
Y502320D03*
X948495Y502784D03*
X948693Y509497D03*
X956188Y509484D03*
Y516420D03*
X952622Y529364D03*
X956700Y786862D03*
X941400Y810062D03*
X946100Y1661100D03*
X972214Y141891D03*
X963520Y214699D03*
X960703Y212668D03*
X971471Y242358D03*
X965792Y350959D03*
X965420Y365719D03*
X963856Y394202D03*
X960059Y387004D03*
X972986Y393171D03*
X970054Y478773D03*
Y485709D03*
X966720Y511362D03*
X960620Y509462D03*
X972379Y509303D03*
X959558Y529364D03*
X962162Y535130D03*
X969098D03*
X958755Y657078D03*
X963520Y665062D03*
X958866Y662378D03*
X959100Y789862D03*
X965622Y1579240D03*
Y1576240D03*
Y1573240D03*
X975688Y152950D03*
Y149950D03*
X985016Y344659D03*
X974791Y339990D03*
X986182Y361062D03*
X979380Y373082D03*
X988159Y409068D03*
X983760Y424292D03*
X980092Y421289D03*
X983720Y512362D03*
X976283Y534226D03*
X988988Y1579240D03*
Y1573240D03*
Y1576240D03*
X994553Y365711D03*
X997598Y382952D03*
X997612Y391804D03*
X1006221Y382945D03*
X997900Y400720D03*
X993387Y429827D03*
X999720Y512862D03*
X991097Y529902D03*
X996675Y1286985D03*
X1012214Y141826D03*
X1022002Y267342D03*
Y270142D03*
X1013500Y344900D03*
X1015638Y382968D03*
X1015637Y391334D03*
X1006589Y392017D03*
X1006750Y401010D03*
X1015657Y401013D03*
X1021259Y420548D03*
X1007249Y422682D03*
X1017511Y430038D03*
X1008720Y498362D03*
X1019145Y503823D03*
X1011720Y589362D03*
X1018720Y592362D03*
X1021720Y601862D03*
X1010630Y748741D03*
X1012354Y1579240D03*
Y1573240D03*
Y1576240D03*
X1023407Y-27681D03*
X1029700Y-26472D03*
X1023407Y-32055D03*
X1029700Y-37001D03*
X1023407Y-17652D03*
X1023422Y-15137D03*
X1023407Y-11497D03*
X1029700Y-16443D03*
X1023422Y-25166D03*
X1023407Y-21526D03*
X1029700Y3615D03*
X1023422Y4921D03*
X1023407Y2406D03*
X1023422Y-5108D03*
X1023407Y-7623D03*
Y-1468D03*
X1029700Y-6414D03*
X1023407Y22464D03*
Y18590D03*
Y8561D03*
X1023422Y14950D03*
X1023407Y12435D03*
X1029700Y13644D03*
Y23673D03*
X1023422Y24979D03*
X1038609Y49388D03*
X1027520Y122732D03*
X1037650Y128842D03*
X1023220Y187574D03*
X1031502Y267342D03*
X1028202D03*
X1025102D03*
X1033133Y272564D03*
X1031502Y270142D03*
X1029833Y272564D03*
X1026733D03*
X1023633D03*
X1028202Y270142D03*
X1025102D03*
X1029094Y383070D03*
Y387872D03*
X1033860Y400802D03*
X1038294Y506504D03*
X1027190Y510672D03*
X1029220Y520032D03*
X1035720Y1579240D03*
Y1573240D03*
Y1576240D03*
X1043629Y375078D03*
Y372578D03*
X1049100Y390162D03*
X1046156Y442699D03*
X1058609Y49388D03*
X1066820Y151632D03*
X1072310Y364422D03*
X1059086Y1579240D03*
Y1573240D03*
Y1576240D03*
X1078609Y49388D03*
X1075100Y55682D03*
X1084146Y67102D03*
X1078270Y93462D03*
X1077270Y369061D03*
Y374131D03*
Y379251D03*
X1073724Y476867D03*
X1081906Y472577D03*
X1076739Y506461D03*
X1077751Y522235D03*
X1098609Y49388D03*
X1097794Y67881D03*
X1102480Y133722D03*
X1105553Y356475D03*
X1096477Y744385D03*
X1102930Y1668690D03*
X1092072Y1734244D03*
X1118609Y49388D03*
X1118110Y1398010D03*
X1109118Y1526046D03*
X1116338Y1711380D03*
X1113055Y1718338D03*
X1132856Y52926D03*
X1129948Y66786D03*
X1127788Y1397126D03*
X1131629Y1420615D03*
X1129029D03*
X1134229D03*
X1123674Y1414936D03*
X1121174D03*
X1123674Y1417536D03*
Y1420136D03*
X1121174Y1417536D03*
Y1420136D03*
X1131629Y1423722D03*
X1129029D03*
X1134229D03*
X1123674Y1422736D03*
X1121174D03*
X1131042Y1436061D03*
X1135942D03*
X1133512D03*
X1131042Y1430461D03*
X1135942D03*
X1133512D03*
X1134429Y1426829D03*
X1136004Y1447858D03*
X1126117Y1450504D03*
X1127008Y1550285D03*
X1133780Y1550301D03*
X1138609Y49388D03*
X1145603Y73679D03*
X1140465Y379592D03*
X1142302Y366532D03*
X1142790Y611122D03*
X1146118Y1397126D03*
X1150843Y1415126D03*
X1148243D03*
X1150843Y1417726D03*
X1148243D03*
X1150732Y1420326D03*
X1142629Y1420615D03*
X1145573Y1420631D03*
X1139429Y1420615D03*
X1136829D03*
X1145573Y1423738D03*
X1136829Y1423722D03*
X1145542Y1426861D03*
X1137029Y1426829D03*
X1145108Y1476732D03*
X1158609Y49388D03*
X1156790Y373231D03*
X1153467Y586462D03*
X1153490Y610322D03*
X1165931Y1397126D03*
X1154714Y1398295D03*
X1157786Y1398252D03*
X1167172Y1420615D03*
X1153913Y1420606D03*
Y1415406D03*
Y1418006D03*
X1159124D03*
Y1420606D03*
Y1415406D03*
X1161724D03*
Y1420606D03*
Y1418006D03*
X1156524Y1415406D03*
Y1420606D03*
Y1418006D03*
X1167172Y1423722D03*
X1153913Y1423206D03*
X1159124D03*
X1161724D03*
X1156524D03*
X1155964Y1440864D03*
X1164260Y1450423D03*
X1158954Y1450274D03*
X1168192Y1604130D03*
X1152950Y1616470D03*
X1165950Y1617729D03*
X1152930Y1633880D03*
X1174980Y585632D03*
X1174880Y592652D03*
X1173990Y602192D03*
X1183230Y739102D03*
X1184661Y1397126D03*
X1183716Y1420631D03*
X1180772Y1420615D03*
X1174972D03*
X1177572D03*
X1172372D03*
X1169772D03*
X1183716Y1423738D03*
X1174972Y1423722D03*
X1172372D03*
X1169772D03*
X1174085Y1436061D03*
Y1430461D03*
X1171655Y1436061D03*
X1169185D03*
X1171655Y1430461D03*
X1169185D03*
X1183685Y1426861D03*
X1175172Y1426829D03*
X1172572D03*
X1174147Y1447858D03*
X1179922Y1550285D03*
X1184501Y1606521D03*
X1185030Y1633010D03*
X1182470Y1618914D03*
X1172530Y1623020D03*
X1176900Y1627510D03*
X1198609Y49388D03*
X1188720Y56755D03*
X1191700Y56822D03*
X1185500Y101400D03*
X1190700Y99000D03*
X1197627Y132859D03*
X1196100Y188962D03*
X1193500D03*
X1192600Y217662D03*
X1193000Y204486D03*
X1195500D03*
X1195100Y217662D03*
X1194840Y240672D03*
X1199027Y588714D03*
X1189135Y1397529D03*
X1187736Y1420387D03*
X1188986Y1415287D03*
Y1417887D03*
X1186386Y1415287D03*
Y1417887D03*
X1191486Y1415287D03*
Y1417887D03*
X1190444Y1420384D03*
X1194750Y1424672D03*
X1197700Y1432672D03*
X1191930Y1424647D03*
X1198010Y1441902D03*
X1198880Y1457162D03*
X1197181Y1563587D03*
X1195994Y1580678D03*
Y1575686D03*
X1200950Y1580678D03*
Y1575686D03*
X1201294Y1599884D03*
X1195994Y1592590D03*
Y1587598D03*
X1200950Y1592590D03*
Y1587598D03*
X1201294Y1604876D03*
Y1611796D03*
Y1616788D03*
X1213026Y56742D03*
X1201800Y94600D03*
X1204800Y108900D03*
X1206900Y115900D03*
X1214573Y148909D03*
X1204420Y195362D03*
X1210084Y224362D03*
X1207220Y247148D03*
X1217720Y249862D03*
X1204880Y754032D03*
X1213010Y1575686D03*
X1208054D03*
X1213010Y1580678D03*
X1208054D03*
X1206250Y1599884D03*
X1213354D03*
X1213010Y1587598D03*
X1208054D03*
X1213010Y1592590D03*
X1208054D03*
X1206250Y1604876D03*
Y1611796D03*
Y1616788D03*
X1213354D03*
Y1604876D03*
Y1611796D03*
X1213980Y1676500D03*
X1218609Y49388D03*
X1228420Y58862D03*
X1230250Y89450D03*
X1223720Y217862D03*
Y205862D03*
X1232000Y244332D03*
Y248332D03*
X1225070Y1580678D03*
Y1575686D03*
X1220114D03*
Y1580678D03*
X1232174D03*
Y1575686D03*
X1218310Y1599884D03*
X1225414D03*
X1230370D03*
X1225070Y1592590D03*
X1220114D03*
X1225070Y1587598D03*
X1220114D03*
X1232174D03*
Y1592590D03*
X1218310Y1616788D03*
Y1604876D03*
Y1611796D03*
X1225414D03*
Y1604876D03*
X1230370Y1611796D03*
Y1604876D03*
X1225414Y1616788D03*
X1230370D03*
X1238609Y49388D03*
X1239907Y95008D03*
X1243808Y116832D03*
X1247333Y121999D03*
X1236520Y213462D03*
X1246444Y256098D03*
X1252040Y306480D03*
X1237130Y1575686D03*
Y1580678D03*
X1244234D03*
X1249190D03*
X1244234Y1575686D03*
X1249190D03*
X1242430Y1599884D03*
X1237474D03*
X1249534D03*
X1237130Y1587598D03*
Y1592590D03*
X1249190D03*
X1244234D03*
Y1587598D03*
X1249190D03*
X1242430Y1616788D03*
X1237474D03*
X1242430Y1611796D03*
Y1604876D03*
X1237474Y1611796D03*
Y1604876D03*
X1249534Y1611796D03*
Y1604876D03*
Y1616788D03*
X1258609Y49388D03*
X1262800Y101100D03*
X1264620Y92724D03*
X1252961Y111903D03*
X1267150Y305998D03*
X1256787Y749605D03*
X1261250Y1575686D03*
X1256294D03*
X1261250Y1580678D03*
X1256294D03*
X1254490Y1599884D03*
X1261594D03*
X1261250Y1587598D03*
X1256294D03*
X1261250Y1592590D03*
X1256294D03*
X1254490Y1611796D03*
Y1604876D03*
Y1616788D03*
X1261594D03*
Y1611796D03*
Y1604876D03*
X1278300Y81232D03*
X1280135Y1340002D03*
Y1337402D03*
Y1345202D03*
Y1342602D03*
X1280312Y1365689D03*
X1273310Y1580678D03*
Y1575592D03*
X1268354D03*
Y1580678D03*
X1280414Y1575686D03*
Y1580678D03*
X1266550Y1599884D03*
X1273654Y1599790D03*
X1278610D03*
X1273310Y1592590D03*
X1268354D03*
X1273310Y1587598D03*
X1268354D03*
X1280414D03*
Y1592590D03*
X1266550Y1616788D03*
Y1611796D03*
Y1604876D03*
X1273654Y1611796D03*
Y1604876D03*
X1278610Y1611796D03*
Y1604876D03*
X1273654Y1616788D03*
X1278610D03*
X1295278Y297056D03*
X1290322D03*
X1294937Y746965D03*
X1292904Y782048D03*
X1292614Y789910D03*
X1291205Y1345875D03*
X1286005Y1342768D03*
Y1345875D03*
X1296405Y1342768D03*
X1293805D03*
X1288605D03*
X1291205D03*
X1288605Y1345875D03*
X1293805D03*
X1291405Y1348982D03*
X1294005D03*
X1292916Y1352531D03*
X1290436D03*
X1287956D03*
X1292916Y1358131D03*
X1290436D03*
X1287956D03*
X1283280Y1372301D03*
X1293887Y1370043D03*
X1294477Y1372651D03*
X1285370Y1575686D03*
Y1580678D03*
X1297430D03*
X1292474D03*
Y1575686D03*
X1297430D03*
X1285714Y1599884D03*
X1290670D03*
X1297774D03*
X1285370Y1587598D03*
Y1592590D03*
X1297430D03*
X1292474D03*
X1297430Y1587598D03*
X1292474D03*
X1290670Y1616788D03*
X1285714D03*
Y1611796D03*
X1290670D03*
X1285714Y1604876D03*
X1290670D03*
X1297774Y1611796D03*
Y1604876D03*
Y1616788D03*
X1311960Y49672D03*
X1314450Y319841D03*
X1312845Y324764D03*
X1305909D03*
X1303017Y785837D03*
X1311952Y1321945D03*
X1307656Y1337104D03*
X1305056D03*
X1307656Y1334504D03*
Y1329304D03*
Y1331904D03*
X1305056Y1334504D03*
Y1329304D03*
Y1331904D03*
Y1339704D03*
X1312488Y1348353D03*
X1299605Y1342768D03*
X1302549Y1345891D03*
X1302520Y1348762D03*
X1315058Y1349488D03*
X1302549Y1342784D03*
X1309490Y1575686D03*
X1304534D03*
X1309490Y1580678D03*
X1304534D03*
X1302730Y1599884D03*
X1309834D03*
X1314790D03*
X1309490Y1587598D03*
X1304534D03*
X1309490Y1592590D03*
X1304534D03*
X1302730Y1611796D03*
Y1604876D03*
Y1616788D03*
X1309834D03*
Y1611796D03*
Y1604876D03*
X1314790Y1616788D03*
Y1611796D03*
Y1604876D03*
X1318609Y49388D03*
X1319125Y296540D03*
X1324081D03*
X1324636Y290920D03*
X1329592D03*
X1330248Y325670D03*
X1323312D03*
X1321386Y319841D03*
X1329977Y334384D03*
X1327601Y540049D03*
X1317970Y1322741D03*
Y1319634D03*
X1325770Y1322741D03*
X1323170D03*
X1331570Y1319634D03*
X1323170D03*
X1325770D03*
X1328370D03*
X1320570Y1322741D03*
Y1319634D03*
X1322444Y1329497D03*
X1324924D03*
X1319964D03*
X1322444Y1335097D03*
X1324924D03*
X1319964D03*
X1323370Y1325848D03*
X1325970D03*
X1324945Y1346877D03*
X1327196Y1349068D03*
X1321550Y1580678D03*
X1316594D03*
X1321550Y1575686D03*
X1316594D03*
X1328654D03*
Y1580678D03*
X1321894Y1599884D03*
X1326850D03*
X1321550Y1592590D03*
X1316594D03*
X1321550Y1587598D03*
X1316594D03*
X1328654D03*
Y1592590D03*
X1321894Y1611796D03*
Y1604876D03*
X1326850Y1611796D03*
Y1604876D03*
X1321894Y1616788D03*
X1326850D03*
X1332726Y-27681D03*
X1339019Y-26472D03*
X1332726Y-32055D03*
X1339019Y-37001D03*
X1332726Y-11497D03*
X1339019Y-16443D03*
X1332741Y-15137D03*
X1332726Y-17652D03*
Y-21526D03*
X1332741Y-25166D03*
X1332726Y2406D03*
X1332741Y4921D03*
X1339019Y3615D03*
X1332726Y-1468D03*
X1339019Y-6414D03*
X1332726Y-7623D03*
X1332741Y-5108D03*
X1332726Y18590D03*
Y22464D03*
X1339019Y13644D03*
X1332726Y12435D03*
X1332741Y14950D03*
X1332726Y8561D03*
X1332741Y24979D03*
X1339019Y23673D03*
X1338609Y49388D03*
X1346720Y82912D03*
X1343362Y283155D03*
X1335947Y290755D03*
X1340903D03*
X1343656Y330749D03*
X1343199Y324461D03*
X1336263D03*
X1336913Y334384D03*
X1335643Y540048D03*
X1336187Y755635D03*
X1339784Y1306506D03*
X1337184D03*
X1344080Y1305919D03*
X1343968Y1300579D03*
X1344080Y1308519D03*
X1334514Y1322757D03*
Y1319650D03*
X1337184Y1309106D03*
X1339784D03*
X1338534Y1319406D03*
X1339784Y1316906D03*
Y1314306D03*
Y1311706D03*
X1337184Y1314306D03*
Y1316906D03*
Y1311706D03*
X1334414Y1325853D03*
X1347015Y1335876D03*
X1343631Y1332568D03*
X1333610Y1575686D03*
Y1580678D03*
X1345670D03*
X1340714D03*
X1345670Y1575686D03*
X1340714D03*
X1338910Y1599884D03*
X1333954D03*
X1346014D03*
X1333610Y1587598D03*
Y1592590D03*
X1345670D03*
X1340714D03*
X1345670Y1587598D03*
X1340714D03*
X1338910Y1616788D03*
Y1611796D03*
Y1604876D03*
X1333954Y1616788D03*
Y1611796D03*
Y1604876D03*
X1346014Y1611796D03*
Y1604876D03*
Y1616788D03*
X1350550Y101632D03*
X1363846Y279848D03*
X1349362Y283155D03*
X1353902Y287540D03*
X1359902D03*
X1350592Y330749D03*
X1356968Y339611D03*
X1350032D03*
X1363539Y334043D03*
X1356603D03*
X1350098Y1306208D03*
X1352698D03*
X1355298D03*
X1360498D03*
X1363698D03*
X1357898D03*
X1352698Y1309315D03*
X1350098D03*
X1355498Y1312422D03*
X1358098D03*
X1355298Y1309315D03*
X1357898D03*
X1352092Y1316071D03*
Y1321671D03*
X1357052Y1316071D03*
X1354572D03*
X1357052Y1321671D03*
X1354572D03*
X1356983Y1334095D03*
X1359516Y1334058D03*
X1355357Y1396020D03*
X1357730Y1575686D03*
X1352774D03*
X1357730Y1580678D03*
X1352774D03*
X1350970Y1599884D03*
X1363030D03*
X1358074D03*
X1357730Y1587598D03*
X1352774D03*
X1357730Y1592590D03*
X1352774D03*
X1350970Y1611796D03*
Y1604876D03*
Y1616788D03*
X1363030D03*
Y1611796D03*
Y1604876D03*
X1358074Y1616788D03*
Y1611796D03*
Y1604876D03*
X1378550Y110692D03*
X1377742Y244372D03*
Y250372D03*
X1377626Y258914D03*
Y264914D03*
X1369846Y279848D03*
X1372381Y661428D03*
X1371931Y672978D03*
Y685278D03*
X1372243Y697108D03*
Y709108D03*
Y721108D03*
X1370662Y1305980D03*
X1371912Y1303480D03*
X1376208Y1305919D03*
Y1303319D03*
X1371912Y1300880D03*
X1376208Y1300719D03*
Y1295586D03*
X1371912Y1295747D03*
Y1298280D03*
X1376208Y1298119D03*
X1369312Y1303480D03*
X1366642Y1306224D03*
X1369312Y1300880D03*
Y1295747D03*
Y1298280D03*
X1376208Y1308519D03*
X1366542Y1312427D03*
X1366642Y1309331D03*
X1379271Y1335963D03*
X1375814Y1332653D03*
X1377060Y1411231D03*
X1371960Y1436172D03*
X1365040Y1431142D03*
X1369790Y1580678D03*
X1364834D03*
X1369790Y1575592D03*
X1364834D03*
X1376894Y1575686D03*
Y1580678D03*
X1375090Y1599790D03*
X1370134D03*
X1369790Y1592590D03*
X1364834D03*
X1369790Y1587598D03*
X1364834D03*
X1376894D03*
Y1592590D03*
X1375090Y1611796D03*
Y1604876D03*
Y1616788D03*
X1370134Y1611796D03*
Y1604876D03*
Y1616788D03*
X1383480Y88932D03*
X1383734Y243329D03*
Y237329D03*
X1388778Y250661D03*
X1388908Y260301D03*
X1386237Y265620D03*
Y275200D03*
X1385190Y501242D03*
X1390220Y497742D03*
X1381131Y656378D03*
Y668378D03*
X1395831Y666278D03*
X1386931Y660978D03*
X1381131Y680278D03*
X1396031Y680678D03*
X1386931Y675478D03*
X1387143Y690208D03*
X1380731Y692208D03*
X1395631Y695108D03*
X1380731Y704208D03*
X1387143Y704708D03*
X1380731Y716208D03*
X1395631Y709608D03*
X1387143Y719235D03*
X1395631Y724135D03*
X1382920Y733725D03*
X1391408Y738625D03*
X1382226Y1306208D03*
X1384826D03*
X1387426D03*
X1390026D03*
X1392626D03*
X1395826D03*
X1386700Y1321671D03*
X1389180D03*
X1382226Y1309315D03*
X1384826D03*
X1390226Y1312422D03*
X1387626D03*
X1390026Y1309315D03*
X1387426D03*
X1384220Y1316071D03*
Y1321671D03*
X1389180Y1316071D03*
X1386700D03*
X1390758Y1333473D03*
X1392076Y1335658D03*
X1388813Y1393160D03*
X1396115Y1405289D03*
Y1412789D03*
X1396615Y1420289D03*
X1384695Y1425047D03*
X1392475Y1576097D03*
X1381850Y1575686D03*
Y1580678D03*
X1396600Y1582500D03*
X1387150Y1599884D03*
X1382194D03*
X1381850Y1587598D03*
Y1592590D03*
X1396600Y1594000D03*
X1387150Y1616788D03*
X1382194D03*
X1387150Y1611796D03*
Y1604876D03*
X1382194Y1611796D03*
Y1604876D03*
X1404630Y220018D03*
X1412270Y230952D03*
X1405436Y238378D03*
X1400207Y238257D03*
X1398770Y1306224D03*
X1404040Y1303480D03*
X1408336Y1305919D03*
Y1303319D03*
X1404040Y1300880D03*
X1408336Y1300719D03*
Y1295586D03*
X1404040Y1295747D03*
Y1298280D03*
X1408336Y1298119D03*
X1401440Y1303480D03*
X1402790Y1305980D03*
X1401440Y1300880D03*
Y1295747D03*
Y1298280D03*
X1408336Y1308519D03*
X1398670Y1312427D03*
X1398770Y1309331D03*
X1411124Y1335924D03*
X1407719Y1332560D03*
X1403615Y1405289D03*
X1411115D03*
Y1412789D03*
X1403615Y1420289D03*
X1411115D03*
X1403350Y1516435D03*
X1403590Y1532255D03*
X1403350Y1521335D03*
X1403740Y1548375D03*
X1403590Y1537155D03*
X1403740Y1543475D03*
X1407200Y1591400D03*
X1411070Y1603282D03*
X1400000Y1630362D03*
Y1642362D03*
X1413350Y220018D03*
X1416020D03*
X1424690D03*
X1424520Y225002D03*
X1416810Y225422D03*
X1428640Y230022D03*
X1431430Y251265D03*
X1428940Y269292D03*
X1414354Y1306208D03*
X1416954D03*
X1419554D03*
X1422154D03*
X1424754D03*
X1427954D03*
X1418828Y1316071D03*
X1416348D03*
X1418828Y1321671D03*
X1416348D03*
X1421308Y1316071D03*
Y1321671D03*
X1414354Y1309315D03*
X1416954D03*
X1419554D03*
X1422354Y1312422D03*
X1419754D03*
X1422154Y1309315D03*
X1421294Y1334095D03*
X1423656Y1335468D03*
X1429345Y1433695D03*
X1427349Y1442776D03*
X1414264Y1439494D03*
X1419256Y1440258D03*
X1423829Y1442776D03*
X1416800Y1564862D03*
X1428403Y1581378D03*
X1418241Y1583441D03*
X1422145Y1575362D03*
X1426680Y1603262D03*
X1425770Y1633772D03*
X1413230Y1641042D03*
X1438609Y49388D03*
X1441125Y57362D03*
X1438680Y64412D03*
X1441490Y224062D03*
X1438720Y220018D03*
X1430130Y259342D03*
X1437177Y720965D03*
X1437182Y1298991D03*
X1430898Y1306224D03*
X1434582Y1304191D03*
Y1306791D03*
Y1301591D03*
Y1296458D03*
Y1298991D03*
X1440507Y1305430D03*
Y1302830D03*
Y1300230D03*
X1440536Y1296455D03*
X1440464Y1308519D03*
X1437182Y1304191D03*
Y1306791D03*
Y1301591D03*
Y1296458D03*
X1430798Y1312427D03*
X1430898Y1309331D03*
X1443785Y1335981D03*
X1440879Y1333085D03*
X1439155Y1399064D03*
X1431717Y1420625D03*
Y1417125D03*
Y1409125D03*
Y1427632D03*
X1436330Y1521152D03*
X1436570Y1536972D03*
X1436720Y1548192D03*
X1437140Y1576012D03*
X1438300Y1598400D03*
X1430250Y1608442D03*
X1438300Y1611000D03*
X1438273Y1671103D03*
X1458609Y49388D03*
X1458720Y153362D03*
Y149362D03*
Y169862D03*
Y165862D03*
Y161862D03*
Y157862D03*
Y181862D03*
Y177862D03*
Y173862D03*
X1446830Y236232D03*
X1453670Y278170D03*
X1459312Y341130D03*
X1460600Y352742D03*
X1456700Y369642D03*
X1454889Y658712D03*
X1454439Y670262D03*
Y682562D03*
X1454751Y694392D03*
Y706392D03*
X1454439Y718362D03*
X1459057Y733545D03*
X1457597Y739035D03*
X1446482Y1306208D03*
X1449082D03*
X1451682D03*
X1456882D03*
X1460082D03*
X1454282D03*
X1450956Y1321671D03*
X1448476D03*
X1453436Y1316071D03*
Y1321671D03*
X1446482Y1309315D03*
X1451882Y1312422D03*
X1449082Y1309315D03*
X1451682D03*
X1454482Y1312422D03*
X1454282Y1309315D03*
X1450956Y1316071D03*
X1448476D03*
X1453303Y1334095D03*
X1455436Y1335598D03*
X1461377Y1417844D03*
X1459135Y1439627D03*
X1459136Y1442241D03*
X1461517Y1575686D03*
Y1580678D03*
X1446600Y1595400D03*
X1461517Y1587598D03*
Y1592590D03*
X1460441Y1602441D03*
X1446786Y1610639D03*
X1452757Y1671399D03*
X1446380Y1676291D03*
X1464200Y67802D03*
X1470220Y145362D03*
X1470101Y207751D03*
X1476858Y225448D03*
X1466940Y230272D03*
X1466958Y244948D03*
X1468620Y258857D03*
X1467230Y252472D03*
X1466660Y273878D03*
X1475790Y404842D03*
X1473310Y418502D03*
X1463639Y653662D03*
X1469651Y655992D03*
X1462010Y645842D03*
X1463639Y665662D03*
X1478139Y660892D03*
X1469439Y670262D03*
X1463639Y677562D03*
X1463239Y689492D03*
X1478139Y689892D03*
X1469651Y684992D03*
X1463239Y701492D03*
X1478139Y704392D03*
X1469477Y699475D03*
X1463239Y713492D03*
X1478139Y718892D03*
X1469651Y713992D03*
X1474100Y735662D03*
X1466451Y726992D03*
X1474939Y731892D03*
X1472592Y1306345D03*
X1463026Y1306224D03*
X1465696Y1303480D03*
X1467046Y1305980D03*
X1468296Y1303480D03*
X1465696Y1300880D03*
X1468296D03*
X1472361Y1322440D03*
X1472592Y1308945D03*
Y1316745D03*
Y1314145D03*
Y1311545D03*
X1462926Y1312427D03*
X1463026Y1309331D03*
X1475599Y1349468D03*
X1475959Y1385027D03*
X1476000Y1393027D03*
X1465747Y1401405D03*
X1466448Y1421499D03*
X1475935Y1439627D03*
X1475936Y1442241D03*
X1467550Y1439642D03*
X1467536Y1442241D03*
X1473577Y1580678D03*
Y1575686D03*
X1466473D03*
Y1580678D03*
X1471773Y1599884D03*
X1466817D03*
X1473577Y1592590D03*
Y1587598D03*
X1466473D03*
Y1592590D03*
X1466817Y1611796D03*
X1471773D03*
X1466817Y1604876D03*
X1471773D03*
Y1616788D03*
X1466817D03*
X1478609Y49388D03*
X1481360Y358792D03*
X1488500Y410152D03*
X1478539Y675462D03*
X1486410Y1322741D03*
X1483810D03*
X1486410Y1319634D03*
X1483810D03*
X1481210Y1322741D03*
Y1319634D03*
X1492210D03*
X1489010D03*
X1478610Y1322741D03*
Y1319634D03*
X1484010Y1325848D03*
X1486610D03*
X1485564Y1335097D03*
X1483084D03*
X1485564Y1329497D03*
X1483084D03*
X1480604Y1335097D03*
Y1329497D03*
X1485523Y1347521D03*
X1487386Y1349258D03*
X1478559Y1385027D03*
X1481159Y1384727D03*
X1478600Y1393027D03*
X1481107Y1393095D03*
X1484395Y1439598D03*
X1484336Y1442241D03*
X1490593Y1580678D03*
Y1575686D03*
X1485637D03*
Y1580678D03*
X1478533D03*
Y1575686D03*
X1490937Y1599884D03*
X1478877D03*
X1483833D03*
X1490593Y1587598D03*
X1485637D03*
Y1592590D03*
X1490593D03*
X1478533D03*
Y1587598D03*
X1490937Y1604876D03*
Y1611796D03*
Y1616788D03*
X1483833D03*
X1478877D03*
Y1611796D03*
X1483833D03*
X1478877Y1604876D03*
X1483833D03*
X1498609Y49388D03*
X1496200Y359522D03*
X1497880Y373062D03*
X1503450Y382693D03*
X1497770Y732502D03*
X1495154Y1322757D03*
Y1319650D03*
X1499048Y1319946D03*
X1504720Y1329143D03*
X1495054Y1325853D03*
X1503786Y1326076D03*
X1504518Y1335982D03*
X1504720Y1342143D03*
Y1344743D03*
X1505116Y1369724D03*
X1509757Y1575686D03*
Y1580678D03*
X1502653D03*
X1497697D03*
X1502653Y1575686D03*
X1497697D03*
X1502997Y1599884D03*
X1507953D03*
X1495893D03*
X1509757Y1587598D03*
Y1592590D03*
X1502653D03*
X1497697D03*
X1502653Y1587598D03*
X1497697D03*
X1502997Y1616788D03*
X1507953D03*
X1502997Y1604876D03*
Y1611796D03*
X1507953Y1604876D03*
Y1611796D03*
X1495893Y1604876D03*
Y1611796D03*
Y1616788D03*
X1518608Y49377D03*
X1522920Y113030D03*
X1526675Y140117D03*
X1526083Y146225D03*
X1513759Y263676D03*
X1516683Y278437D03*
X1511624Y291175D03*
X1519336Y303426D03*
X1520094Y306543D03*
X1514369Y308467D03*
X1524505Y748912D03*
X1522066Y1312808D03*
X1526066D03*
X1518066D03*
X1515066D03*
X1511066D03*
X1510738Y1345539D03*
Y1342432D03*
X1518538Y1345539D03*
Y1342432D03*
X1515938Y1345539D03*
Y1342432D03*
X1513338Y1345539D03*
Y1342432D03*
X1521138D03*
X1524338D03*
X1518738Y1348646D03*
X1516138D03*
X1515212Y1352295D03*
X1512732D03*
X1517692D03*
X1515212Y1357895D03*
X1512732D03*
X1517692D03*
X1518451Y1369919D03*
X1521817Y1580678D03*
Y1575686D03*
X1514713D03*
Y1580678D03*
X1520013Y1599884D03*
X1515057D03*
X1521817Y1592590D03*
Y1587598D03*
X1514713D03*
Y1592590D03*
X1520013Y1604876D03*
X1515057D03*
X1520013Y1611796D03*
X1515057D03*
Y1616788D03*
X1520013D03*
X1534818Y66801D03*
Y71793D03*
X1539774Y66801D03*
Y71793D03*
X1541774Y69297D03*
X1532818D03*
X1534774Y103093D03*
X1529818D03*
X1535320Y113062D03*
X1529500Y129602D03*
X1545447Y156035D03*
X1537262Y197834D03*
X1540989Y616587D03*
X1535052Y1325904D03*
X1532552Y1334504D03*
X1535052D03*
X1529952D03*
X1532552Y1339704D03*
X1529952D03*
X1537652Y1325904D03*
Y1334504D03*
X1532552Y1337104D03*
X1529952D03*
X1538510Y1346392D03*
X1531302Y1342204D03*
X1535892Y1346354D03*
Y1343754D03*
X1527282Y1345555D03*
Y1342448D03*
X1538757Y1356355D03*
X1527182Y1348651D03*
X1538757Y1360855D03*
Y1365355D03*
X1533877Y1575592D03*
X1538833D03*
X1533877Y1580678D03*
X1538833D03*
X1526773D03*
Y1575686D03*
X1539177Y1599790D03*
X1527117Y1599884D03*
X1532073D03*
X1533877Y1587598D03*
X1538833D03*
X1533877Y1592590D03*
X1538833D03*
X1526773D03*
Y1587598D03*
X1539177Y1611796D03*
Y1604876D03*
Y1616788D03*
X1527117D03*
Y1604876D03*
Y1611796D03*
X1532073Y1616788D03*
Y1604876D03*
Y1611796D03*
X1547768Y3010D03*
X1555635Y16999D03*
Y21991D03*
X1553635Y19495D03*
X1553486Y23935D03*
X1548530D03*
X1546530Y25931D03*
X1555486D03*
X1547429Y37106D03*
X1554515D03*
Y48720D03*
X1547429D03*
X1554818Y69297D03*
X1556818Y66801D03*
Y71793D03*
X1543818Y75297D03*
X1552774D03*
X1550774Y77793D03*
Y72801D03*
X1545818Y77793D03*
Y72801D03*
X1554239Y138263D03*
X1554723Y200375D03*
X1557560Y196912D03*
X1554723Y224529D03*
Y248945D03*
X1554727Y631527D03*
X1550417Y677045D03*
X1550057Y693485D03*
X1548479Y706088D03*
X1557997Y1575686D03*
Y1580678D03*
X1550893D03*
X1545937D03*
X1550893Y1575686D03*
X1545937D03*
X1556193Y1599884D03*
X1551237D03*
X1544133Y1599790D03*
X1557997Y1587598D03*
Y1592590D03*
X1545937D03*
X1550893D03*
Y1587598D03*
X1545937D03*
X1551237Y1616788D03*
X1556193D03*
Y1604876D03*
X1551237D03*
X1556193Y1611796D03*
X1551237D03*
X1544133Y1604876D03*
Y1611796D03*
Y1616788D03*
X1567768Y3010D03*
X1560591Y16999D03*
Y21991D03*
X1569808Y16999D03*
Y21991D03*
X1574764Y16999D03*
Y21991D03*
X1562591Y19495D03*
X1567808D03*
X1567659Y23935D03*
X1562703D03*
X1560703Y25931D03*
X1569659D03*
X1574876D03*
X1561602Y37106D03*
X1568688D03*
Y48720D03*
X1561602D03*
X1563774Y69297D03*
X1561774Y66801D03*
Y71793D03*
X1565818Y75297D03*
X1574774D03*
X1572774Y77793D03*
Y72801D03*
X1567818Y77793D03*
Y72801D03*
X1559860Y240002D03*
X1575169Y303929D03*
X1560717Y648522D03*
X1570720Y729362D03*
X1570057Y1580678D03*
X1575013D03*
X1570057Y1575686D03*
X1575013D03*
X1562953D03*
Y1580678D03*
X1575357Y1599884D03*
X1563297D03*
X1568253D03*
X1570057Y1592590D03*
X1575013D03*
X1570057Y1587598D03*
X1575013D03*
X1562953D03*
Y1592590D03*
X1575357Y1616788D03*
Y1604876D03*
Y1611796D03*
X1563297Y1604876D03*
Y1611796D03*
X1568253Y1604876D03*
Y1611796D03*
X1563297Y1616788D03*
X1568253D03*
X1587768Y3010D03*
X1583981Y16999D03*
Y21991D03*
X1588937Y16999D03*
Y21991D03*
X1576764Y19495D03*
X1581981D03*
X1590937D03*
X1576876Y23935D03*
X1581832D03*
X1591050D03*
X1583832Y25931D03*
X1589050D03*
X1575775Y37106D03*
X1582862D03*
X1589948D03*
Y48720D03*
X1582862D03*
X1575775D03*
X1576818Y69297D03*
X1585774D03*
X1578818Y66801D03*
Y71793D03*
X1583774Y66801D03*
Y71793D03*
X1587818Y75297D03*
X1589818Y77793D03*
Y72801D03*
X1582117Y1575686D03*
X1587073D03*
X1582117Y1580678D03*
X1587073D03*
X1587417Y1599884D03*
X1580313D03*
X1582117Y1587598D03*
X1587073D03*
X1582117Y1592590D03*
X1587073D03*
X1587417Y1604876D03*
Y1611796D03*
Y1616788D03*
X1580313D03*
Y1604876D03*
Y1611796D03*
X1607768Y3010D03*
X1598155Y16999D03*
Y21991D03*
X1603111Y16999D03*
Y21991D03*
X1596155Y19495D03*
X1605111D03*
X1596006Y23935D03*
X1598006Y25931D03*
X1597035Y37106D03*
X1604122D03*
Y48720D03*
X1597035D03*
X1598818Y69297D03*
X1607774D03*
X1600818Y66801D03*
Y71793D03*
X1605774Y66801D03*
Y71793D03*
X1596774Y75297D03*
X1594774Y77793D03*
Y72801D03*
X1603778Y189943D03*
X1603726Y198061D03*
X1596444Y215526D03*
X1598030Y251002D03*
X1606980Y1449922D03*
X1606237Y1575686D03*
Y1580678D03*
X1594177D03*
X1599133D03*
X1594177Y1575686D03*
X1599133D03*
X1599477Y1599884D03*
X1604433D03*
X1592373D03*
X1606237Y1587598D03*
Y1592590D03*
X1594177D03*
X1599133D03*
X1594177Y1587598D03*
X1599133D03*
X1599477Y1616788D03*
X1604433D03*
X1599477Y1604876D03*
Y1611796D03*
X1604433Y1604876D03*
Y1611796D03*
X1592373Y1604876D03*
Y1611796D03*
Y1616788D03*
X1620818Y69297D03*
X1622818Y66801D03*
Y71793D03*
X1609818Y75297D03*
X1618774D03*
X1616774Y77793D03*
Y72801D03*
X1611818Y77793D03*
Y72801D03*
X1623448Y1420028D03*
Y1417428D03*
Y1414828D03*
Y1412228D03*
X1612630Y1418842D03*
X1615597Y1433669D03*
X1618297Y1580678D03*
X1623253D03*
X1618297Y1575686D03*
X1623253D03*
X1611193D03*
Y1580678D03*
X1623597Y1599884D03*
X1611537D03*
X1616493D03*
X1618297Y1592590D03*
X1623253D03*
X1618297Y1587598D03*
X1623253D03*
X1611193D03*
Y1592590D03*
X1623597Y1616788D03*
Y1604876D03*
Y1611796D03*
X1611537Y1604876D03*
Y1611796D03*
X1616493Y1604876D03*
Y1611796D03*
X1611537Y1616788D03*
X1616493D03*
X1634021Y16999D03*
Y21991D03*
X1638977Y16999D03*
Y21991D03*
X1632021Y19495D03*
X1631872Y23935D03*
X1626916D03*
X1624916Y25931D03*
X1633872D03*
X1639089D03*
X1625814Y37106D03*
X1632901D03*
X1639988D03*
X1625814Y48720D03*
X1632901D03*
X1639988D03*
X1629774Y69297D03*
X1627774Y66801D03*
Y71793D03*
X1633022Y75297D03*
X1635022Y77793D03*
X1639978D03*
Y72801D03*
X1635022D03*
X1635032Y196188D03*
X1642135Y414202D03*
X1629262Y1394418D03*
X1625948Y1417428D03*
Y1412228D03*
X1633103Y1417907D03*
X1630503D03*
X1635703D03*
X1633103Y1421014D03*
X1630503D03*
X1635703D03*
X1638303Y1417907D03*
Y1421014D03*
X1625948Y1414828D03*
Y1420028D03*
X1635903Y1424121D03*
X1638503D03*
X1632516Y1427753D03*
Y1433353D03*
X1634986Y1427753D03*
Y1433353D03*
X1637416Y1427753D03*
Y1433353D03*
X1627591Y1447796D03*
X1637478Y1445150D03*
X1630357Y1575592D03*
X1635313D03*
X1630357Y1580678D03*
X1635313D03*
X1640613Y1599790D03*
X1635657D03*
X1628553Y1599884D03*
X1630357Y1587598D03*
X1635313D03*
X1630357Y1592590D03*
X1635313D03*
X1640613Y1604876D03*
Y1611796D03*
X1635657Y1604876D03*
Y1611796D03*
X1640613Y1616788D03*
X1635657D03*
X1628553D03*
Y1604876D03*
Y1611796D03*
X1648194Y16999D03*
Y21991D03*
X1653150Y16999D03*
Y21991D03*
X1640977Y19495D03*
X1646194D03*
X1655150D03*
X1641089Y23935D03*
X1646045D03*
X1648045Y25931D03*
X1654161Y37106D03*
X1647074D03*
Y48720D03*
X1654161D03*
X1644022Y69297D03*
X1652978D03*
X1646022Y66801D03*
Y71793D03*
X1650978Y66801D03*
Y71793D03*
X1655022Y75297D03*
X1641978D03*
X1657022Y77793D03*
Y72801D03*
X1652610Y394727D03*
X1652810Y407402D03*
X1647110Y434177D03*
X1651890Y520540D03*
X1649220Y620662D03*
X1656188Y1394736D03*
X1647592Y1394418D03*
X1655779Y1417618D03*
Y1412418D03*
Y1415018D03*
X1644103Y1417907D03*
X1647047Y1417923D03*
Y1421030D03*
X1653279Y1412418D03*
X1650679D03*
X1653279Y1415018D03*
X1650679D03*
X1653168Y1417618D03*
X1650557D03*
X1640903Y1417907D03*
X1647016Y1424153D03*
X1648947Y1476695D03*
X1647373Y1580678D03*
X1642417D03*
X1647373Y1575686D03*
X1642417D03*
X1647717Y1599884D03*
X1652673D03*
X1647373Y1592590D03*
X1642417D03*
X1647373Y1587598D03*
X1642417D03*
X1647717Y1616788D03*
X1652673D03*
X1647717Y1604876D03*
Y1611796D03*
X1652673Y1604876D03*
Y1611796D03*
X1671050Y23935D03*
X1669050Y25931D03*
X1669948Y37106D03*
Y48720D03*
X1666022Y69297D03*
X1668022Y66801D03*
Y71793D03*
X1672978Y66801D03*
Y71793D03*
X1663978Y75297D03*
X1661978Y77793D03*
Y72801D03*
X1668030Y200580D03*
X1666074Y229710D03*
X1660176Y231100D03*
X1670400Y229462D03*
X1659610Y394727D03*
X1663610D03*
X1661110Y434177D03*
X1660866Y546749D03*
X1664040Y569642D03*
X1668040D03*
X1672040D03*
X1662120Y604782D03*
X1657220Y620662D03*
X1667405Y1394418D03*
X1659260Y1394693D03*
X1658390Y1420218D03*
Y1415018D03*
Y1412418D03*
Y1417618D03*
X1663590Y1420218D03*
X1660990D03*
Y1415018D03*
Y1417618D03*
Y1412418D03*
X1663590Y1415018D03*
Y1417618D03*
Y1412418D03*
X1668646Y1417907D03*
Y1421014D03*
X1671246Y1417907D03*
Y1421014D03*
X1670659Y1427753D03*
X1673129D03*
X1670659Y1433353D03*
X1673129D03*
X1657438Y1438156D03*
X1660428Y1447566D03*
X1667577Y1447545D03*
X1666123Y1497362D03*
X1665940Y1512862D03*
X1666110Y1504662D03*
X1666123Y1524862D03*
Y1537862D03*
Y1541862D03*
Y1553557D03*
X1666198Y1565557D03*
Y1585321D03*
X1678155Y16999D03*
Y21991D03*
X1683111Y16999D03*
Y21991D03*
X1676155Y19495D03*
X1685111D03*
X1676006Y23935D03*
X1685223D03*
X1678006Y25931D03*
X1683223D03*
X1677035Y37106D03*
X1684122D03*
X1677035Y48720D03*
X1684122D03*
X1688156Y69297D03*
X1674978D03*
X1677156Y75297D03*
X1686112D03*
X1684112Y77793D03*
Y72801D03*
X1679156Y77793D03*
Y72801D03*
X1676300Y219762D03*
X1681900Y227962D03*
X1682810Y465940D03*
X1676040Y569627D03*
X1688301Y722158D03*
X1683121D03*
X1680401D03*
X1686135Y1394418D03*
X1687860Y1415179D03*
X1689210Y1417679D03*
X1687860Y1412579D03*
X1685190Y1417923D03*
X1676446Y1417907D03*
X1679046D03*
X1682246D03*
X1676446Y1421014D03*
X1685190Y1421030D03*
X1673846Y1417907D03*
Y1421014D03*
X1676646Y1424121D03*
X1685159Y1424153D03*
X1675559Y1427753D03*
Y1433353D03*
X1674046Y1424121D03*
X1675621Y1445150D03*
X1679508Y1503421D03*
Y1522921D03*
Y1543921D03*
Y1563380D03*
Y1583880D03*
X1692328Y16999D03*
Y21991D03*
X1697284Y16999D03*
Y21991D03*
X1690328Y19495D03*
X1699284D03*
X1690179Y23935D03*
X1692179Y25931D03*
X1691208Y37106D03*
X1698295D03*
X1705381D03*
X1698295Y48720D03*
X1691208D03*
X1705381D03*
X1697112Y69297D03*
X1690156Y66801D03*
Y71793D03*
X1695112Y66801D03*
Y71793D03*
X1699156Y75297D03*
X1701156Y77793D03*
Y72801D03*
X1695950Y96437D03*
X1697725Y205120D03*
X1700846Y455894D03*
X1702760Y478207D03*
X1696760D03*
X1702760Y490207D03*
X1696760D03*
Y484207D03*
X1696120Y506937D03*
X1703720Y509362D03*
X1696851Y515607D03*
X1693701D03*
X1702270Y552742D03*
X1698920Y698562D03*
X1695227Y722325D03*
X1699307Y722465D03*
X1698137Y718345D03*
X1701087Y719055D03*
X1695367Y719345D03*
X1691021Y722158D03*
X1698537Y766015D03*
X1690809Y1393970D03*
X1699150Y1393613D03*
X1690460Y1415179D03*
Y1412579D03*
X1691918Y1417676D03*
X1692960Y1415179D03*
Y1412579D03*
X1693404Y1421939D03*
X1699593Y1428384D03*
X1697820Y1423616D03*
X1699545Y1425868D03*
X1699437Y1431295D03*
X1699457Y1439185D03*
Y1447805D03*
X1691988Y1498303D03*
Y1517803D03*
Y1538803D03*
Y1558262D03*
X1714520Y37162D03*
X1710920Y82162D03*
X1708112Y75297D03*
X1706112Y77793D03*
Y72801D03*
X1708000Y99122D03*
X1714180Y154790D03*
X1721400Y374462D03*
X1711477Y465229D03*
Y468379D03*
X1708760Y478031D03*
Y490207D03*
Y484207D03*
X1710500Y538162D03*
X1706720Y703762D03*
X1709107Y728449D03*
X1718149Y1496270D03*
X1717149Y1505895D03*
X1720174D03*
X1717988Y1520951D03*
X1711988D03*
X1717149Y1513945D03*
X1720174D03*
X1714988Y1520951D03*
X1708988D03*
X1717988Y1530445D03*
X1714988D03*
X1708988D03*
X1711988D03*
X1727768Y3010D03*
X1732320Y28162D03*
X1728820D03*
X1725320D03*
X1729520Y61762D03*
X1729620Y57262D03*
X1730820Y76362D03*
X1726918Y101967D03*
X1733378Y134907D03*
X1736508D03*
X1723240Y185200D03*
X1737704Y183139D03*
X1737260Y368132D03*
X1732660Y372692D03*
X1725400Y372062D03*
X1725500Y383662D03*
X1737434Y398990D03*
X1727760Y420415D03*
X1747768Y3010D03*
X1754090Y16302D03*
X1748400Y37262D03*
X1753398Y48720D03*
X1745485Y119539D03*
X1747482Y121367D03*
X1741222Y151527D03*
X1747591Y171733D03*
X1751084Y190928D03*
X1745000Y299862D03*
X1746970Y1451872D03*
X1750970Y1459172D03*
Y1456172D03*
X1767768Y3010D03*
X1769900Y37732D03*
X1760485Y48720D03*
X1759700Y57662D03*
X1764400Y57462D03*
X1758063Y68637D03*
X1758573Y87107D03*
Y83607D03*
X1768168Y80497D03*
X1758568Y79697D03*
X1765068Y80397D03*
X1766278Y93627D03*
X1768483Y166260D03*
X1763731Y283817D03*
X1766725Y282981D03*
X1763731Y279517D03*
X1760398Y279548D03*
X1766765Y279433D03*
X1757439Y279611D03*
X1760398Y283848D03*
X1759509Y292434D03*
X1762549Y286704D03*
X1757439Y283911D03*
X1768045Y295238D03*
X1765053Y295188D03*
X1762285Y295137D03*
X1759629Y295164D03*
X1767309Y290994D03*
X1763045Y289691D03*
X1759529Y289864D03*
X1766655Y286531D03*
X1767455Y302651D03*
X1758563Y310478D03*
X1754963D03*
X1770520Y364148D03*
Y368148D03*
X1767300Y461393D03*
X1765670Y458012D03*
X1767300Y465893D03*
X1764112Y703948D03*
X1761612D03*
X1764112Y695648D03*
X1763570Y693192D03*
X1761612Y695648D03*
X1764072Y720508D03*
X1761572D03*
X1764112Y712248D03*
X1761612D03*
X1760160Y1476032D03*
X1763730Y1483712D03*
Y1480712D03*
X1763830Y1490782D03*
Y1487782D03*
X1785178Y86927D03*
Y89927D03*
X1784238Y150744D03*
X1786690Y234782D03*
Y231782D03*
X1771029Y295164D03*
X1771229Y291064D03*
X1772863Y310478D03*
X1782420Y443987D03*
X1773870Y438222D03*
X1776160Y592792D03*
X1787768Y3010D03*
X1794910Y44573D03*
X1797324Y161465D03*
X1803129Y362293D03*
X1802929Y385293D03*
X1795479Y408056D03*
X1795468Y421334D03*
X1800107Y1256426D03*
X1795484Y1496401D03*
X1792645Y1511423D03*
X1798450Y1524830D03*
X1801450D03*
Y1527830D03*
X1814322Y49388D03*
X1807549Y56415D03*
X1807580Y59397D03*
X1810835Y163986D03*
X1806365Y154032D03*
X1819939Y177243D03*
X1820307Y373829D03*
X1820144Y398052D03*
X1819374Y410432D03*
X1818874Y423932D03*
X1818816Y468872D03*
X1803517Y1495567D03*
X1818410Y1525815D03*
X1812250Y1521830D03*
X1811250Y1524830D03*
Y1527830D03*
X1807850D03*
X1804650D03*
Y1524830D03*
X1807850D03*
X1814370Y1528900D03*
X1814210Y1525815D03*
X1818524Y1528991D03*
X1834322Y49388D03*
X1823508Y158868D03*
X1829026Y367701D03*
X1823426Y1507916D03*
X1831994Y1525977D03*
X1835334Y1520921D03*
X1828510Y1525915D03*
X1821710D03*
X1830466Y1606658D03*
X1838910Y185772D03*
X1843134Y244362D03*
X1836750Y373632D03*
X1838020Y459121D03*
X1854096Y52383D03*
G54D43*
X335349Y985939D03*
X549278Y949619D03*
X1300207Y177799D03*
X1311491Y985939D03*
X1355761Y177798D03*
X1525420Y949619D03*
X1879155Y592848D03*
Y840748D03*
X1889155Y592848D03*
Y840748D03*
X1900275Y964708D03*
X1910275D03*
X1931395Y592868D03*
X1921395D03*
X1952395Y1205248D03*
X1942395D03*
X1963362Y593010D03*
X1973362D03*
X1984482Y1205220D03*
X1994482D03*
X2015452Y593020D03*
X2005452D03*
X2026452Y1205400D03*
X2047419Y593162D03*
X2036452Y1205400D03*
X2057419Y593162D03*
X2078539Y1205372D03*
X2068539D03*
G54D57*
X828780Y1694890D03*
Y1684890D03*
X818780Y1694890D03*
Y1684890D03*
X828780Y1704890D03*
X818780D03*
X828780Y1714890D03*
X818780D03*
X853780Y1694890D03*
Y1684890D03*
Y1704890D03*
Y1714890D03*
X863780Y1694890D03*
Y1684890D03*
Y1704890D03*
Y1714890D03*
X888780Y1684890D03*
Y1694890D03*
Y1704890D03*
Y1714890D03*
X898780Y1684890D03*
Y1694890D03*
Y1704890D03*
Y1714890D03*
X918780Y1704890D03*
X958780Y1694890D03*
Y1684890D03*
Y1704890D03*
Y1714890D03*
X968780Y1694890D03*
Y1684890D03*
Y1704890D03*
Y1714890D03*
X993780Y1684890D03*
Y1694890D03*
X1003780Y1684890D03*
Y1694890D03*
X993780Y1704890D03*
Y1714890D03*
X1003780Y1704890D03*
Y1714890D03*
X1028780Y1684890D03*
Y1694890D03*
X1038780Y1684890D03*
Y1694890D03*
X1028780Y1704890D03*
Y1714890D03*
X1038780Y1704890D03*
Y1714890D03*
G54D16*
X27699Y770144D03*
Y783530D03*
Y776837D03*
Y800263D03*
Y793570D03*
Y820341D03*
Y813648D03*
Y806955D03*
Y830381D03*
Y850459D03*
Y843766D03*
Y837074D03*
Y867192D03*
Y857152D03*
Y880577D03*
Y873885D03*
Y893963D03*
Y887270D03*
Y917389D03*
Y910696D03*
Y904003D03*
Y930774D03*
Y924081D03*
Y947507D03*
Y940814D03*
Y964239D03*
Y954200D03*
Y977625D03*
Y970932D03*
Y991011D03*
Y984318D03*
Y1031168D03*
Y1024475D03*
Y1017782D03*
Y1044554D03*
Y1037861D03*
Y1057940D03*
Y1051247D03*
Y1078018D03*
Y1071326D03*
Y1064633D03*
Y1094751D03*
Y1088058D03*
Y1108137D03*
Y1101444D03*
Y1124869D03*
Y1114829D03*
Y1144948D03*
Y1138255D03*
Y1131562D03*
Y1161680D03*
Y1151641D03*
Y1175066D03*
Y1168373D03*
Y1188452D03*
Y1181759D03*
Y1205184D03*
Y1198491D03*
Y1225263D03*
Y1218570D03*
Y1211877D03*
Y1241995D03*
Y1235302D03*
Y1248688D03*
X43841Y766798D03*
X36399Y770144D03*
X43841Y780184D03*
Y773491D03*
X36399Y783530D03*
Y776837D03*
X43841Y803609D03*
Y796916D03*
Y790223D03*
X36399Y800263D03*
Y793570D03*
X43841Y816995D03*
Y810302D03*
X36399Y820341D03*
Y813648D03*
Y806955D03*
X43841Y833727D03*
Y827034D03*
X36399Y830381D03*
X43841Y847113D03*
Y840420D03*
X36399Y850459D03*
Y843766D03*
Y837074D03*
X43841Y863845D03*
Y853806D03*
X36399Y867192D03*
Y857152D03*
X43841Y883924D03*
Y877231D03*
Y870538D03*
X36399Y880577D03*
Y873885D03*
X43841Y900656D03*
Y890617D03*
X36399Y893963D03*
Y887270D03*
X43841Y914042D03*
Y907349D03*
X36399Y917389D03*
Y910696D03*
Y904003D03*
X43841Y927428D03*
Y920735D03*
X36399Y930774D03*
Y924081D03*
X43841Y944160D03*
Y937467D03*
X36399Y947507D03*
Y940814D03*
X43841Y960892D03*
Y950853D03*
X36399Y964239D03*
Y954200D03*
X43841Y980971D03*
Y974278D03*
Y967585D03*
X36399Y977625D03*
Y970932D03*
X43841Y987664D03*
X36399Y991011D03*
Y984318D03*
X43841Y1027822D03*
Y1017782D03*
X36399Y1031168D03*
Y1024475D03*
Y1017782D03*
X43841Y1047900D03*
Y1041207D03*
Y1034515D03*
X36399Y1044554D03*
Y1037861D03*
X43841Y1061286D03*
Y1054593D03*
X36399Y1057940D03*
Y1051247D03*
X43841Y1074672D03*
Y1067979D03*
X36399Y1078018D03*
Y1071326D03*
Y1064633D03*
X43841Y1091404D03*
Y1084711D03*
X36399Y1094751D03*
Y1088058D03*
X43841Y1111483D03*
Y1104790D03*
Y1098097D03*
X36399Y1108137D03*
Y1101444D03*
X43841Y1128215D03*
Y1121522D03*
X36399Y1124869D03*
Y1114829D03*
X43841Y1141601D03*
Y1134908D03*
X36399Y1144948D03*
Y1138255D03*
Y1131562D03*
X43841Y1158333D03*
Y1148294D03*
X36399Y1161680D03*
Y1151641D03*
X43841Y1171719D03*
Y1165026D03*
X36399Y1175066D03*
Y1168373D03*
X43841Y1185105D03*
Y1178412D03*
X36399Y1188452D03*
Y1181759D03*
X43841Y1208530D03*
Y1201837D03*
Y1195144D03*
X36399Y1205184D03*
Y1198491D03*
X43841Y1221916D03*
Y1215223D03*
X36399Y1225263D03*
Y1218570D03*
Y1211877D03*
X43841Y1238648D03*
Y1231955D03*
X36399Y1241995D03*
Y1235302D03*
X43841Y1245341D03*
X36399Y1248688D03*
X36449Y1257262D03*
X33546Y1273364D03*
X30746D03*
X57399Y770144D03*
X52541Y766798D03*
X57399Y783530D03*
Y776837D03*
X52541Y780184D03*
Y773491D03*
X57399Y800263D03*
Y793570D03*
X52541Y803609D03*
Y796916D03*
Y790223D03*
X57399Y820341D03*
Y813648D03*
Y806955D03*
X52541Y816995D03*
Y810302D03*
X57399Y830381D03*
X52541Y833727D03*
Y827034D03*
X57399Y850459D03*
Y843766D03*
Y837074D03*
X52541Y847113D03*
Y840420D03*
X57399Y867192D03*
Y857152D03*
X52541Y863845D03*
Y853806D03*
X57399Y880577D03*
Y873885D03*
X52541Y883924D03*
Y877231D03*
Y870538D03*
X57399Y893963D03*
Y887270D03*
X52541Y900656D03*
Y890617D03*
X57399Y917389D03*
Y910696D03*
Y904003D03*
X52541Y914042D03*
Y907349D03*
X57399Y930774D03*
Y924081D03*
X52541Y927428D03*
Y920735D03*
X57399Y947507D03*
Y940814D03*
X52541Y944160D03*
Y937467D03*
X57399Y964239D03*
Y954200D03*
X52541Y960892D03*
Y950853D03*
X57399Y977625D03*
Y970932D03*
X52541Y980971D03*
Y974278D03*
Y967585D03*
X57399Y991011D03*
Y984318D03*
X52541Y987664D03*
X57399Y1031168D03*
Y1024475D03*
Y1017782D03*
X52541Y1027822D03*
Y1017782D03*
X57399Y1044554D03*
Y1037861D03*
X52541Y1047900D03*
Y1041207D03*
Y1034515D03*
X57399Y1057940D03*
Y1051247D03*
X52541Y1061286D03*
Y1054593D03*
X57399Y1078018D03*
Y1071326D03*
Y1064633D03*
X52541Y1074672D03*
Y1067979D03*
X57399Y1094751D03*
Y1088058D03*
X52541Y1091404D03*
Y1084711D03*
X57399Y1108137D03*
Y1101444D03*
X52541Y1111483D03*
Y1104790D03*
Y1098097D03*
X57399Y1124869D03*
Y1114829D03*
X52541Y1128215D03*
Y1121522D03*
X57399Y1144948D03*
Y1138255D03*
Y1131562D03*
X52541Y1141601D03*
Y1134908D03*
X57399Y1161680D03*
Y1151641D03*
X52541Y1158333D03*
Y1148294D03*
X57399Y1175066D03*
Y1168373D03*
X52541Y1171719D03*
Y1165026D03*
X57399Y1188452D03*
Y1181759D03*
X52541Y1185105D03*
Y1178412D03*
X57399Y1205184D03*
Y1198491D03*
X52541Y1208530D03*
Y1201837D03*
Y1195144D03*
X57399Y1225263D03*
Y1218570D03*
Y1211877D03*
X52541Y1221916D03*
Y1215223D03*
X57399Y1241995D03*
Y1235302D03*
X52541Y1238648D03*
Y1231955D03*
Y1248688D03*
X57399D03*
X52541Y1245341D03*
X60446Y1273364D03*
X49546D03*
X46746D03*
X73541Y766798D03*
X66099Y770144D03*
X73541Y780184D03*
Y773491D03*
X66099Y783530D03*
Y776837D03*
X73541Y803609D03*
Y796916D03*
Y790223D03*
X66099Y800263D03*
Y793570D03*
X73541Y816995D03*
Y810302D03*
X66099Y820341D03*
Y813648D03*
Y806955D03*
X73541Y833727D03*
Y827034D03*
X66099Y830381D03*
X73541Y847113D03*
Y840420D03*
X66099Y850459D03*
Y843766D03*
Y837074D03*
X73541Y863845D03*
Y853806D03*
X66099Y867192D03*
Y857152D03*
X73541Y883924D03*
Y877231D03*
Y870538D03*
X66099Y880577D03*
Y873885D03*
X73541Y900656D03*
Y890617D03*
X66099Y893963D03*
Y887270D03*
X73541Y914042D03*
Y907349D03*
X66099Y917389D03*
Y910696D03*
Y904003D03*
X73541Y927428D03*
Y920735D03*
X66099Y930774D03*
Y924081D03*
X73541Y944160D03*
Y937467D03*
X66099Y947507D03*
Y940814D03*
X73541Y960892D03*
Y950853D03*
X66099Y964239D03*
Y954200D03*
X73541Y980971D03*
Y974278D03*
Y967585D03*
X66099Y977625D03*
Y970932D03*
X73541Y987664D03*
X66099Y991011D03*
Y984318D03*
X73541Y1027822D03*
Y1017782D03*
X66099Y1031168D03*
Y1024475D03*
Y1017782D03*
X73541Y1047900D03*
Y1041207D03*
Y1034515D03*
X66099Y1044554D03*
Y1037861D03*
X73541Y1061286D03*
Y1054593D03*
X66099Y1057940D03*
Y1051247D03*
X73541Y1074672D03*
Y1067979D03*
X66099Y1078018D03*
Y1071326D03*
Y1064633D03*
X73541Y1091404D03*
Y1084711D03*
X66099Y1094751D03*
Y1088058D03*
X73541Y1111483D03*
Y1104790D03*
Y1098097D03*
X66099Y1108137D03*
Y1101444D03*
X73541Y1128215D03*
Y1121522D03*
X66099Y1124869D03*
Y1114829D03*
X73541Y1141601D03*
Y1134908D03*
X66099Y1144948D03*
Y1138255D03*
Y1131562D03*
X73541Y1158333D03*
Y1148294D03*
X66099Y1161680D03*
Y1151641D03*
X73541Y1171719D03*
Y1165026D03*
X66099Y1175066D03*
Y1168373D03*
X73541Y1185105D03*
Y1178412D03*
X66099Y1188452D03*
Y1181759D03*
X73541Y1208530D03*
Y1201837D03*
Y1195144D03*
X66099Y1205184D03*
Y1198491D03*
X73541Y1221916D03*
Y1215223D03*
X66099Y1225263D03*
Y1218570D03*
Y1211877D03*
X73541Y1238648D03*
Y1231955D03*
X66099Y1241995D03*
Y1235302D03*
X66189Y1257488D03*
X73541Y1245341D03*
X66099Y1248688D03*
X76446Y1273364D03*
X63246D03*
X87099Y770144D03*
X82241Y766798D03*
X87099Y783530D03*
Y776837D03*
X82241Y780184D03*
Y773491D03*
X87099Y800263D03*
Y793570D03*
X82241Y803609D03*
Y796916D03*
Y790223D03*
X87099Y820341D03*
Y813648D03*
Y806955D03*
X82241Y816995D03*
Y810302D03*
X87099Y830381D03*
X82241Y833727D03*
Y827034D03*
X87099Y850459D03*
Y843766D03*
Y837074D03*
X82241Y847113D03*
Y840420D03*
X87099Y867192D03*
Y857152D03*
X82241Y863845D03*
Y853806D03*
X87099Y880577D03*
Y873885D03*
X82241Y883924D03*
Y877231D03*
Y870538D03*
X87099Y893963D03*
Y887270D03*
X82241Y900656D03*
Y890617D03*
X87099Y917389D03*
Y910696D03*
Y904003D03*
X82241Y914042D03*
Y907349D03*
X87099Y930774D03*
Y924081D03*
X82241Y927428D03*
Y920735D03*
X87099Y947507D03*
Y940814D03*
X82241Y944160D03*
Y937467D03*
X87099Y964239D03*
Y954200D03*
X82241Y960892D03*
Y950853D03*
X87099Y977625D03*
Y970932D03*
X82241Y980971D03*
Y974278D03*
Y967585D03*
X87099Y991011D03*
Y984318D03*
X82241Y987664D03*
X87099Y1031168D03*
Y1024475D03*
Y1017782D03*
X82241Y1027822D03*
Y1017782D03*
X87099Y1044554D03*
Y1037861D03*
X82241Y1047900D03*
Y1041207D03*
Y1034515D03*
X87099Y1057940D03*
Y1051247D03*
X82241Y1061286D03*
Y1054593D03*
X87099Y1078018D03*
Y1071326D03*
Y1064633D03*
X82241Y1074672D03*
Y1067979D03*
X87099Y1094751D03*
Y1088058D03*
X82241Y1091404D03*
Y1084711D03*
X87099Y1108137D03*
Y1101444D03*
X82241Y1111483D03*
Y1104790D03*
Y1098097D03*
X87099Y1124869D03*
Y1114829D03*
X82241Y1128215D03*
Y1121522D03*
X87099Y1144948D03*
Y1138255D03*
Y1131562D03*
X82241Y1141601D03*
Y1134908D03*
X87099Y1161680D03*
Y1151641D03*
X82241Y1158333D03*
Y1148294D03*
X87099Y1175066D03*
Y1168373D03*
X82241Y1171719D03*
Y1165026D03*
X87099Y1188452D03*
Y1181759D03*
X82241Y1185105D03*
Y1178412D03*
X87099Y1205184D03*
Y1198491D03*
X82241Y1208530D03*
Y1201837D03*
Y1195144D03*
X87099Y1225263D03*
Y1218570D03*
Y1211877D03*
X82241Y1221916D03*
Y1215223D03*
X87099Y1241995D03*
Y1235302D03*
X82241Y1238648D03*
Y1231955D03*
X87099Y1248688D03*
X82241Y1245341D03*
X92946Y1273364D03*
X90146D03*
X79246D03*
X103241Y766798D03*
X95799Y770144D03*
X103241Y780184D03*
Y773491D03*
X95799Y783530D03*
Y776837D03*
X103241Y803609D03*
Y796916D03*
Y790223D03*
X95799Y800263D03*
Y793570D03*
X103241Y816995D03*
Y810302D03*
X95799Y820341D03*
Y813648D03*
Y806955D03*
X103241Y833727D03*
Y827034D03*
X95799Y830381D03*
X103241Y847113D03*
Y840420D03*
X95799Y850459D03*
Y843766D03*
Y837074D03*
X103241Y863845D03*
Y853806D03*
X95799Y867192D03*
Y857152D03*
X103241Y883924D03*
Y877231D03*
Y870538D03*
X95799Y880577D03*
Y873885D03*
X103241Y900656D03*
Y890617D03*
X95799Y893963D03*
Y887270D03*
X103241Y914042D03*
Y907349D03*
X95799Y917389D03*
Y910696D03*
Y904003D03*
X103241Y927428D03*
Y920735D03*
X95799Y930774D03*
Y924081D03*
X103241Y944160D03*
Y937467D03*
X95799Y947507D03*
Y940814D03*
X103241Y960892D03*
Y950853D03*
X95799Y964239D03*
Y954200D03*
X103241Y980971D03*
Y974278D03*
Y967585D03*
X95799Y977625D03*
Y970932D03*
X103241Y987664D03*
X95799Y991011D03*
Y984318D03*
X103241Y1027822D03*
Y1017782D03*
X95799Y1031168D03*
Y1024475D03*
Y1017782D03*
X103241Y1047900D03*
Y1041207D03*
Y1034515D03*
X95799Y1044554D03*
Y1037861D03*
X103241Y1061286D03*
Y1054593D03*
X95799Y1057940D03*
Y1051247D03*
X103241Y1074672D03*
Y1067979D03*
X95799Y1078018D03*
Y1071326D03*
Y1064633D03*
X103241Y1091404D03*
Y1084711D03*
X95799Y1094751D03*
Y1088058D03*
X103241Y1111483D03*
Y1104790D03*
Y1098097D03*
X95799Y1108137D03*
Y1101444D03*
X103241Y1128215D03*
Y1121522D03*
X95799Y1124869D03*
Y1114829D03*
X103241Y1141601D03*
Y1134908D03*
X95799Y1144948D03*
Y1138255D03*
Y1131562D03*
X103241Y1158333D03*
Y1148294D03*
X95799Y1161680D03*
Y1151641D03*
X103241Y1171719D03*
Y1165026D03*
X95799Y1175066D03*
Y1168373D03*
X103241Y1185105D03*
Y1178412D03*
X95799Y1188452D03*
Y1181759D03*
X103241Y1208530D03*
Y1201837D03*
Y1195144D03*
X95799Y1205184D03*
Y1198491D03*
X103241Y1221916D03*
Y1215223D03*
X95799Y1225263D03*
Y1218570D03*
Y1211877D03*
X103241Y1238648D03*
Y1231955D03*
X95799Y1241995D03*
Y1235302D03*
X95849Y1257262D03*
X103241Y1245341D03*
X95799Y1248688D03*
X108946Y1273364D03*
X106146D03*
X125499Y770144D03*
X116799D03*
X111941Y766798D03*
X125499Y783530D03*
X116799D03*
X125499Y776837D03*
X116799D03*
X111941Y780184D03*
Y773491D03*
X125499Y800263D03*
X116799D03*
X125499Y793570D03*
X116799D03*
X111941Y803609D03*
Y796916D03*
Y790223D03*
X125499Y820341D03*
X116799D03*
X125499Y813648D03*
X116799D03*
X125499Y806955D03*
X116799D03*
X111941Y816995D03*
Y810302D03*
X125499Y830381D03*
X116799D03*
X111941Y833727D03*
Y827034D03*
X125499Y850459D03*
X116799D03*
X125499Y843766D03*
X116799D03*
X125499Y837074D03*
X116799D03*
X111941Y847113D03*
Y840420D03*
X125499Y867192D03*
X116799D03*
X125499Y857152D03*
X116799D03*
X111941Y863845D03*
Y853806D03*
X125499Y880577D03*
X116799D03*
X125499Y873885D03*
X116799D03*
X111941Y883924D03*
Y877231D03*
Y870538D03*
X125499Y893963D03*
X116799D03*
X125499Y887270D03*
X116799D03*
X111941Y900656D03*
Y890617D03*
X125499Y917389D03*
X116799D03*
X125499Y910696D03*
X116799D03*
X125499Y904003D03*
X116799D03*
X111941Y914042D03*
Y907349D03*
X125499Y930774D03*
X116799D03*
X125499Y924081D03*
X116799D03*
X111941Y927428D03*
Y920735D03*
X125499Y947507D03*
X116799D03*
X125499Y940814D03*
X116799D03*
X111941Y944160D03*
Y937467D03*
X125499Y964239D03*
X116799D03*
X125499Y954200D03*
X116799D03*
X111941Y960892D03*
Y950853D03*
X125499Y977625D03*
X116799D03*
X125499Y970932D03*
X116799D03*
X111941Y980971D03*
Y974278D03*
Y967585D03*
X125499Y991011D03*
X116799D03*
X125499Y984318D03*
X116799D03*
X111941Y987664D03*
X125499Y1031168D03*
X116799D03*
X125499Y1024475D03*
X116799D03*
X125499Y1017782D03*
X116799D03*
X111941Y1027822D03*
Y1017782D03*
X125499Y1044554D03*
X116799D03*
X125499Y1037861D03*
X116799D03*
X111941Y1047900D03*
Y1041207D03*
Y1034515D03*
X125499Y1057940D03*
X116799D03*
X125499Y1051247D03*
X116799D03*
X111941Y1061286D03*
Y1054593D03*
X125499Y1078018D03*
X116799D03*
X125499Y1071326D03*
X116799D03*
X125499Y1064633D03*
X116799D03*
X111941Y1074672D03*
Y1067979D03*
X125499Y1094751D03*
X116799D03*
X125499Y1088058D03*
X116799D03*
X111941Y1091404D03*
Y1084711D03*
X125499Y1108137D03*
X116799D03*
X125499Y1101444D03*
X116799D03*
X111941Y1111483D03*
Y1104790D03*
Y1098097D03*
X125499Y1124869D03*
X116799D03*
X125499Y1114829D03*
X116799D03*
X111941Y1128215D03*
Y1121522D03*
X125499Y1144948D03*
X116799D03*
X125499Y1138255D03*
X116799D03*
X125499Y1131562D03*
X116799D03*
X111941Y1141601D03*
Y1134908D03*
X125499Y1161680D03*
X116799D03*
X125499Y1151641D03*
X116799D03*
X111941Y1158333D03*
Y1148294D03*
X125499Y1175066D03*
X116799D03*
X125499Y1168373D03*
X116799D03*
X111941Y1171719D03*
Y1165026D03*
X125499Y1188452D03*
X116799D03*
X125499Y1181759D03*
X116799D03*
X111941Y1185105D03*
Y1178412D03*
X125499Y1205184D03*
X116799D03*
X125499Y1198491D03*
X116799D03*
X111941Y1208530D03*
Y1201837D03*
Y1195144D03*
X125499Y1225263D03*
X116799D03*
X125499Y1218570D03*
X116799D03*
X125499Y1211877D03*
X116799D03*
X111941Y1221916D03*
Y1215223D03*
X125499Y1241995D03*
X116799D03*
X125499Y1235302D03*
X116799D03*
X111941Y1238648D03*
Y1231955D03*
X125412Y1257102D03*
X125499Y1248688D03*
X116799D03*
X111941Y1245341D03*
X119846Y1273364D03*
X122646D03*
X141641Y766798D03*
X132941D03*
X141641Y773491D03*
X132941D03*
X141641Y780184D03*
X132941D03*
X141641Y803609D03*
X132941D03*
X141641Y790223D03*
X132941D03*
X141641Y796916D03*
X132941D03*
X141641Y816995D03*
X132941D03*
X141641Y810302D03*
X132941D03*
X141641Y833727D03*
X132941D03*
X141641Y827034D03*
X132941D03*
X141641Y840420D03*
X132941D03*
X141641Y847113D03*
X132941D03*
Y863845D03*
X141641D03*
Y853806D03*
X132941D03*
Y883924D03*
X141641D03*
X132941Y870538D03*
X141641D03*
X132941Y877231D03*
X141641D03*
X132941Y900656D03*
X141641D03*
X132941Y890617D03*
X141641D03*
X132941Y907349D03*
X141641D03*
X132941Y914042D03*
X141641D03*
X132941Y920735D03*
X141641D03*
X132941Y927428D03*
X141641D03*
X132941Y937467D03*
X141641D03*
X132941Y944160D03*
X141641D03*
X132941Y960892D03*
X141641D03*
X132941Y950853D03*
X141641D03*
X132941Y980971D03*
X141641D03*
X132941Y974278D03*
X141641D03*
X132941Y967585D03*
X141641D03*
X132941Y987664D03*
X141641D03*
X132941Y1027822D03*
X141641D03*
X132941Y1017782D03*
X141641D03*
X132941Y1047900D03*
X141641D03*
X132941Y1041207D03*
X141641D03*
X132941Y1034515D03*
X141641D03*
Y1061286D03*
X132941D03*
X141641Y1054593D03*
X132941D03*
X141641Y1074672D03*
X132941D03*
X141641Y1067979D03*
X132941D03*
X141641Y1091404D03*
X132941D03*
X141641Y1084711D03*
X132941D03*
X141641Y1111483D03*
X132941D03*
X141641Y1104790D03*
X132941D03*
X141641Y1098097D03*
X132941D03*
X141641Y1128215D03*
X132941D03*
X141641Y1121522D03*
X132941D03*
X141641Y1141601D03*
X132941D03*
X141641Y1134908D03*
X132941D03*
X141641Y1158333D03*
X132941D03*
X141641Y1148294D03*
X132941D03*
X141641Y1171719D03*
X132941D03*
X141641Y1165026D03*
X132941D03*
X141641Y1185105D03*
X132941D03*
X141641Y1178412D03*
X132941D03*
X141641Y1208530D03*
X132941D03*
X141641Y1201837D03*
X132941D03*
X141641Y1195144D03*
X132941D03*
Y1221916D03*
X141641D03*
X132941Y1215223D03*
X141641D03*
X132941Y1238648D03*
X141641D03*
X132941Y1231955D03*
X141641D03*
X132941Y1245341D03*
X141641D03*
X135846Y1273364D03*
X138646D03*
X146499Y770144D03*
X155199D03*
X146499Y783530D03*
X155199D03*
X146499Y776837D03*
X155199D03*
X146499Y800263D03*
X155199D03*
X146499Y793570D03*
X155199D03*
X146499Y820341D03*
X155199D03*
X146499Y813648D03*
X155199D03*
X146499Y806955D03*
X155199D03*
X146499Y830381D03*
X155199D03*
X146499Y850459D03*
X155199D03*
X146499Y843766D03*
X155199D03*
X146499Y837074D03*
X155199D03*
Y867192D03*
X146499D03*
Y857152D03*
X155199D03*
Y880577D03*
X146499D03*
X155199Y873885D03*
X146499D03*
X155199Y893963D03*
X146499D03*
X155199Y887270D03*
X146499D03*
X155199Y917389D03*
X146499D03*
X155199Y910696D03*
X146499D03*
X155199Y904003D03*
X146499D03*
X155199Y930774D03*
X146499D03*
X155199Y924081D03*
X146499D03*
X155199Y947507D03*
X146499D03*
X155199Y940814D03*
X146499D03*
X155199Y964239D03*
X146499D03*
X155199Y954200D03*
X146499D03*
X155199Y977625D03*
X146499D03*
X155199Y970932D03*
X146499D03*
X155199Y991011D03*
X146499D03*
X155199Y984318D03*
X146499D03*
X155199Y1031168D03*
X146499D03*
X155199Y1024475D03*
X146499D03*
X155199Y1017782D03*
X146499D03*
X155199Y1044554D03*
X146499D03*
X155199Y1037861D03*
X146499D03*
X155199Y1057940D03*
X146499D03*
X155199Y1051247D03*
X146499D03*
X155199Y1078018D03*
X146499D03*
X155199Y1071326D03*
X146499D03*
X155199Y1064633D03*
X146499D03*
X155199Y1094751D03*
X146499D03*
X155199Y1088058D03*
X146499D03*
X155199Y1108137D03*
X146499D03*
X155199Y1101444D03*
X146499D03*
X155199Y1124869D03*
X146499D03*
X155199Y1114829D03*
X146499D03*
X155199Y1144948D03*
X146499D03*
X155199Y1138255D03*
X146499D03*
X155199Y1131562D03*
X146499D03*
X155199Y1161680D03*
X146499D03*
X155199Y1151641D03*
X146499D03*
X155199Y1175066D03*
X146499D03*
X155199Y1168373D03*
X146499D03*
X155199Y1188452D03*
X146499D03*
X155199Y1181759D03*
X146499D03*
X155199Y1205184D03*
X146499D03*
X155199Y1198491D03*
X146499D03*
X155199Y1225263D03*
X146499D03*
X155199Y1218570D03*
X146499D03*
X155199Y1211877D03*
X146499D03*
X155199Y1241995D03*
X146499D03*
X155199Y1235302D03*
X146499D03*
X155135Y1257134D03*
X155199Y1248688D03*
X146499D03*
X149546Y1273364D03*
X152346D03*
X176199Y770144D03*
X162641Y766798D03*
X171341D03*
X176199Y783530D03*
Y776837D03*
X162641Y780184D03*
X171341D03*
Y773491D03*
X162641D03*
X176199Y800263D03*
X162641Y803609D03*
X171341D03*
X176199Y793570D03*
X162641Y796916D03*
X171341D03*
X162641Y790223D03*
X171341D03*
X176199Y820341D03*
X162641Y816995D03*
X171341D03*
X176199Y813648D03*
Y806955D03*
X162641Y810302D03*
X171341D03*
X162641Y833727D03*
X171341D03*
X176199Y830381D03*
X162641Y827034D03*
X171341D03*
X176199Y850459D03*
Y843766D03*
Y837074D03*
X162641Y847113D03*
X171341D03*
X162641Y840420D03*
X171341D03*
X176199Y867192D03*
X171341Y863845D03*
X162641D03*
X176199Y857152D03*
X162641Y853806D03*
X171341D03*
Y883924D03*
X162641D03*
X176199Y880577D03*
Y873885D03*
X171341Y877231D03*
X162641D03*
X171341Y870538D03*
X162641D03*
X171341Y900656D03*
X162641D03*
X176199Y893963D03*
Y887270D03*
X171341Y890617D03*
X162641D03*
X176199Y917389D03*
Y910696D03*
Y904003D03*
X171341Y914042D03*
X162641D03*
X171341Y907349D03*
X162641D03*
X176199Y930774D03*
Y924081D03*
X171341Y927428D03*
X162641D03*
X171341Y920735D03*
X162641D03*
X176199Y947507D03*
Y940814D03*
X171341Y944160D03*
X162641D03*
X171341Y937467D03*
X162641D03*
X176199Y964239D03*
Y954200D03*
X171341Y960892D03*
X162641D03*
X171341Y950853D03*
X162641D03*
X171341Y980971D03*
X162641D03*
X176199Y977625D03*
Y970932D03*
X171341Y974278D03*
X162641D03*
X171341Y967585D03*
X162641D03*
X176199Y991011D03*
Y984318D03*
X171341Y987664D03*
X162641D03*
X176199Y1031168D03*
Y1024475D03*
Y1017782D03*
X171341Y1027822D03*
X162641D03*
X171341Y1017782D03*
X162641D03*
X171341Y1047900D03*
X162641D03*
X176199Y1044554D03*
Y1037861D03*
X171341Y1041207D03*
X162641D03*
X171341Y1034515D03*
X162641D03*
X176199Y1057940D03*
Y1051247D03*
X171341Y1061286D03*
X162641D03*
X171341Y1054593D03*
X162641D03*
X176199Y1078018D03*
Y1071326D03*
Y1064633D03*
X171341Y1074672D03*
X162641D03*
X171341Y1067979D03*
X162641D03*
X176199Y1094751D03*
Y1088058D03*
X171341Y1091404D03*
X162641D03*
X171341Y1084711D03*
X162641D03*
X171341Y1111483D03*
X162641D03*
X176199Y1108137D03*
Y1101444D03*
X171341Y1104790D03*
X162641D03*
X171341Y1098097D03*
X162641D03*
X171341Y1128215D03*
X162641D03*
X176199Y1124869D03*
Y1114829D03*
X171341Y1121522D03*
X162641D03*
X176199Y1144948D03*
Y1138255D03*
Y1131562D03*
X171341Y1141601D03*
X162641D03*
X171341Y1134908D03*
X162641D03*
X176199Y1161680D03*
Y1151641D03*
X171341Y1158333D03*
X162641D03*
X171341Y1148294D03*
X162641D03*
X176199Y1175066D03*
Y1168373D03*
X171341Y1171719D03*
X162641D03*
X171341Y1165026D03*
X162641D03*
X176199Y1188452D03*
Y1181759D03*
X171341Y1185105D03*
X162641D03*
X171341Y1178412D03*
X162641D03*
X176199Y1205184D03*
Y1198491D03*
X171341Y1208530D03*
X162641D03*
X171341Y1201837D03*
X162641D03*
X171341Y1195144D03*
X162641D03*
X176199Y1225263D03*
Y1218570D03*
Y1211877D03*
X162641Y1221916D03*
X171341D03*
Y1215223D03*
X162641D03*
X176199Y1241995D03*
Y1235302D03*
X171341Y1238648D03*
X162641D03*
X171341Y1231955D03*
X162641D03*
X176199Y1248688D03*
X171341Y1245341D03*
X162641D03*
X165546Y1273364D03*
X168346D03*
X192341Y766798D03*
X184899Y770144D03*
X192341Y780184D03*
Y773491D03*
X184899Y783530D03*
Y776837D03*
X192341Y803609D03*
Y796916D03*
Y790223D03*
X184899Y800263D03*
Y793570D03*
X192341Y816995D03*
Y810302D03*
X184899Y820341D03*
Y813648D03*
Y806955D03*
X192341Y833727D03*
X191491Y827034D03*
X184899Y830381D03*
X192341Y847113D03*
Y840420D03*
X184899Y850459D03*
Y843766D03*
Y837074D03*
X191491Y863845D03*
X184899Y867192D03*
X192341Y853806D03*
X184899Y857152D03*
X192341Y883924D03*
Y877231D03*
Y870538D03*
X184899Y880577D03*
Y873885D03*
X192341Y900656D03*
Y890617D03*
X184899Y893963D03*
Y887270D03*
X192341Y914042D03*
Y907349D03*
X184899Y917389D03*
Y910696D03*
Y904003D03*
X191491Y927428D03*
X192341Y920735D03*
X184899Y930774D03*
Y924081D03*
X192341Y937467D03*
Y944160D03*
X184899Y947507D03*
Y940814D03*
X192341Y960892D03*
Y950853D03*
X184899Y964239D03*
Y954200D03*
X192341Y974278D03*
Y980971D03*
Y967585D03*
X184899Y977625D03*
Y970932D03*
X192341Y987664D03*
X184899Y991011D03*
Y984318D03*
X192341Y1027822D03*
Y1017782D03*
X184899Y1031168D03*
Y1024475D03*
Y1017782D03*
X192341Y1047900D03*
Y1041207D03*
Y1034515D03*
X184899Y1044554D03*
Y1037861D03*
X192341Y1054593D03*
Y1061286D03*
X184899Y1057940D03*
Y1051247D03*
X192341Y1074672D03*
Y1067979D03*
X184899Y1078018D03*
Y1071326D03*
Y1064633D03*
X192341Y1091404D03*
X191491Y1084711D03*
X184899Y1094751D03*
Y1088058D03*
X192341Y1111483D03*
Y1104790D03*
Y1098097D03*
X184899Y1108137D03*
Y1101444D03*
X192341Y1128215D03*
Y1121522D03*
X184899Y1124869D03*
Y1114829D03*
X192341Y1141601D03*
Y1134908D03*
X184899Y1144948D03*
Y1138255D03*
Y1131562D03*
X191491Y1158333D03*
X192341Y1148294D03*
X184899Y1161680D03*
Y1151641D03*
X192341Y1171719D03*
Y1165026D03*
X184899Y1175066D03*
Y1168373D03*
X192341Y1185105D03*
Y1178412D03*
X184899Y1188452D03*
Y1181759D03*
X192341Y1208530D03*
Y1201837D03*
Y1195144D03*
X184899Y1205184D03*
Y1198491D03*
X192341Y1221916D03*
Y1215223D03*
X184899Y1225263D03*
Y1218570D03*
Y1211877D03*
X192341Y1238648D03*
X191491Y1231955D03*
X184899Y1241995D03*
Y1235302D03*
X184923Y1258871D03*
X192341Y1245341D03*
X184899Y1248688D03*
X192594Y1271262D03*
X192605Y1268774D03*
X182046Y1273364D03*
X179246D03*
X186697Y1578182D03*
Y1590094D03*
X191997Y1602380D03*
Y1614292D03*
X205899Y770144D03*
X201041Y766798D03*
X205899Y783530D03*
Y776837D03*
X201041Y780184D03*
Y773491D03*
X205899Y800263D03*
Y793570D03*
X201041Y803609D03*
Y796916D03*
Y790223D03*
X205899Y813648D03*
Y806955D03*
X205049Y820341D03*
X201041Y816995D03*
Y810302D03*
X205049Y830381D03*
X201041Y833727D03*
Y827034D03*
X205899Y850459D03*
Y837074D03*
Y843766D03*
X201041Y847113D03*
Y840420D03*
X205049Y867192D03*
X201041Y863845D03*
X205049Y857152D03*
X201041Y853806D03*
X205899Y873885D03*
Y880577D03*
X201041Y883924D03*
Y877231D03*
Y870538D03*
X205899Y893963D03*
Y887270D03*
X201041Y900656D03*
Y890617D03*
X205899Y917389D03*
Y910696D03*
Y904003D03*
X201041Y914042D03*
Y907349D03*
X205049Y930774D03*
Y924081D03*
X201041Y927428D03*
Y920735D03*
X205899Y940814D03*
Y947507D03*
X201041Y937467D03*
Y944160D03*
X205899Y964239D03*
Y954200D03*
X201041Y960892D03*
Y950853D03*
X205899Y970932D03*
Y977625D03*
X201041Y974278D03*
Y980971D03*
Y967585D03*
X205899Y991011D03*
Y984318D03*
X201041Y987664D03*
X205899Y1031168D03*
Y1017782D03*
Y1024475D03*
X201041Y1027822D03*
Y1017782D03*
X205899Y1044554D03*
Y1037861D03*
X201041Y1047900D03*
Y1041207D03*
Y1034515D03*
X205899Y1057940D03*
Y1051247D03*
X201041Y1054593D03*
Y1061286D03*
X205049Y1078018D03*
X205899Y1071326D03*
Y1064633D03*
X201041Y1074672D03*
Y1067979D03*
X205899Y1094751D03*
X205049Y1088058D03*
X201041Y1091404D03*
Y1084711D03*
X205899Y1101444D03*
Y1108137D03*
X201041Y1111483D03*
Y1104790D03*
Y1098097D03*
X205899Y1114829D03*
Y1124869D03*
X201041Y1128215D03*
Y1121522D03*
X205899Y1144948D03*
Y1138255D03*
Y1131562D03*
X201041Y1141601D03*
Y1134908D03*
X205049Y1161680D03*
Y1151641D03*
X201041Y1158333D03*
Y1148294D03*
X205899Y1168373D03*
Y1175066D03*
X201041Y1171719D03*
Y1165026D03*
X205899Y1188452D03*
Y1181759D03*
X201041Y1185105D03*
Y1178412D03*
X205899Y1205184D03*
Y1198491D03*
X201041Y1208530D03*
Y1201837D03*
Y1195144D03*
X205049Y1225263D03*
X205899Y1211877D03*
Y1218570D03*
X201041Y1221916D03*
Y1215223D03*
X205899Y1241995D03*
X205049Y1235302D03*
X201041Y1238648D03*
Y1231955D03*
X205899Y1248688D03*
X201041Y1245341D03*
X206268Y1271348D03*
X206337Y1268720D03*
X194497Y1578182D03*
X206557D03*
X198757D03*
X194497Y1590094D03*
X206557D03*
X198757D03*
X199797Y1614292D03*
Y1602380D03*
X204057Y1614292D03*
Y1602380D03*
X222041Y766798D03*
X214599Y770144D03*
X222041Y780184D03*
Y773491D03*
X214599Y783530D03*
Y776837D03*
X222041Y803609D03*
Y796916D03*
Y790223D03*
X214599Y800263D03*
Y793570D03*
X222041Y810302D03*
X221191Y816995D03*
X214599Y813648D03*
Y806955D03*
X215449Y820341D03*
X222041Y833727D03*
X221191Y827034D03*
X215449Y830381D03*
X222041Y847113D03*
Y840420D03*
X214599Y850459D03*
Y837074D03*
Y843766D03*
X221191Y863845D03*
X215449Y867192D03*
X222041Y853806D03*
X215449Y857152D03*
X222041Y877231D03*
X221191Y870538D03*
X222041Y883924D03*
X214599Y873885D03*
Y880577D03*
X222041Y900656D03*
Y890617D03*
X214599Y893963D03*
Y887270D03*
X222041Y914042D03*
Y907349D03*
X214599Y917389D03*
Y910696D03*
Y904003D03*
X221241Y927428D03*
X222041Y920735D03*
X215449Y930774D03*
Y924081D03*
X222041Y944160D03*
X221191Y937467D03*
X214599Y940814D03*
Y947507D03*
X222041Y960892D03*
Y950853D03*
X214599Y964239D03*
Y954200D03*
X222041Y980971D03*
Y974278D03*
Y967585D03*
X214599Y970932D03*
Y977625D03*
Y991011D03*
Y984318D03*
X222041Y987664D03*
Y1027822D03*
Y1017782D03*
X214599Y1031168D03*
Y1017782D03*
Y1024475D03*
X222041Y1047900D03*
Y1041207D03*
Y1034515D03*
X214599Y1044554D03*
Y1037861D03*
X222041Y1054593D03*
Y1061286D03*
X214599Y1057940D03*
Y1051247D03*
X222041Y1067979D03*
X221191Y1074672D03*
X215449Y1078018D03*
X214599Y1071326D03*
Y1064633D03*
X222041Y1091404D03*
X221191Y1084711D03*
X214599Y1094751D03*
X215449Y1088058D03*
X222041Y1111483D03*
Y1098097D03*
Y1104790D03*
X214599Y1101444D03*
Y1108137D03*
X222041Y1128215D03*
Y1121522D03*
X214599Y1114829D03*
Y1124869D03*
X222041Y1141601D03*
X221191Y1134908D03*
X214599Y1144948D03*
Y1138255D03*
Y1131562D03*
X222041Y1158333D03*
X221191Y1148294D03*
X215449Y1161680D03*
Y1151641D03*
X222041Y1165026D03*
Y1171719D03*
X214599Y1168373D03*
Y1175066D03*
X222041Y1185105D03*
Y1178412D03*
X214599Y1188452D03*
Y1181759D03*
X222041Y1208530D03*
Y1201837D03*
Y1195144D03*
X214599Y1205184D03*
Y1198491D03*
X222041Y1221916D03*
Y1215223D03*
X215449Y1225263D03*
X214599Y1211877D03*
Y1218570D03*
X221191Y1231955D03*
Y1238648D03*
X214599Y1241995D03*
X215449Y1235302D03*
X222041Y1245341D03*
X214824Y1258711D03*
X214599Y1248688D03*
X224987Y1273535D03*
X218617Y1578182D03*
X210817D03*
X222877D03*
X218617Y1590094D03*
X210817D03*
X222877D03*
X211857Y1614292D03*
Y1602380D03*
X223917Y1614292D03*
X216117D03*
X223917Y1602380D03*
X216117D03*
X235599Y770144D03*
X230741Y766798D03*
X235599Y783530D03*
Y776837D03*
X230741Y780184D03*
Y773491D03*
X235599Y800263D03*
Y793570D03*
X230741Y803609D03*
Y796916D03*
Y790223D03*
X234749Y820341D03*
Y813648D03*
X235599Y806955D03*
X230741Y810302D03*
X231006Y817554D03*
X235599Y830381D03*
X230741Y833727D03*
X231591Y827034D03*
X235599Y850459D03*
Y837074D03*
Y843766D03*
X230741Y847113D03*
Y840420D03*
X234749Y867492D03*
X231591Y863845D03*
X234749Y857152D03*
X230741Y853806D03*
X235599Y874185D03*
Y880577D03*
X230741Y877231D03*
X231059Y871084D03*
X230741Y883924D03*
X235599Y893963D03*
Y887270D03*
X230741Y900656D03*
Y890617D03*
X235599Y917389D03*
Y910696D03*
Y904003D03*
X230741Y914042D03*
Y907349D03*
X235599Y930774D03*
Y924081D03*
X231541Y927428D03*
X230741Y920735D03*
X235599Y947507D03*
X234859Y940814D03*
X230741Y944660D03*
X231591Y937467D03*
X235599Y964239D03*
Y954200D03*
X230741Y960892D03*
Y950853D03*
X235599Y977625D03*
Y970932D03*
X230741Y980971D03*
Y974278D03*
Y967585D03*
X235599Y991011D03*
X230741Y987664D03*
X235599Y984318D03*
Y1031168D03*
X230741Y1027822D03*
Y1017782D03*
X235599D03*
Y1024475D03*
Y1044554D03*
Y1037861D03*
X230741Y1047900D03*
Y1041207D03*
Y1034515D03*
X235599Y1051247D03*
Y1057940D03*
X230741Y1054593D03*
Y1061286D03*
X234749Y1078018D03*
X235599Y1071326D03*
Y1064633D03*
X230741Y1067979D03*
X231591Y1074672D03*
X235599Y1094751D03*
X234749Y1088058D03*
X230741Y1091404D03*
Y1084711D03*
X235599Y1108137D03*
Y1101444D03*
X230741Y1111483D03*
Y1098097D03*
Y1104790D03*
X234749Y1124869D03*
X235599Y1114829D03*
X230741Y1128215D03*
Y1121522D03*
X235599Y1144948D03*
Y1138255D03*
X234749Y1131562D03*
X230741Y1141601D03*
X231591Y1134908D03*
X235599Y1151641D03*
Y1161680D03*
X230741Y1158333D03*
X231591Y1148294D03*
X235599Y1175066D03*
Y1168373D03*
X230741Y1165026D03*
Y1171719D03*
X235599Y1188452D03*
Y1181759D03*
X230741Y1185105D03*
Y1178412D03*
X235599Y1205184D03*
Y1198491D03*
X230741Y1208530D03*
Y1201837D03*
Y1195144D03*
X234749Y1225263D03*
X235599Y1218570D03*
Y1211877D03*
X230741Y1221916D03*
Y1215223D03*
X235599Y1241995D03*
X235186Y1234977D03*
X231591Y1231955D03*
Y1238648D03*
X235599Y1248688D03*
X230741Y1245341D03*
X227746Y1273364D03*
X240966Y1273143D03*
X238971Y1274353D03*
X230677Y1578182D03*
X234937D03*
X230677Y1590094D03*
X234937D03*
X228177Y1614292D03*
X235977D03*
X228177Y1602380D03*
X235977D03*
X240237D03*
Y1614292D03*
X233268Y1679920D03*
Y1675383D03*
X241142Y1679320D03*
X233268Y1698627D03*
Y1694093D03*
Y1689556D03*
Y1684454D03*
X241142Y1683857D03*
Y1688391D03*
Y1693493D03*
Y1698030D03*
X233268Y1712800D03*
Y1708266D03*
Y1703729D03*
X241142Y1702564D03*
Y1707666D03*
Y1712203D03*
X233268Y1717903D03*
Y1722440D03*
Y1726974D03*
X241142Y1716737D03*
Y1730911D03*
Y1726377D03*
Y1721840D03*
X251741Y766798D03*
X244299Y770144D03*
X251741Y780184D03*
Y773491D03*
X244299Y783530D03*
Y776837D03*
X251741Y803609D03*
Y796916D03*
Y790223D03*
X244299Y800263D03*
Y793570D03*
X250891Y816995D03*
X251741Y810302D03*
X245149Y820341D03*
Y813648D03*
X244299Y806955D03*
X251741Y833727D03*
X250891Y827034D03*
X244299Y830381D03*
X251741Y847113D03*
Y840420D03*
X244299Y850459D03*
Y837074D03*
Y843766D03*
X250891Y863845D03*
Y853806D03*
X245149Y867192D03*
Y857152D03*
X251741Y870538D03*
Y883924D03*
Y877231D03*
X244299Y873885D03*
Y880577D03*
X250891Y900656D03*
X251741Y890617D03*
X244299Y893963D03*
Y887270D03*
X251741Y914042D03*
Y907349D03*
X244299Y917389D03*
Y910696D03*
Y904003D03*
X250891Y927428D03*
X251741Y920735D03*
X245149Y930774D03*
X244299Y924081D03*
X251741Y944160D03*
X250891Y937467D03*
X244299Y947507D03*
X245149Y940814D03*
X251741Y960892D03*
Y950853D03*
X244299Y964239D03*
Y954200D03*
X251741Y980971D03*
Y974278D03*
Y967585D03*
X244299Y977625D03*
Y970932D03*
X251741Y987664D03*
X244299Y991011D03*
Y984318D03*
Y1031168D03*
X251741Y1027822D03*
Y1017782D03*
X244299D03*
Y1024475D03*
X251741Y1047900D03*
Y1041207D03*
Y1034515D03*
X244299Y1044554D03*
Y1037861D03*
X251741Y1061286D03*
Y1054593D03*
X244299Y1051247D03*
Y1057940D03*
X250891Y1074672D03*
Y1067979D03*
X245149Y1078018D03*
X244299Y1071326D03*
Y1064633D03*
X251741Y1091404D03*
Y1084711D03*
X244299Y1094751D03*
X245149Y1088058D03*
X251741Y1104790D03*
X250891Y1111483D03*
X251741Y1098097D03*
X244299Y1108137D03*
Y1101444D03*
X251741Y1128215D03*
X250891Y1121522D03*
X245149Y1124869D03*
X244299Y1114829D03*
X251741Y1134908D03*
Y1141601D03*
X244299Y1144948D03*
Y1138255D03*
X245149Y1131562D03*
X251741Y1158333D03*
Y1148294D03*
X244299Y1151641D03*
Y1161680D03*
X251741Y1171719D03*
Y1165026D03*
X244299Y1175066D03*
Y1168373D03*
X251741Y1185105D03*
Y1178412D03*
X244299Y1188452D03*
Y1181759D03*
X251741Y1208530D03*
Y1201837D03*
X250891Y1195144D03*
X244299Y1205184D03*
Y1198491D03*
X250891Y1221916D03*
X251741Y1215223D03*
X245149Y1225263D03*
X244299Y1218570D03*
Y1211877D03*
X250891Y1231955D03*
X244299Y1241995D03*
X245149Y1235302D03*
X251741Y1238648D03*
X244299Y1248688D03*
X251741Y1245341D03*
X244789Y1260093D03*
X254897Y1274040D03*
X257197Y1273640D03*
X242737Y1578182D03*
X246997D03*
X254797D03*
X242737Y1590094D03*
X246997D03*
X254797D03*
X248037Y1602380D03*
Y1614292D03*
X252297Y1602380D03*
Y1614292D03*
X249016Y1675383D03*
Y1679920D03*
X256890Y1679320D03*
X249016Y1684454D03*
Y1689556D03*
Y1694093D03*
Y1698627D03*
X256890Y1683857D03*
Y1688391D03*
Y1693493D03*
Y1698030D03*
X249016Y1703729D03*
Y1708266D03*
Y1712800D03*
X256890Y1702564D03*
Y1707666D03*
Y1712203D03*
X249016Y1726974D03*
Y1722440D03*
Y1717903D03*
X256890Y1716737D03*
Y1730911D03*
Y1726377D03*
Y1721840D03*
X260441Y766798D03*
Y780184D03*
Y773491D03*
Y803609D03*
Y796916D03*
Y790223D03*
X261291Y816995D03*
X260441Y810302D03*
Y833727D03*
X261291Y827034D03*
X260441Y847113D03*
Y840420D03*
X261291Y863845D03*
Y853806D03*
X260441Y870538D03*
Y883924D03*
Y877231D03*
Y900656D03*
Y890617D03*
Y914042D03*
Y907349D03*
X261291Y927428D03*
X260441Y920735D03*
Y944160D03*
X261291Y937467D03*
X260441Y960892D03*
Y950853D03*
Y980971D03*
Y974278D03*
Y967585D03*
Y987664D03*
Y1027822D03*
Y1017782D03*
Y1047900D03*
Y1041207D03*
Y1034515D03*
Y1061286D03*
Y1054593D03*
X261291Y1074672D03*
Y1067979D03*
X260441Y1091404D03*
Y1084711D03*
Y1104790D03*
X261291Y1111483D03*
X260441Y1098097D03*
Y1128215D03*
X261291Y1121522D03*
X260441Y1134908D03*
Y1141601D03*
Y1158333D03*
Y1148294D03*
Y1171719D03*
Y1165026D03*
Y1185105D03*
Y1178412D03*
Y1208530D03*
Y1201837D03*
Y1195144D03*
X261291Y1221916D03*
X260441Y1215223D03*
X261291Y1231955D03*
X260441Y1238648D03*
Y1245341D03*
X266857Y1578182D03*
X259057D03*
X271117D03*
X266857Y1590094D03*
X259057D03*
X271117D03*
X260097Y1602380D03*
Y1614292D03*
X272157Y1602380D03*
Y1614292D03*
X264357D03*
Y1602380D03*
X264764Y1675383D03*
Y1679920D03*
X272638Y1679320D03*
X264764Y1684454D03*
Y1689556D03*
Y1694093D03*
Y1698627D03*
X272638Y1683857D03*
Y1688391D03*
Y1693493D03*
Y1698030D03*
X264764Y1703729D03*
Y1708266D03*
Y1712800D03*
X272638Y1702564D03*
Y1707666D03*
Y1712203D03*
X264764Y1726974D03*
Y1722440D03*
Y1717903D03*
X272638Y1716737D03*
Y1730911D03*
Y1726377D03*
Y1721840D03*
X278917Y1578182D03*
X283177D03*
X278917Y1590094D03*
X283177D03*
X284217Y1602380D03*
Y1614292D03*
X276417D03*
Y1602380D03*
X288477Y1614292D03*
Y1602380D03*
X280512Y1675383D03*
Y1679920D03*
Y1684454D03*
Y1689556D03*
Y1694093D03*
Y1698627D03*
Y1703729D03*
Y1708266D03*
Y1712800D03*
Y1726974D03*
Y1722440D03*
Y1717903D03*
X290977Y1578182D03*
X295237D03*
X303037D03*
X290977Y1590094D03*
X295237D03*
X303037D03*
X296277Y1614292D03*
Y1602380D03*
X300537D03*
Y1614292D03*
X300197Y1679920D03*
Y1675383D03*
Y1698627D03*
Y1694093D03*
Y1689556D03*
Y1684454D03*
Y1712800D03*
Y1708266D03*
Y1703729D03*
Y1717903D03*
Y1722440D03*
Y1726974D03*
X315097Y1578182D03*
X307297D03*
X319357D03*
X315097Y1590094D03*
X307297D03*
X319357D03*
X308337Y1602380D03*
Y1614292D03*
X320397D03*
X312597D03*
X320397Y1602380D03*
X312597D03*
X308071Y1679320D03*
X315945Y1679920D03*
Y1675383D03*
X308071Y1683857D03*
Y1698030D03*
Y1693493D03*
Y1688391D03*
X315945Y1698627D03*
Y1694093D03*
Y1689556D03*
Y1684454D03*
X308071Y1702564D03*
Y1712203D03*
Y1707666D03*
X315945Y1712800D03*
Y1708266D03*
Y1703729D03*
X308071Y1716737D03*
Y1721840D03*
Y1726377D03*
Y1730911D03*
X315945Y1717903D03*
Y1722440D03*
Y1726974D03*
X327157Y1578182D03*
X331417D03*
X327157Y1590094D03*
X331417D03*
X324657Y1602380D03*
X332457D03*
X324657Y1614292D03*
X332457D03*
X336717Y1602380D03*
Y1614292D03*
X323819Y1679320D03*
X331693Y1679920D03*
Y1675383D03*
X323819Y1683857D03*
Y1698030D03*
Y1693493D03*
Y1688391D03*
X331693Y1698627D03*
Y1694093D03*
Y1689556D03*
Y1684454D03*
X323819Y1702564D03*
Y1712203D03*
Y1707666D03*
X331693Y1712800D03*
Y1708266D03*
Y1703729D03*
X323819Y1716737D03*
Y1721840D03*
Y1726377D03*
Y1730911D03*
X331693Y1717903D03*
Y1722440D03*
Y1726974D03*
X352579Y854584D03*
X347029Y870606D03*
Y889832D03*
X343707Y1091513D03*
X339217Y1578182D03*
X343477D03*
X351277D03*
X339217Y1590094D03*
X343477D03*
X351277D03*
X344517Y1602380D03*
Y1614292D03*
X348777Y1602380D03*
Y1614292D03*
X339567Y1679320D03*
X347441Y1679920D03*
Y1675383D03*
X355315Y1679320D03*
X339567Y1683857D03*
Y1698030D03*
Y1693493D03*
Y1688391D03*
X347441Y1698627D03*
Y1694093D03*
Y1689556D03*
Y1684454D03*
X355315Y1683857D03*
Y1698030D03*
Y1693493D03*
Y1688391D03*
X339567Y1702564D03*
Y1712203D03*
Y1707666D03*
X347441Y1712800D03*
Y1708266D03*
Y1703729D03*
X355315Y1702564D03*
Y1712203D03*
Y1707666D03*
X339567Y1716737D03*
Y1721840D03*
Y1726377D03*
Y1730911D03*
X347441Y1717903D03*
Y1722440D03*
Y1726974D03*
X355315Y1716737D03*
Y1721840D03*
Y1726377D03*
Y1730911D03*
X359979Y841467D03*
X367379D03*
X365529Y851380D03*
X369229D03*
X359979Y880219D03*
Y899445D03*
X371078D03*
X359979Y918670D03*
X365529Y941100D03*
X359979Y937896D03*
X371078D03*
X369662Y1006093D03*
X365962Y1076587D03*
X363337Y1578088D03*
X355537Y1578182D03*
X367597D03*
X363337Y1590094D03*
X355537D03*
X367597D03*
X356577Y1602380D03*
Y1614292D03*
X368637D03*
X360837D03*
X368637Y1602286D03*
X360837Y1602380D03*
X382179Y841467D03*
X374779D03*
X380329Y851380D03*
X376629D03*
X372929D03*
X384029D03*
X387729D03*
X378478Y931488D03*
X378911Y1060565D03*
X375397Y1578182D03*
Y1590094D03*
X372897Y1602380D03*
X380697D03*
X372897Y1614292D03*
X380697D03*
X389579Y841467D03*
X396978Y899445D03*
Y937896D03*
X415185Y985580D03*
X417575D03*
X415185Y1014540D03*
X417575D03*
X435829Y851380D03*
Y864197D03*
Y877014D03*
Y889832D03*
Y902649D03*
X428429Y921875D03*
X430279Y937897D03*
X433979D03*
X433980Y944305D03*
Y957123D03*
Y950714D03*
Y963531D03*
Y976348D03*
Y969940D03*
Y982757D03*
X434411Y1009298D03*
X434412Y1002889D03*
X434411Y1028524D03*
Y1022115D03*
X434412Y1015706D03*
Y1034932D03*
X434411Y1092608D03*
X450629Y851380D03*
Y877014D03*
X437678Y912262D03*
X441379Y937897D03*
X445079D03*
X437679D03*
X446929Y941101D03*
X446930Y947510D03*
Y960327D03*
Y953918D03*
Y966736D03*
Y979553D03*
Y973144D03*
X447362Y1006094D03*
Y999685D03*
Y1012502D03*
Y1025319D03*
Y1018911D03*
Y1031728D03*
X456178Y912262D03*
X461729Y921875D03*
X462261Y942152D03*
X464561D03*
X466861D03*
X454423Y949139D03*
X454393Y963829D03*
Y966129D03*
X463874Y956540D03*
X466272D03*
X454423Y951439D03*
X466272Y971100D03*
X463874Y971140D03*
X454263Y981209D03*
Y978909D03*
X454463Y995299D03*
Y992999D03*
X466272Y985580D03*
X463874D03*
X466272Y1014540D03*
X463874D03*
X454443Y1009409D03*
Y1007109D03*
X466272Y1000060D03*
X463874D03*
X468895Y1014550D03*
X465862Y1057361D03*
X458462Y1063770D03*
X465862D03*
X456611Y1073383D03*
X454762Y1070178D03*
X467711Y1073383D03*
Y1066974D03*
X474678Y899445D03*
Y912262D03*
X480229Y921875D03*
X471204Y1014540D03*
X475111Y1060565D03*
X484361Y1057361D03*
X475111Y1066974D03*
X473262Y1070178D03*
X478811Y1073383D03*
X484361Y1076587D03*
X482512Y1066974D03*
X478812Y1079791D03*
X475111D03*
X482911Y1578182D03*
X478651D03*
X470851D03*
X482911Y1590094D03*
X478651D03*
X470851D03*
X483951Y1614292D03*
Y1602380D03*
X476151D03*
Y1614292D03*
X489478Y912262D03*
X495462Y1057361D03*
X499162Y1063770D03*
X495462Y1076587D03*
X493612Y1073383D03*
X486211D03*
X497311Y1066974D03*
X495462Y1108630D03*
X493611Y1111834D03*
X494971Y1578182D03*
X490711D03*
X494971Y1590094D03*
X490711D03*
X500271Y1614292D03*
Y1602380D03*
X488211Y1614292D03*
Y1602380D03*
X496011D03*
Y1614292D03*
X497441Y1675383D03*
Y1679920D03*
Y1684454D03*
Y1689556D03*
Y1694093D03*
Y1698627D03*
Y1703729D03*
Y1708266D03*
Y1712800D03*
Y1726974D03*
Y1722440D03*
Y1717903D03*
X507978Y937896D03*
X509829Y947509D03*
X510262Y1057361D03*
X506562Y1063770D03*
X510262Y1076587D03*
X512111Y1073383D03*
X508411Y1066974D03*
X515811D03*
X508411Y1079791D03*
X515811Y1086200D03*
X507031Y1578182D03*
X514831D03*
X502771D03*
X507031Y1590094D03*
X514831D03*
X502771D03*
X512331Y1614292D03*
Y1602380D03*
X508071Y1614292D03*
Y1602380D03*
X513189Y1675383D03*
Y1679920D03*
X505315Y1679320D03*
X513189Y1684454D03*
Y1689556D03*
Y1694093D03*
Y1698627D03*
X505315Y1688391D03*
Y1693493D03*
Y1698030D03*
Y1683857D03*
X513189Y1703729D03*
Y1708266D03*
Y1712800D03*
X505315Y1707666D03*
Y1712203D03*
Y1702564D03*
X513189Y1726974D03*
Y1722440D03*
Y1717903D03*
X505315Y1730911D03*
Y1726377D03*
Y1721840D03*
Y1716737D03*
X521362Y1057361D03*
X525061Y1063770D03*
X532462D03*
X521362Y1076587D03*
X519512Y1073383D03*
X523211Y1066974D03*
X534311D03*
X531151Y1578182D03*
X519091D03*
X526891D03*
X531151Y1590094D03*
X519091D03*
X526891D03*
X532191Y1614292D03*
Y1602380D03*
X524391Y1614292D03*
Y1602380D03*
X520131D03*
Y1614292D03*
X528937Y1675383D03*
Y1679920D03*
X521063Y1679320D03*
X528937Y1684454D03*
Y1689556D03*
Y1694093D03*
Y1698627D03*
X521063Y1688391D03*
Y1693493D03*
Y1698030D03*
Y1683857D03*
X528937Y1703729D03*
Y1708266D03*
Y1712800D03*
X521063Y1707666D03*
Y1712203D03*
Y1702564D03*
X528937Y1726974D03*
Y1722440D03*
Y1717903D03*
X521063Y1730911D03*
Y1726377D03*
Y1721840D03*
Y1716737D03*
X543129Y928283D03*
X539429D03*
X537578Y925079D03*
X535729Y928283D03*
X548678Y925079D03*
X537578Y944304D03*
X548678D03*
X536161Y1057361D03*
X549422Y1064850D03*
X541711Y1073383D03*
X545411Y1066974D03*
X536161Y1076587D03*
X536162Y1070178D03*
X538011Y1073383D03*
X547262Y1070178D03*
X543211Y1578182D03*
X538951D03*
X543211Y1590094D03*
X538951D03*
X548511Y1614292D03*
Y1602380D03*
X536451D03*
Y1614292D03*
X544251Y1602380D03*
Y1614292D03*
X544685Y1675383D03*
Y1679920D03*
X536811Y1679320D03*
X544685Y1684454D03*
Y1689556D03*
Y1694093D03*
Y1698627D03*
X536811Y1688391D03*
Y1693493D03*
Y1698030D03*
Y1683857D03*
X544685Y1703729D03*
Y1708266D03*
Y1712800D03*
X536811Y1707666D03*
Y1712203D03*
Y1702564D03*
X544685Y1726974D03*
Y1722440D03*
Y1717903D03*
X536811Y1730911D03*
Y1726377D03*
Y1721840D03*
Y1716737D03*
X555271Y1578182D03*
X563071D03*
X551011D03*
X555271Y1590094D03*
X563071D03*
X551011D03*
X560571Y1602380D03*
X556311Y1614292D03*
Y1602380D03*
X552559Y1679320D03*
X564370Y1675383D03*
Y1679920D03*
X552559Y1688391D03*
Y1693493D03*
Y1698030D03*
Y1683857D03*
X564370Y1684454D03*
Y1689556D03*
Y1694093D03*
Y1698627D03*
X552559Y1707666D03*
Y1712203D03*
Y1702564D03*
X564370Y1703729D03*
Y1708266D03*
Y1712800D03*
X552559Y1730911D03*
Y1726377D03*
Y1721840D03*
Y1716737D03*
X564370Y1726974D03*
Y1722440D03*
Y1717903D03*
X579391Y1578182D03*
X567331D03*
X575131D03*
X579391Y1590094D03*
X567331D03*
X575131D03*
X580431Y1614292D03*
X572631D03*
Y1602380D03*
X568371D03*
Y1614292D03*
X580118Y1675383D03*
Y1679920D03*
X572244Y1679320D03*
X580118Y1684454D03*
Y1689556D03*
Y1694093D03*
Y1698627D03*
X572244Y1688391D03*
Y1693493D03*
Y1698030D03*
Y1683857D03*
X580118Y1703729D03*
Y1708266D03*
Y1712800D03*
X572244Y1707666D03*
Y1712203D03*
Y1702564D03*
X580118Y1726974D03*
Y1722440D03*
Y1717903D03*
X572244Y1730911D03*
Y1726377D03*
Y1721840D03*
Y1716737D03*
X599251Y1578182D03*
X591451D03*
X587191D03*
X599251Y1590094D03*
X591451D03*
X587191D03*
X596751Y1614292D03*
Y1602380D03*
X584691D03*
Y1614292D03*
X592491Y1602380D03*
Y1614292D03*
X595866Y1675383D03*
Y1679920D03*
X587992Y1679320D03*
X595866Y1684454D03*
Y1689556D03*
Y1694093D03*
Y1698627D03*
X587992Y1688391D03*
Y1693493D03*
Y1698030D03*
Y1683857D03*
X595866Y1703729D03*
Y1708266D03*
Y1712800D03*
X587992Y1707666D03*
Y1712203D03*
Y1702564D03*
X595866Y1726974D03*
Y1722440D03*
Y1717903D03*
X587992Y1730911D03*
Y1726377D03*
Y1721840D03*
Y1716737D03*
X615571Y1578182D03*
X603511D03*
X611311D03*
X615571Y1590094D03*
X603511D03*
X611311D03*
X608811Y1602380D03*
Y1614292D03*
X604551Y1602380D03*
Y1614292D03*
X611614Y1675383D03*
Y1679920D03*
X603740Y1679320D03*
X611614Y1684454D03*
Y1689556D03*
Y1694093D03*
Y1698627D03*
X603740Y1688391D03*
Y1693493D03*
Y1698030D03*
Y1683857D03*
X611614Y1703729D03*
Y1708266D03*
Y1712800D03*
X603740Y1707666D03*
Y1712203D03*
Y1702564D03*
X611614Y1726974D03*
Y1722440D03*
Y1717903D03*
X603740Y1730911D03*
Y1726377D03*
Y1721840D03*
Y1716737D03*
X629599Y770144D03*
X620899D03*
X629599Y783530D03*
X620899D03*
X629599Y776837D03*
X620899D03*
X620846Y800263D03*
X629599D03*
Y793570D03*
X620899D03*
Y820341D03*
X629599D03*
X620076Y813648D03*
X630593D03*
X619632Y806955D03*
X630792D03*
X620899Y830381D03*
X629599D03*
X620005Y850459D03*
X630754D03*
X620899Y843766D03*
X629599D03*
Y837074D03*
X620899D03*
Y867192D03*
X629599D03*
X620058Y857152D03*
X630481D03*
X620899Y880577D03*
X629599D03*
X620899Y873885D03*
X629599D03*
X630756Y893963D03*
X620899D03*
X629599Y887270D03*
X620899D03*
Y910696D03*
X629599D03*
Y917389D03*
X620899D03*
X629599Y904003D03*
X620899D03*
X630399Y930697D03*
X619905Y930774D03*
X620899Y924081D03*
X629599D03*
Y947507D03*
X620899D03*
X619964Y940814D03*
X630777D03*
X629599Y964239D03*
X620899D03*
X629599Y954200D03*
X620899D03*
Y977625D03*
X629599D03*
Y970932D03*
X620899D03*
Y991011D03*
X629599D03*
Y984318D03*
X620899D03*
Y1031168D03*
X629599D03*
X620899Y1017782D03*
X629599D03*
X620899Y1024475D03*
X629599D03*
X620899Y1044554D03*
X629599D03*
X620899Y1037861D03*
X629599D03*
X620899Y1057940D03*
X629599D03*
Y1051247D03*
X620899D03*
Y1078018D03*
X629599D03*
X630399Y1071326D03*
X619999D03*
X620899Y1064633D03*
X629599D03*
X620899Y1088058D03*
X629599D03*
Y1094751D03*
X620899D03*
Y1108137D03*
X629599D03*
Y1101444D03*
X620899D03*
X630363Y1124674D03*
X620369Y1124969D03*
X630399Y1114829D03*
X620099D03*
X620899Y1131562D03*
X629599D03*
Y1144948D03*
X620899D03*
X629599Y1138255D03*
X620899D03*
X620511Y1161680D03*
X629833Y1161581D03*
X629599Y1151641D03*
X620899D03*
X629599Y1175066D03*
X620899D03*
X629599Y1168373D03*
X620899D03*
X630623Y1188452D03*
X620899D03*
X629599Y1181759D03*
X620899D03*
X629599Y1205184D03*
X620899D03*
Y1198491D03*
X629599D03*
X620899Y1225263D03*
X629599D03*
Y1218570D03*
X620899D03*
X629599Y1211877D03*
X620899D03*
X629599Y1241995D03*
X620899D03*
X630922Y1235302D03*
X620036D03*
X620899Y1248688D03*
X629599D03*
X625246Y1273164D03*
X627646D03*
X627631Y1578182D03*
X623371D03*
X627631Y1590094D03*
X623371D03*
X628671Y1602380D03*
Y1614292D03*
X620871D03*
Y1602380D03*
X616611Y1614292D03*
Y1602380D03*
X619488Y1679320D03*
Y1688391D03*
Y1693493D03*
Y1698030D03*
Y1683857D03*
Y1707666D03*
Y1712203D03*
Y1702564D03*
Y1730911D03*
Y1726377D03*
Y1721840D03*
Y1716737D03*
X637041Y766798D03*
X645741D03*
Y773491D03*
X637041D03*
X645741Y780184D03*
X637041D03*
Y803609D03*
X645741D03*
X637041Y796916D03*
X645741D03*
Y790223D03*
X637041D03*
X636221Y810302D03*
X646844D03*
X646774Y816995D03*
X637041D03*
X645741Y833727D03*
X637041D03*
Y827034D03*
X645741D03*
X637041Y847113D03*
X645801D03*
X637041Y840420D03*
X645741D03*
X646819Y853806D03*
X636332Y853955D03*
X645918Y863845D03*
X636266D03*
X637041Y877231D03*
X645741D03*
X637041Y870538D03*
X645741D03*
Y883924D03*
X637041D03*
Y900656D03*
X645741D03*
X637041Y890617D03*
X645741D03*
X637041Y914042D03*
X645741D03*
Y907349D03*
X637041D03*
X646393Y927526D03*
X636026Y927428D03*
X645741Y920735D03*
X637041D03*
X645741Y944160D03*
X637041D03*
X636170Y937467D03*
X646703D03*
X645741Y960892D03*
X637041D03*
Y950853D03*
X645741D03*
X637041Y980971D03*
X645741D03*
X637041Y974278D03*
X645741D03*
X637041Y967585D03*
X645741D03*
X637041Y987664D03*
X645741D03*
X637041Y1027822D03*
X645741D03*
Y1017782D03*
X637041D03*
X645741Y1047900D03*
X637041D03*
Y1041207D03*
X645741D03*
X637041Y1034515D03*
X645741D03*
X637041Y1061286D03*
X645741D03*
Y1054593D03*
X637041D03*
X636141Y1074672D03*
X646541D03*
X645741Y1067979D03*
X636841D03*
X637041Y1091404D03*
X645741D03*
Y1084711D03*
X636241D03*
X645741Y1111483D03*
X637041D03*
X645741Y1098097D03*
X637041D03*
X645741Y1104790D03*
X637041D03*
Y1121522D03*
X645741D03*
X637041Y1128915D03*
X645741Y1128215D03*
X646584Y1135108D03*
X635744Y1134908D03*
X645741Y1141601D03*
X637041D03*
X645741Y1148294D03*
X637041D03*
X645741Y1158333D03*
X637041D03*
Y1171719D03*
X645741D03*
Y1165026D03*
X637041D03*
Y1185105D03*
X645741D03*
Y1178412D03*
X637041D03*
X645741Y1208530D03*
X637041D03*
X645741Y1201837D03*
X637041D03*
Y1195144D03*
X645741D03*
X636005Y1221916D03*
X646570D03*
X645741Y1215223D03*
X637041D03*
X645741Y1238648D03*
X637041D03*
X635995Y1231862D03*
X646539Y1231955D03*
X645741Y1245341D03*
X637041D03*
X634213Y1258679D03*
X642746Y1273364D03*
X639946D03*
X647491Y1578088D03*
X639691Y1578182D03*
X635431D03*
X647491Y1590094D03*
X639691D03*
X635431D03*
X644991Y1614292D03*
Y1602380D03*
X632931D03*
Y1614292D03*
X640731D03*
Y1602380D03*
X650599Y770144D03*
X659299D03*
X650599Y783530D03*
X659299D03*
X650599Y776837D03*
X659299D03*
Y800263D03*
X650599D03*
Y793570D03*
X659299D03*
Y806955D03*
X650599D03*
X660432Y813648D03*
X650599D03*
X660199Y820341D03*
X650599D03*
X659299Y830381D03*
X650599D03*
X659299Y850459D03*
X650599D03*
X659299Y843766D03*
X650599D03*
Y837074D03*
X659299D03*
Y857152D03*
X650599D03*
X649563Y867192D03*
X660299D03*
X659299Y873885D03*
X650599D03*
Y880577D03*
X659299D03*
X650599Y893963D03*
X659299D03*
X650599Y887270D03*
X659299D03*
Y917389D03*
X650599D03*
X659299Y910696D03*
X650599D03*
Y904003D03*
X659299D03*
X660504Y924081D03*
X650599D03*
X660174Y930774D03*
X649661D03*
X659299Y947507D03*
X650599D03*
X659299Y940814D03*
X650599D03*
X659299Y964239D03*
X650599D03*
Y954200D03*
X659299D03*
Y977625D03*
X650599D03*
X659299Y970932D03*
X650599D03*
X659299Y991011D03*
X650599D03*
X659299Y984318D03*
X650599D03*
X659299Y1031168D03*
X650599D03*
X659299Y1017782D03*
X650599D03*
X659299Y1024475D03*
X650599D03*
X659299Y1044554D03*
X650599D03*
X659299Y1037861D03*
X650599D03*
X659299Y1051247D03*
X650599D03*
Y1057940D03*
X659299D03*
X660099Y1078018D03*
X649799D03*
X659299Y1071326D03*
X650599D03*
X659299Y1064633D03*
X650599D03*
X659299Y1094751D03*
X650599D03*
X660099Y1088058D03*
X649799D03*
X650599Y1108137D03*
X659299D03*
X650599Y1101444D03*
X659299D03*
X660199Y1124869D03*
X649932Y1124640D03*
X659299Y1114829D03*
X650599D03*
X659299Y1130762D03*
X650599D03*
X659299Y1138255D03*
X650599D03*
X659299Y1144948D03*
X650599D03*
X659299Y1151641D03*
X650599D03*
Y1161680D03*
X659299D03*
X650599Y1175066D03*
X659299D03*
X650599Y1168373D03*
X659299D03*
X650599Y1188452D03*
X659299D03*
X650599Y1181759D03*
X659299D03*
X650599Y1205184D03*
X659299D03*
X650599Y1198491D03*
X659299D03*
X660070Y1225263D03*
X649913D03*
X659299Y1218570D03*
X650599D03*
X659299Y1211877D03*
X650599D03*
X659299Y1241995D03*
X650599D03*
X660234Y1235302D03*
X649701D03*
X650599Y1248688D03*
X659299D03*
X659546Y1257664D03*
X656446Y1273364D03*
X653646D03*
X651751Y1578182D03*
X659551D03*
X651751Y1590094D03*
X659551D03*
X657051Y1602380D03*
Y1614292D03*
X652791Y1602286D03*
Y1614292D03*
X680299Y770144D03*
X675441Y766798D03*
X666741D03*
X680299Y783530D03*
Y776837D03*
X666741Y773491D03*
X675441D03*
X666741Y780184D03*
X675441D03*
Y803609D03*
X666741D03*
X680299Y800263D03*
Y793570D03*
X666741Y796916D03*
X675441D03*
X666741Y790223D03*
X675441D03*
X676403Y816995D03*
X665803D03*
X675441Y810302D03*
X666741D03*
X680299Y820341D03*
Y813648D03*
Y806955D03*
X675441Y833727D03*
X666741D03*
X676625Y827034D03*
X665876D03*
X680299Y830381D03*
X675441Y847113D03*
X666741D03*
X680299Y850459D03*
Y843766D03*
Y837074D03*
X666741Y840420D03*
X675441D03*
X676417Y853806D03*
X665890D03*
X680299Y867192D03*
Y857152D03*
X665916Y863845D03*
X676600D03*
X675441Y877231D03*
X666741D03*
X675441Y870538D03*
X666741D03*
Y883924D03*
X675441D03*
X680299Y880577D03*
Y873885D03*
X666741Y900656D03*
X675441D03*
X680299Y893963D03*
Y887270D03*
X666741Y890617D03*
X675441D03*
Y914042D03*
X666741D03*
X680299Y917389D03*
Y910696D03*
Y904003D03*
X666741Y907349D03*
X675441D03*
X676488Y927428D03*
X665896D03*
X675441Y920735D03*
X666741D03*
X680299Y930774D03*
Y924081D03*
X675441Y944160D03*
X666741D03*
X676359Y937467D03*
X665923D03*
X680299Y947507D03*
Y940814D03*
Y964239D03*
X675441Y960892D03*
X666741D03*
X680299Y954200D03*
X666741Y950853D03*
X675441D03*
Y980971D03*
X666741D03*
X680299Y970932D03*
X675441Y974278D03*
X666741D03*
X675441Y967585D03*
X666741D03*
X680299Y977625D03*
X675441Y987664D03*
X666741D03*
X680299Y991011D03*
Y984318D03*
Y1031168D03*
Y1024475D03*
X675441Y1027822D03*
X666741D03*
X675441Y1017782D03*
X666741D03*
X680299D03*
X675441Y1047900D03*
X666741D03*
X680299Y1037861D03*
X675441Y1041207D03*
X666741D03*
X675441Y1034515D03*
X666741D03*
X680299Y1044554D03*
Y1057940D03*
Y1051247D03*
X675441Y1054593D03*
X666741D03*
Y1061286D03*
X675441D03*
X676341Y1074672D03*
X665841D03*
X675441Y1067979D03*
X666741D03*
X680299Y1078018D03*
Y1071326D03*
Y1064633D03*
X675441Y1091404D03*
X666741D03*
X676241Y1084711D03*
X665941D03*
X680299Y1094751D03*
Y1088058D03*
X666741Y1111483D03*
X675441D03*
X680299Y1108137D03*
Y1101444D03*
X666741Y1104790D03*
X675441D03*
X666741Y1098097D03*
X675441D03*
X666741Y1128215D03*
X675441D03*
X680299Y1124869D03*
Y1114829D03*
X666741Y1121522D03*
X675441D03*
X680299Y1144948D03*
Y1138255D03*
Y1131562D03*
X666741Y1141601D03*
X675441D03*
X666741Y1134908D03*
X675441D03*
X676652Y1148294D03*
X665602D03*
X676241Y1158333D03*
X665941D03*
X680299Y1161680D03*
Y1151641D03*
X675441Y1165026D03*
X666741D03*
X680299Y1175066D03*
Y1168373D03*
X666741Y1171719D03*
X675441D03*
X680299Y1188452D03*
Y1181759D03*
X666741Y1185105D03*
X675441D03*
X666741Y1178412D03*
X675441D03*
X680299Y1205184D03*
Y1198491D03*
X666741Y1208530D03*
X675441D03*
X666741Y1201837D03*
X675441D03*
X666741Y1195144D03*
X675441D03*
X680299Y1218570D03*
Y1225263D03*
X676448Y1221916D03*
X665651D03*
X675441Y1215223D03*
X666741D03*
X680299Y1211877D03*
X675441Y1238648D03*
X666741D03*
X676462Y1231955D03*
X665912D03*
X680299Y1241995D03*
Y1235302D03*
X675441Y1245341D03*
X666741D03*
X676046Y1257964D03*
X680299Y1248688D03*
X672446Y1273364D03*
X669646D03*
X664851Y1602380D03*
Y1614292D03*
X696441Y766798D03*
X688999Y770144D03*
X696441Y773491D03*
Y780184D03*
X688999Y783530D03*
Y776837D03*
X696441Y803609D03*
Y796916D03*
Y790223D03*
X688999Y800263D03*
Y793570D03*
X696441Y816995D03*
Y810302D03*
X689888Y820341D03*
X688999Y813648D03*
Y806955D03*
X696441Y833727D03*
Y827034D03*
X688999Y830381D03*
X696441Y847113D03*
X688999Y850459D03*
X696441Y840420D03*
X688999Y843766D03*
Y837074D03*
X696441Y863845D03*
Y853806D03*
X688999Y867192D03*
X689896Y857152D03*
X696441Y883924D03*
Y877231D03*
Y870538D03*
X688999Y880577D03*
Y873885D03*
X696441Y900656D03*
Y890617D03*
X688999Y893963D03*
Y887270D03*
X696441Y914042D03*
Y907349D03*
X688999Y917389D03*
Y910696D03*
Y904003D03*
X696441Y927428D03*
Y920735D03*
X690104Y930774D03*
X688999Y924081D03*
X696441Y944160D03*
Y937467D03*
X688999Y947507D03*
Y940814D03*
X696441Y960892D03*
Y950853D03*
X688999Y964239D03*
Y954200D03*
X696441Y980971D03*
Y974278D03*
Y967585D03*
X688999Y970932D03*
Y977625D03*
X696441Y987664D03*
X688999Y991011D03*
Y984318D03*
X696441Y1027822D03*
Y1017782D03*
X688999Y1031168D03*
Y1024475D03*
Y1017782D03*
X696441Y1047900D03*
Y1041207D03*
Y1034515D03*
X688999Y1037861D03*
Y1044554D03*
X696441Y1054593D03*
Y1061286D03*
X688999Y1057940D03*
X696441Y1074672D03*
Y1067979D03*
X688999Y1077118D03*
Y1071326D03*
Y1064633D03*
X696441Y1091404D03*
Y1084711D03*
X688999Y1094751D03*
Y1088058D03*
X696441Y1111483D03*
Y1104790D03*
Y1098097D03*
X688999Y1108137D03*
Y1101444D03*
X696441Y1128215D03*
Y1121522D03*
X688999Y1124869D03*
Y1114829D03*
X696441Y1141601D03*
Y1134908D03*
X688999Y1144948D03*
Y1138255D03*
Y1131562D03*
X696441Y1158333D03*
Y1148294D03*
X688999Y1161680D03*
X689999Y1151641D03*
X696441Y1171719D03*
Y1165026D03*
X688999Y1175066D03*
Y1168373D03*
X696441Y1185105D03*
Y1178412D03*
X688999Y1188452D03*
Y1181759D03*
X696441Y1208530D03*
Y1201837D03*
Y1195144D03*
X688999Y1205184D03*
Y1198491D03*
X696441Y1221916D03*
Y1215223D03*
X688999Y1218570D03*
X689799Y1225263D03*
X688999Y1211877D03*
X696441Y1238648D03*
Y1231955D03*
X688999Y1241995D03*
Y1235302D03*
X688916Y1256964D03*
X696441Y1245341D03*
X688999Y1248688D03*
X686146Y1273364D03*
X683346D03*
X709999Y770144D03*
X705141Y766798D03*
X709999Y783530D03*
Y776837D03*
X705141Y773491D03*
Y780184D03*
X709999Y800263D03*
Y793570D03*
X705141Y803609D03*
Y796916D03*
Y790223D03*
X709999Y820341D03*
Y813648D03*
Y806955D03*
X705141Y816995D03*
Y810302D03*
X709999Y830381D03*
X705141Y833727D03*
Y827034D03*
Y847113D03*
X709999Y850459D03*
Y843766D03*
Y837074D03*
X705141Y840420D03*
Y863845D03*
Y853806D03*
X709999Y867192D03*
Y857152D03*
X705141Y883924D03*
Y877231D03*
Y870538D03*
X709999Y880577D03*
Y873885D03*
X705141Y900656D03*
Y890617D03*
X709999Y893963D03*
Y887270D03*
X705141Y914042D03*
Y907349D03*
X709999Y917389D03*
Y910696D03*
Y904003D03*
X705141Y927428D03*
Y920735D03*
X709999Y930774D03*
Y924081D03*
X705141Y944160D03*
Y937467D03*
X709999Y947507D03*
Y940814D03*
X705141Y960892D03*
Y950853D03*
X709999Y964239D03*
Y954200D03*
X705141Y980971D03*
Y974278D03*
Y967585D03*
X709999Y977625D03*
Y970932D03*
X705141Y987664D03*
X709999Y991011D03*
Y984318D03*
X705141Y1027822D03*
Y1017782D03*
X709999Y1031168D03*
Y1024475D03*
Y1017782D03*
X705141Y1047900D03*
Y1041207D03*
Y1034515D03*
X709999Y1044554D03*
Y1037861D03*
X705141Y1054593D03*
Y1061286D03*
X709999Y1057940D03*
Y1051247D03*
X705141Y1074672D03*
Y1067979D03*
X709999Y1078018D03*
Y1071326D03*
Y1064633D03*
X705141Y1091404D03*
Y1084711D03*
X709999Y1094751D03*
Y1088058D03*
X705141Y1111483D03*
Y1104790D03*
Y1098097D03*
X709999Y1108137D03*
Y1101444D03*
X705141Y1128215D03*
Y1121522D03*
X709999Y1124869D03*
Y1114829D03*
X705141Y1141601D03*
Y1134908D03*
X709999Y1144948D03*
Y1138255D03*
Y1131562D03*
X705141Y1158333D03*
Y1148294D03*
X709999Y1161680D03*
Y1151641D03*
X705141Y1171719D03*
Y1165026D03*
X709999Y1175066D03*
Y1168373D03*
X705141Y1185105D03*
Y1178412D03*
X709999Y1188452D03*
Y1181759D03*
X705141Y1208530D03*
Y1201837D03*
Y1195144D03*
X709999Y1205184D03*
Y1198491D03*
X705141Y1221916D03*
Y1215223D03*
X709999Y1225263D03*
Y1218570D03*
Y1211877D03*
X705141Y1238648D03*
Y1231955D03*
X709999Y1241995D03*
Y1235302D03*
X705141Y1245341D03*
X709999Y1248688D03*
X713046Y1273364D03*
X702146D03*
X699346D03*
X726141Y766798D03*
X718699Y770144D03*
X726141Y773491D03*
Y780184D03*
X718699Y783530D03*
Y776837D03*
X726141Y803609D03*
Y796916D03*
Y790223D03*
X718699Y800263D03*
Y793570D03*
X726141Y816995D03*
Y810302D03*
X718699Y820341D03*
Y813648D03*
Y806955D03*
X726141Y833727D03*
Y827034D03*
X718699Y830381D03*
X726141Y847113D03*
Y840420D03*
X718699Y850459D03*
Y843766D03*
Y837074D03*
X726141Y863845D03*
Y853806D03*
X718699Y867192D03*
Y857152D03*
X726141Y883924D03*
Y877231D03*
Y870538D03*
X718699Y880577D03*
Y873885D03*
X726141Y900656D03*
Y890617D03*
X718699Y893963D03*
Y887270D03*
X726141Y914042D03*
Y907349D03*
X718699Y917389D03*
Y910696D03*
Y904003D03*
X726141Y927428D03*
Y920735D03*
X718699Y930774D03*
Y924081D03*
X726141Y944160D03*
Y937467D03*
X718699Y947507D03*
Y940814D03*
X726141Y960892D03*
Y950853D03*
X718699Y964239D03*
Y954200D03*
X726141Y980971D03*
Y974278D03*
Y967585D03*
X718699Y977625D03*
Y970932D03*
X726141Y987664D03*
X718699Y991011D03*
Y984318D03*
X726141Y1027822D03*
Y1017782D03*
X718699Y1031168D03*
Y1024475D03*
Y1017782D03*
X726141Y1047900D03*
Y1041207D03*
Y1034515D03*
X718699Y1044554D03*
Y1037861D03*
X726141Y1061286D03*
Y1054593D03*
X718699Y1057940D03*
Y1051247D03*
X726141Y1074672D03*
Y1067979D03*
X718699Y1078018D03*
Y1071326D03*
Y1064633D03*
X726141Y1091404D03*
Y1084711D03*
X718699Y1094751D03*
Y1088058D03*
X726141Y1111483D03*
Y1104790D03*
Y1098097D03*
X718699Y1108137D03*
Y1101444D03*
X726141Y1128215D03*
Y1121522D03*
X718699Y1124869D03*
Y1114829D03*
X726141Y1141601D03*
Y1134908D03*
X718699Y1144948D03*
Y1138255D03*
Y1131562D03*
X726141Y1158333D03*
Y1148294D03*
X718699Y1161680D03*
Y1151641D03*
X726141Y1171719D03*
Y1165026D03*
X718699Y1175066D03*
Y1168373D03*
X726141Y1185105D03*
Y1178412D03*
X718699Y1188452D03*
Y1181759D03*
X726141Y1208530D03*
Y1201837D03*
Y1195144D03*
X718699Y1205184D03*
Y1198491D03*
X726141Y1221916D03*
Y1215223D03*
X718699Y1225263D03*
Y1218570D03*
Y1211877D03*
X726141Y1238648D03*
Y1231955D03*
X718699Y1241995D03*
Y1235302D03*
X726141Y1245341D03*
X719046Y1257064D03*
X718699Y1248688D03*
X729046Y1273364D03*
X715846D03*
X739699Y770144D03*
X734841Y766798D03*
X739699Y783530D03*
Y776837D03*
X734841Y773491D03*
Y780184D03*
X739699Y800263D03*
Y793570D03*
X734841Y803609D03*
Y796916D03*
Y790223D03*
X739699Y820341D03*
Y813648D03*
Y806955D03*
X734841Y816995D03*
Y810302D03*
X739699Y830381D03*
X734841Y833727D03*
Y827034D03*
X739699Y850459D03*
Y843766D03*
Y837074D03*
X734841Y847113D03*
Y840420D03*
X739699Y867192D03*
Y857152D03*
X734841Y863845D03*
Y853806D03*
X739699Y880577D03*
Y873885D03*
X734841Y883924D03*
Y877231D03*
Y870538D03*
X739699Y893963D03*
Y887270D03*
X734841Y900656D03*
Y890617D03*
X739699Y917389D03*
Y910696D03*
Y904003D03*
X734841Y914042D03*
Y907349D03*
X739699Y930774D03*
Y924081D03*
X734841Y927428D03*
Y920735D03*
X739699Y947507D03*
Y940814D03*
X734841Y944160D03*
Y937467D03*
X739699Y964239D03*
Y954200D03*
X734841Y960892D03*
Y950853D03*
X739699Y977625D03*
Y970932D03*
X734841Y980971D03*
Y974278D03*
Y967585D03*
X739699Y991011D03*
Y984318D03*
X734841Y987664D03*
X739699Y1031168D03*
Y1024475D03*
Y1017782D03*
X734841Y1027822D03*
Y1017782D03*
X739699Y1044554D03*
Y1037861D03*
X734841Y1047900D03*
Y1041207D03*
Y1034515D03*
X739699Y1057940D03*
Y1051247D03*
X734841Y1061286D03*
Y1054593D03*
X739699Y1078018D03*
Y1071326D03*
Y1064633D03*
X734841Y1074672D03*
Y1067979D03*
X739699Y1094751D03*
Y1088058D03*
X734841Y1091404D03*
Y1084711D03*
X739699Y1108137D03*
Y1101444D03*
X734841Y1111483D03*
Y1104790D03*
Y1098097D03*
X739699Y1124869D03*
Y1114829D03*
X734841Y1128215D03*
Y1121522D03*
X739699Y1144948D03*
Y1138255D03*
Y1131562D03*
X734841Y1141601D03*
Y1134908D03*
X739699Y1161680D03*
Y1151641D03*
X734841Y1158333D03*
Y1148294D03*
X739699Y1175066D03*
Y1168373D03*
X734841Y1171719D03*
Y1165026D03*
X739699Y1188452D03*
Y1181759D03*
X734841Y1185105D03*
Y1178412D03*
X739699Y1205184D03*
Y1198491D03*
X734841Y1208530D03*
Y1201837D03*
Y1195144D03*
X739699Y1225263D03*
Y1218570D03*
Y1211877D03*
X734841Y1221916D03*
Y1215223D03*
X739699Y1241995D03*
Y1235302D03*
X734841Y1238648D03*
Y1231955D03*
X739699Y1248688D03*
X734841Y1245341D03*
X745546Y1273364D03*
X742746D03*
X731372Y1273464D03*
X755841Y766798D03*
X748399Y770144D03*
X755841Y780184D03*
Y773491D03*
X748399Y783530D03*
Y776837D03*
X755841Y803609D03*
Y796916D03*
Y790223D03*
X748399Y800263D03*
Y793570D03*
X755841Y816995D03*
Y810302D03*
X748399Y820341D03*
Y813648D03*
Y806955D03*
X755841Y833727D03*
Y827034D03*
X748399Y830381D03*
X755841Y847113D03*
Y840420D03*
X748399Y850459D03*
Y843766D03*
Y837074D03*
X755841Y863845D03*
Y853806D03*
X748399Y867192D03*
Y857152D03*
X755841Y883924D03*
Y877231D03*
Y870538D03*
X748399Y880577D03*
Y873885D03*
X755841Y900656D03*
Y890617D03*
X748399Y893963D03*
Y887270D03*
X755841Y914042D03*
Y907349D03*
X748399Y917389D03*
Y910696D03*
Y904003D03*
X755841Y927428D03*
Y920735D03*
X748399Y930774D03*
Y924081D03*
X755841Y944160D03*
Y937467D03*
X748399Y947507D03*
Y940814D03*
X755841Y960892D03*
Y950853D03*
X748399Y964239D03*
Y954200D03*
X755841Y980971D03*
Y974278D03*
Y967585D03*
X748399Y977625D03*
Y970932D03*
X755841Y987664D03*
X748399Y991011D03*
Y984318D03*
X755841Y1027822D03*
Y1017782D03*
X748399Y1031168D03*
Y1024475D03*
Y1017782D03*
X755841Y1047900D03*
Y1041207D03*
Y1034515D03*
X748399Y1044554D03*
Y1037861D03*
X755841Y1054593D03*
Y1061286D03*
X748399Y1057940D03*
X755841Y1067979D03*
Y1074672D03*
X748399Y1078018D03*
Y1071326D03*
Y1064633D03*
X755841Y1084711D03*
Y1091404D03*
X748399Y1094751D03*
Y1088058D03*
X755841Y1111483D03*
Y1104790D03*
Y1098097D03*
X748399Y1108137D03*
Y1101444D03*
X755841Y1128215D03*
Y1121522D03*
X748399Y1124869D03*
Y1114829D03*
X755841Y1141601D03*
Y1134908D03*
X748399Y1144948D03*
Y1138255D03*
Y1131562D03*
X755841Y1158333D03*
Y1148294D03*
X748399Y1161680D03*
Y1151641D03*
X755841Y1171719D03*
Y1165026D03*
X748399Y1175066D03*
Y1168373D03*
X755841Y1185105D03*
Y1178412D03*
X748399Y1188452D03*
Y1181759D03*
X755841Y1208530D03*
Y1201837D03*
Y1195144D03*
X748399Y1205184D03*
Y1198491D03*
X755841Y1221916D03*
Y1215223D03*
X748399Y1225263D03*
Y1218570D03*
Y1211877D03*
X755841Y1238648D03*
Y1231955D03*
X748399Y1241995D03*
Y1235302D03*
X755841Y1245341D03*
X748283Y1256964D03*
X748399Y1248688D03*
X758746Y1273364D03*
X761546D03*
X769399Y770144D03*
X778099D03*
X764541Y766798D03*
X769399Y783530D03*
X778099D03*
X769399Y776837D03*
X778099D03*
X764541Y780184D03*
Y773491D03*
X769399Y800263D03*
X778099D03*
X769399Y793570D03*
X778099D03*
X764541Y803609D03*
Y796916D03*
Y790223D03*
X769399Y820341D03*
X778099D03*
X769399Y813648D03*
X778099D03*
X769399Y806955D03*
X778099D03*
X764541Y816995D03*
Y810302D03*
X769399Y830381D03*
X778099D03*
X764541Y833727D03*
Y827034D03*
X769399Y850459D03*
X778099D03*
Y843766D03*
X769399D03*
Y837074D03*
X778099D03*
X764541Y847113D03*
Y840420D03*
X778099Y867192D03*
X769399D03*
Y857152D03*
X778099D03*
X764541Y863845D03*
Y853806D03*
X769399Y880577D03*
X778099D03*
X769399Y873885D03*
X778099D03*
X764541Y883924D03*
Y877231D03*
Y870538D03*
X778099Y893963D03*
X769399D03*
Y887270D03*
X778099D03*
X764541Y900656D03*
Y890617D03*
X769399Y917389D03*
X778099D03*
X769399Y910696D03*
X778099D03*
X769399Y904003D03*
X778099D03*
X764541Y914042D03*
Y907349D03*
X769399Y930774D03*
X778099D03*
X769399Y924081D03*
X778099D03*
X764541Y927428D03*
Y920735D03*
X769399Y947507D03*
X778099D03*
X769399Y940814D03*
X778099D03*
X764541Y944160D03*
Y937467D03*
X769399Y964239D03*
X778099D03*
X769399Y954200D03*
X778099D03*
X764541Y960892D03*
Y950853D03*
X769399Y977625D03*
X778099D03*
X769399Y970932D03*
X778099D03*
X764541Y980971D03*
Y974278D03*
Y967585D03*
X769399Y991011D03*
X778099D03*
X769399Y984318D03*
X778099D03*
X764541Y987664D03*
X769399Y1031168D03*
X778099D03*
X769399Y1024475D03*
X778099D03*
X769399Y1017782D03*
X778099D03*
X764541Y1027822D03*
Y1017782D03*
X778099Y1044554D03*
X769399D03*
Y1037861D03*
X778099D03*
X764541Y1047900D03*
Y1041207D03*
Y1034515D03*
X769399Y1057940D03*
X778099D03*
X769399Y1051247D03*
X778099D03*
X764541Y1054593D03*
Y1061286D03*
X778099Y1078018D03*
X769399D03*
X778099Y1071326D03*
X769399D03*
Y1064633D03*
X778099D03*
X764541Y1067979D03*
Y1074672D03*
X778099Y1094751D03*
X769399D03*
X778099Y1088058D03*
X769399D03*
X764541Y1084711D03*
Y1091404D03*
X778099Y1108137D03*
X769399D03*
X778099Y1101444D03*
X769399D03*
X764541Y1111483D03*
Y1104790D03*
Y1098097D03*
X778099Y1124869D03*
X769399D03*
X778099Y1114829D03*
X769399D03*
X764541Y1128215D03*
Y1121522D03*
X778099Y1144948D03*
X769399D03*
X778099Y1138255D03*
X769399D03*
X778099Y1131562D03*
X769399D03*
X764541Y1141601D03*
Y1134908D03*
X778099Y1161680D03*
X769399D03*
X778099Y1151641D03*
X769399D03*
X764541Y1158333D03*
Y1148294D03*
X778099Y1175066D03*
X769399D03*
X778099Y1168373D03*
X769399D03*
X764541Y1171719D03*
Y1165026D03*
X778099Y1188452D03*
X769399D03*
X778099Y1181759D03*
X769399D03*
X764541Y1185105D03*
Y1178412D03*
X769399Y1205184D03*
X778099D03*
Y1198491D03*
X769399D03*
X764541Y1208530D03*
Y1201837D03*
Y1195144D03*
X778099Y1225263D03*
X769399D03*
X778099Y1218570D03*
X769399D03*
Y1211877D03*
X778099D03*
X764541Y1221916D03*
Y1215223D03*
X778099Y1241995D03*
X769399D03*
X778099Y1235302D03*
X769399D03*
X764541Y1238648D03*
Y1231955D03*
X778346Y1257264D03*
X778099Y1248688D03*
X769399D03*
X764541Y1245341D03*
X772446Y1273364D03*
X775246D03*
X785541Y766798D03*
X794241D03*
X785541Y773491D03*
X794241D03*
X785541Y780184D03*
X794241D03*
X785541Y803609D03*
X794241D03*
X785541Y790223D03*
X794241D03*
X785541Y796916D03*
X794241D03*
X785541Y816995D03*
X794241D03*
X785541Y810302D03*
X794241D03*
X785541Y833727D03*
X794241D03*
X785541Y827034D03*
X794241D03*
X785541Y840420D03*
X794241D03*
X785541Y847113D03*
X794241D03*
X785541Y853806D03*
X794241D03*
X785541Y863845D03*
X794241D03*
X785541Y883924D03*
X794241D03*
X785541Y870538D03*
X794241D03*
X785541Y877231D03*
X794241D03*
X785541Y900656D03*
X794241D03*
X785541Y890617D03*
X794241D03*
X785541Y907349D03*
X794241D03*
X785541Y914042D03*
X794241D03*
X785541Y920735D03*
X794241D03*
X785541Y927428D03*
X794241D03*
X785541Y937467D03*
X794241D03*
X785541Y944160D03*
X794241D03*
X785541Y960892D03*
X794241D03*
X785541Y950853D03*
X794241D03*
X785541Y980971D03*
X794241D03*
X785541Y974278D03*
X794241D03*
X785541Y967585D03*
X794241D03*
X785541Y987664D03*
X794241D03*
X785541Y1027822D03*
X794241D03*
X785541Y1017782D03*
X794241D03*
X785541Y1047900D03*
X794241D03*
X785541Y1041207D03*
X794241D03*
X785541Y1034515D03*
X794241D03*
X785541Y1054593D03*
X794241D03*
X785541Y1061286D03*
X794241D03*
X785541Y1074672D03*
X794241D03*
X785541Y1067979D03*
X794241D03*
X785541Y1091404D03*
X794241D03*
X785541Y1084711D03*
X794241D03*
X785541Y1111483D03*
X794241D03*
X785541Y1104790D03*
X794241D03*
X785541Y1098097D03*
X794241D03*
X785541Y1128215D03*
X794241D03*
X785541Y1121522D03*
X794241D03*
X785541Y1141601D03*
X794241D03*
X785541Y1134908D03*
X794241D03*
X785541Y1158333D03*
X794241D03*
X785541Y1148294D03*
X794241D03*
X785541Y1171719D03*
X794241D03*
X785541Y1165026D03*
X794241D03*
X785541Y1178412D03*
X794241D03*
X785541Y1185105D03*
X794241D03*
X785541Y1208530D03*
X794241D03*
X785541Y1195144D03*
X794241D03*
X785541Y1201837D03*
X794241D03*
X785541Y1221916D03*
X794241D03*
X785541Y1215223D03*
X794241D03*
X785541Y1238648D03*
X794241D03*
X785541Y1231955D03*
X794241D03*
X785541Y1245341D03*
X794241D03*
X788446Y1273364D03*
X791246D03*
X799099Y770144D03*
X807799D03*
X799099Y783530D03*
X807799D03*
X799099Y776837D03*
X807799D03*
X799099Y800263D03*
X807799D03*
X799099Y793570D03*
X807799D03*
X799099Y820341D03*
X807799D03*
X799099Y806955D03*
X807799D03*
X799099Y813648D03*
X807799D03*
X799099Y830381D03*
X807799D03*
X799099Y850459D03*
X807799D03*
X799099Y837074D03*
X807799D03*
X799099Y843766D03*
X807799D03*
X799099Y867192D03*
X807799D03*
X799099Y857152D03*
X807799D03*
X799099Y873885D03*
X807799D03*
X799099Y880577D03*
X807799D03*
X799099Y887270D03*
X807799D03*
X799099Y893963D03*
X807799D03*
X799099Y917389D03*
X807799D03*
X799099Y904003D03*
X807799D03*
X799099Y910696D03*
X807799D03*
X799099Y930774D03*
X807799D03*
X799099Y924081D03*
X807799D03*
X799099Y947507D03*
X807799D03*
X799099Y940814D03*
X807799D03*
X799099Y964239D03*
X807799D03*
X799099Y954200D03*
X807799D03*
X799099Y970932D03*
X807799D03*
X799099Y977625D03*
X807799D03*
X799099Y991011D03*
X807799D03*
X799099Y984318D03*
X807799D03*
X799099Y1031168D03*
X807799D03*
X799099Y1024475D03*
X807799D03*
X799099Y1017782D03*
X807799D03*
X799099Y1037861D03*
X807799D03*
X799099Y1044554D03*
X807799D03*
X799099Y1057940D03*
X807799D03*
X799099Y1051247D03*
X807799D03*
X799099Y1078018D03*
X807799D03*
X799099Y1071326D03*
X807799D03*
X799099Y1064633D03*
X807799D03*
X799099Y1094751D03*
X807799D03*
X799099Y1088058D03*
X807799D03*
X799099Y1108137D03*
X807799D03*
X799099Y1101444D03*
X807799D03*
X799099Y1124869D03*
X807799D03*
X799099Y1114829D03*
X807799D03*
X799099Y1144948D03*
X807799D03*
X799099Y1138255D03*
X807799D03*
X799099Y1131562D03*
X807799D03*
X799099Y1161680D03*
X807799D03*
X799099Y1151641D03*
X807799D03*
X799099Y1175066D03*
X807799D03*
X799099Y1168373D03*
X807799D03*
X799099Y1188452D03*
X807799D03*
X799099Y1181759D03*
X807799D03*
X799099Y1205184D03*
X807799D03*
X799099Y1198491D03*
X807799D03*
X799099Y1225263D03*
X807799D03*
X799099Y1211877D03*
X807799D03*
X799099Y1218570D03*
X807799D03*
X799099Y1241995D03*
X807799D03*
X799099Y1235302D03*
X807799D03*
X799099Y1248688D03*
X807799D03*
X808046Y1257664D03*
X804946Y1273364D03*
X802146D03*
X815241Y766798D03*
X823941D03*
X815241Y773491D03*
X823941D03*
X815241Y780184D03*
X823941D03*
X815241Y803609D03*
X823941D03*
X815241Y790223D03*
X823941D03*
X815241Y796916D03*
X823941D03*
X815241Y816995D03*
X823941D03*
X815241Y810302D03*
X823941D03*
X815241Y833727D03*
X823941D03*
X815241Y827034D03*
X823941D03*
X815241Y840420D03*
X823941D03*
X815241Y847113D03*
X823941D03*
X815241Y853806D03*
X823941D03*
X815241Y863845D03*
X823941D03*
X815241Y883924D03*
X823941D03*
X815241Y870538D03*
X823941D03*
X815241Y877231D03*
X823941D03*
X815241Y900656D03*
X823941D03*
X815241Y890617D03*
X823941D03*
X815241Y907349D03*
X823941D03*
X815241Y914042D03*
X823941D03*
X815241Y920735D03*
X823941D03*
X815241Y927428D03*
X823941D03*
X815241Y937467D03*
X823941D03*
X815241Y944160D03*
X823941D03*
X815241Y960892D03*
X823941D03*
X815241Y950853D03*
X823941D03*
X815241Y980971D03*
X823941D03*
X815241Y974278D03*
X823941D03*
X815241Y967585D03*
X823941D03*
X815241Y987664D03*
X823941D03*
X815241Y1027822D03*
X823941D03*
X815241Y1017782D03*
X823941D03*
X815241Y1047900D03*
X823941D03*
X815241Y1041207D03*
X823941D03*
X815241Y1034515D03*
X823941D03*
X815241Y1054593D03*
X823941D03*
X815241Y1061286D03*
X823941D03*
X815241Y1074672D03*
X823941D03*
X815241Y1067979D03*
X823941D03*
X815241Y1091404D03*
X823941D03*
X815241Y1084711D03*
X823941D03*
X815241Y1111483D03*
X823941D03*
X815241Y1104790D03*
X823941D03*
X815241Y1098097D03*
X823941D03*
X815241Y1128215D03*
X823941D03*
X815241Y1121522D03*
X823941D03*
X815241Y1141601D03*
X823941D03*
X815241Y1134908D03*
X823941D03*
X815241Y1158333D03*
X823941D03*
X815241Y1148294D03*
X823941D03*
X815241Y1171719D03*
X823941D03*
X815241Y1165026D03*
X823941D03*
X815241Y1178412D03*
X823941D03*
X815241Y1185105D03*
X823941D03*
X815241Y1208530D03*
X823941D03*
X815241Y1195144D03*
X823941D03*
X815241Y1201837D03*
X823941D03*
X815241Y1221916D03*
X823941D03*
X815241Y1215223D03*
X823941D03*
X815241Y1238648D03*
X823941D03*
X815241Y1231955D03*
X823941D03*
X815241Y1245341D03*
X823941D03*
X820946Y1273364D03*
X818146D03*
X828799Y770144D03*
X837499D03*
X828799Y783530D03*
X837499D03*
X828799Y776837D03*
X837499D03*
Y800263D03*
X828799D03*
X837499Y793570D03*
X828799D03*
Y820341D03*
X837499D03*
X828799Y813648D03*
X837499D03*
X828799Y806955D03*
X837499D03*
X828799Y830381D03*
X837499D03*
X828799Y850459D03*
X837499D03*
X828799Y843766D03*
X837499D03*
X828799Y837074D03*
X837499D03*
X828799Y867192D03*
X837499D03*
X828799Y857152D03*
X837499D03*
X828799Y880577D03*
X837499D03*
X828799Y873885D03*
X837499D03*
X828799Y893963D03*
X837499D03*
X828799Y887270D03*
X837499D03*
X828799Y917389D03*
X837499D03*
Y904003D03*
X828799D03*
X837499Y910696D03*
X828799D03*
Y930774D03*
X837499D03*
X828799Y924081D03*
X837499D03*
X828799Y947507D03*
X837499D03*
X828799Y940814D03*
X837499D03*
X828799Y964239D03*
X837499D03*
X828799Y954200D03*
X837499D03*
X828799Y977625D03*
X837499D03*
X828799Y970932D03*
X837499D03*
X828799Y991011D03*
X837499D03*
X828799Y984318D03*
X837499D03*
X828799Y1031168D03*
X837499D03*
X828799Y1024475D03*
X837499D03*
X828799Y1017782D03*
X837499D03*
X828799Y1044554D03*
X837499D03*
X828799Y1037861D03*
X837499D03*
X828799Y1057940D03*
X837499D03*
X828799Y1051247D03*
X837499D03*
X828799Y1078018D03*
X837499D03*
X828799Y1071326D03*
X837499D03*
X828799Y1064633D03*
X837499D03*
X828799Y1094751D03*
X837499D03*
Y1088058D03*
X828799D03*
X837499Y1108137D03*
X828799D03*
Y1101444D03*
X837499D03*
Y1124869D03*
X828799D03*
X837499Y1114829D03*
X828799D03*
X837499Y1144948D03*
X828799D03*
X837499Y1138255D03*
X828799D03*
X837499Y1131562D03*
X828799D03*
X837499Y1161680D03*
X828799D03*
X837499Y1151641D03*
X828799D03*
X837499Y1175066D03*
X828799D03*
X837499Y1168373D03*
X828799D03*
Y1188452D03*
X837499D03*
Y1181759D03*
X828799D03*
X837499Y1205184D03*
X828799D03*
X837499Y1198491D03*
X828799D03*
X837499Y1225263D03*
X828799D03*
X837499Y1218570D03*
X828799D03*
X837499Y1211877D03*
X828799D03*
X837499Y1241995D03*
X828799D03*
X837499Y1235302D03*
X828799D03*
X837499Y1248688D03*
X828799D03*
X837846Y1256964D03*
X839246Y1273064D03*
X842046D03*
X831846Y1273364D03*
X834646D03*
X844941Y766798D03*
X853641D03*
X844941Y780184D03*
X853641D03*
X844941Y773491D03*
X853641D03*
X844941Y803609D03*
X853641D03*
X844941Y796916D03*
X853641D03*
X844941Y790223D03*
X853641D03*
X844941Y816995D03*
X853641D03*
X844941Y810302D03*
X853641D03*
X844941Y833727D03*
X853641D03*
X844941Y827034D03*
X853641D03*
X844941Y847113D03*
X853641D03*
X844941Y840420D03*
X853641D03*
X844941Y863845D03*
X853641D03*
X844941Y853806D03*
X853641D03*
X844941Y883924D03*
X853641D03*
X844941Y877231D03*
X853641D03*
X844941Y870538D03*
X853641D03*
X844941Y900656D03*
X853641D03*
X844941Y890617D03*
X853641D03*
X844941Y914042D03*
X853641D03*
X844941Y907349D03*
X853641D03*
X844941Y927428D03*
X853641D03*
X844941Y920735D03*
X853641D03*
X844941Y944160D03*
X853641D03*
X844941Y937467D03*
X853641D03*
X844941Y960892D03*
X853641D03*
X844941Y950853D03*
X853641D03*
X844941Y980971D03*
X853641D03*
X844941Y974278D03*
X853641D03*
X844941Y967585D03*
X853641D03*
X844941Y987664D03*
X853641D03*
X844941Y1027822D03*
X853641D03*
X844941Y1017782D03*
X853641D03*
X844941Y1047900D03*
X853641D03*
X844941Y1041207D03*
X853641D03*
X844941Y1034515D03*
X853641D03*
X844941Y1061286D03*
X853641D03*
X844941Y1054593D03*
X853641D03*
X844941Y1074672D03*
X853641D03*
X844941Y1067979D03*
X853641D03*
X844941Y1091404D03*
X853641D03*
X844941Y1084711D03*
X853641D03*
X844941Y1111483D03*
X853641D03*
X844941Y1104790D03*
X853641D03*
X844941Y1098097D03*
X853641D03*
X844941Y1128215D03*
X853641D03*
X844941Y1121522D03*
X853641D03*
X844941Y1141601D03*
X853641D03*
X844941Y1134908D03*
X853641D03*
X844941Y1158333D03*
X853641D03*
X844941Y1148294D03*
X853641D03*
X844941Y1171719D03*
X853641D03*
X844941Y1165026D03*
X853641D03*
X844941Y1185105D03*
X853641D03*
X844941Y1178412D03*
X853641D03*
X844941Y1208530D03*
X853641D03*
X844941Y1201837D03*
X853641D03*
X844941Y1195144D03*
X853641D03*
X844941Y1221916D03*
X853641D03*
X844941Y1215223D03*
X853641D03*
X844941Y1238648D03*
X853641D03*
X844941Y1231955D03*
X853641D03*
X844941Y1245341D03*
X853641D03*
X1003841Y770144D03*
Y783530D03*
Y776837D03*
Y800263D03*
Y793570D03*
Y820341D03*
Y813648D03*
Y806955D03*
Y830381D03*
Y850459D03*
Y843766D03*
Y837074D03*
Y867192D03*
Y857152D03*
Y880577D03*
Y873885D03*
Y893963D03*
Y887270D03*
Y917389D03*
Y910696D03*
Y904003D03*
Y930774D03*
Y924081D03*
Y947507D03*
Y940814D03*
Y964239D03*
Y954200D03*
Y977625D03*
Y970932D03*
Y991011D03*
Y984318D03*
Y1031168D03*
Y1024475D03*
Y1017782D03*
Y1044554D03*
Y1037861D03*
Y1057940D03*
Y1051247D03*
Y1078018D03*
Y1071326D03*
Y1064633D03*
Y1094751D03*
Y1088058D03*
Y1108137D03*
Y1101444D03*
Y1124869D03*
Y1114829D03*
Y1144948D03*
Y1138255D03*
Y1131562D03*
Y1161680D03*
Y1151641D03*
Y1175066D03*
Y1168373D03*
Y1188452D03*
Y1181759D03*
Y1205184D03*
Y1198491D03*
Y1225263D03*
Y1218570D03*
Y1211877D03*
Y1241995D03*
Y1235302D03*
Y1248688D03*
X1019983Y766798D03*
X1012541Y770144D03*
X1019983Y780184D03*
Y773491D03*
X1012541Y783530D03*
Y776837D03*
X1019983Y803609D03*
Y796916D03*
Y790223D03*
X1012541Y800263D03*
Y793570D03*
X1019983Y816995D03*
Y810302D03*
X1012541Y820341D03*
Y813648D03*
Y806955D03*
X1019983Y833727D03*
Y827034D03*
X1012541Y830381D03*
X1019983Y847113D03*
Y840420D03*
X1012541Y850459D03*
Y843766D03*
Y837074D03*
X1019983Y863845D03*
Y853806D03*
X1012541Y867192D03*
Y857152D03*
X1019983Y883924D03*
Y877231D03*
Y870538D03*
X1012541Y880577D03*
Y873885D03*
X1019983Y900656D03*
Y890617D03*
X1012541Y893963D03*
Y887270D03*
X1019983Y914042D03*
Y907349D03*
X1012541Y917389D03*
Y910696D03*
Y904003D03*
X1019983Y927428D03*
Y920735D03*
X1012541Y930774D03*
Y924081D03*
X1019983Y944160D03*
Y937467D03*
X1012541Y947507D03*
Y940814D03*
X1019983Y960892D03*
Y950853D03*
X1012541Y964239D03*
Y954200D03*
X1019983Y980971D03*
Y974278D03*
Y967585D03*
X1012541Y977625D03*
Y970932D03*
X1019983Y987664D03*
X1012541Y991011D03*
Y984318D03*
X1019983Y1027822D03*
Y1017782D03*
X1012541Y1031168D03*
Y1024475D03*
Y1017782D03*
X1019983Y1047900D03*
Y1041207D03*
Y1034515D03*
X1012541Y1044554D03*
Y1037861D03*
X1019983Y1061286D03*
Y1054593D03*
X1012541Y1057940D03*
Y1051247D03*
X1019983Y1067979D03*
Y1074672D03*
X1012541Y1078018D03*
Y1071326D03*
Y1064633D03*
X1019983Y1091404D03*
Y1084711D03*
X1012541Y1094751D03*
Y1088058D03*
X1019983Y1111483D03*
Y1104790D03*
Y1098097D03*
X1012541Y1108137D03*
Y1101444D03*
X1019983Y1128215D03*
Y1121522D03*
X1012541Y1124869D03*
Y1114829D03*
X1019983Y1141601D03*
Y1134908D03*
X1012541Y1144948D03*
Y1138255D03*
Y1131562D03*
X1019983Y1158333D03*
Y1148294D03*
X1012541Y1161680D03*
Y1151641D03*
X1019983Y1171719D03*
Y1165026D03*
X1012541Y1175066D03*
Y1168373D03*
X1019983Y1185105D03*
Y1178412D03*
X1012541Y1188452D03*
Y1181759D03*
X1019983Y1208530D03*
Y1201837D03*
Y1195144D03*
X1012541Y1205184D03*
Y1198491D03*
X1019983Y1221916D03*
Y1215223D03*
X1012541Y1225263D03*
Y1218570D03*
Y1211877D03*
X1019983Y1238648D03*
Y1231955D03*
X1012541Y1241995D03*
Y1235302D03*
X1012543Y1257198D03*
X1019983Y1245341D03*
X1012541Y1248688D03*
X1017111Y1273299D03*
X1014111D03*
X1033541Y770144D03*
X1028683Y766798D03*
X1033541Y783530D03*
Y776837D03*
X1028683Y780184D03*
Y773491D03*
X1033541Y800263D03*
Y793570D03*
X1028683Y803609D03*
Y796916D03*
Y790223D03*
X1033541Y820341D03*
Y813648D03*
Y806955D03*
X1028683Y816995D03*
Y810302D03*
X1033541Y830381D03*
X1028683Y833727D03*
Y827034D03*
X1033541Y850459D03*
Y843766D03*
Y837074D03*
X1028683Y847113D03*
Y840420D03*
X1033541Y867192D03*
Y857152D03*
X1028683Y863845D03*
Y853806D03*
X1033541Y880577D03*
Y873885D03*
X1028683Y883924D03*
Y877231D03*
Y870538D03*
X1033541Y893963D03*
Y887270D03*
X1028683Y900656D03*
Y890617D03*
X1033541Y917389D03*
Y910696D03*
Y904003D03*
X1028683Y914042D03*
Y907349D03*
X1033541Y930774D03*
Y924081D03*
X1028683Y927428D03*
Y920735D03*
X1033541Y947507D03*
Y940814D03*
X1028683Y944160D03*
Y937467D03*
X1033541Y964239D03*
Y954200D03*
X1028683Y960892D03*
Y950853D03*
X1033541Y977625D03*
Y970932D03*
X1028683Y980971D03*
Y974278D03*
Y967585D03*
X1033541Y991011D03*
Y984318D03*
X1028683Y987664D03*
X1033541Y1031168D03*
Y1017782D03*
Y1024475D03*
X1028683Y1027822D03*
Y1017782D03*
X1033541Y1044554D03*
Y1037861D03*
X1028683Y1047900D03*
Y1041207D03*
Y1034515D03*
X1033541Y1057940D03*
Y1051247D03*
X1028683Y1061286D03*
Y1054593D03*
X1033541Y1078018D03*
Y1071326D03*
Y1064633D03*
X1028683Y1067979D03*
Y1074672D03*
X1033541Y1094751D03*
Y1088058D03*
X1028683Y1091404D03*
Y1084711D03*
X1033541Y1108137D03*
Y1101444D03*
X1028683Y1111483D03*
Y1104790D03*
Y1098097D03*
X1033541Y1114829D03*
Y1124869D03*
X1028683Y1128215D03*
Y1121522D03*
X1033541Y1144948D03*
Y1138255D03*
Y1131562D03*
X1028683Y1141601D03*
Y1134908D03*
X1033541Y1161680D03*
Y1151641D03*
X1028683Y1158333D03*
Y1148294D03*
X1033541Y1175066D03*
Y1168373D03*
X1028683Y1171719D03*
Y1165026D03*
X1033541Y1188452D03*
Y1181759D03*
X1028683Y1185105D03*
Y1178412D03*
X1033541Y1205184D03*
Y1198491D03*
X1028683Y1208530D03*
Y1201837D03*
Y1195144D03*
X1033541Y1225263D03*
Y1218570D03*
Y1211877D03*
X1028683Y1221916D03*
Y1215223D03*
X1033541Y1241995D03*
Y1235302D03*
X1028683Y1238648D03*
Y1231955D03*
X1033541Y1248688D03*
X1028683Y1245341D03*
X1036588Y1273344D03*
X1022888D03*
X1025688D03*
X1049683Y766798D03*
X1042241Y770144D03*
X1049683Y780184D03*
Y773491D03*
X1042241Y783530D03*
Y776837D03*
X1049683Y803609D03*
Y796916D03*
Y790223D03*
X1042241Y800263D03*
Y793570D03*
X1049683Y816995D03*
Y810302D03*
X1042241Y820341D03*
Y813648D03*
Y806955D03*
X1049683Y833727D03*
Y827034D03*
X1042241Y830381D03*
X1049683Y847113D03*
Y840420D03*
X1042241Y850459D03*
Y843766D03*
Y837074D03*
X1049683Y863845D03*
Y853806D03*
X1042241Y867192D03*
Y857152D03*
X1049683Y883924D03*
Y877231D03*
Y870538D03*
X1042241Y880577D03*
Y873885D03*
X1049683Y900656D03*
Y890617D03*
X1042241Y893963D03*
Y887270D03*
X1049683Y914042D03*
Y907349D03*
X1042241Y917389D03*
Y910696D03*
Y904003D03*
X1049683Y927428D03*
Y920735D03*
X1042241Y930774D03*
Y924081D03*
X1049683Y944160D03*
Y937467D03*
X1042241Y947507D03*
Y940814D03*
X1049683Y960892D03*
Y950853D03*
X1042241Y964239D03*
Y954200D03*
X1049683Y980971D03*
Y974278D03*
Y967585D03*
X1042241Y977625D03*
Y970932D03*
X1049683Y987664D03*
X1042241Y991011D03*
Y984318D03*
X1049683Y1027822D03*
Y1017782D03*
X1042241Y1031168D03*
Y1017782D03*
Y1024475D03*
X1049683Y1047900D03*
Y1041207D03*
Y1034515D03*
X1042241Y1044554D03*
Y1037861D03*
X1049683Y1061286D03*
Y1054593D03*
X1042241Y1057940D03*
Y1051247D03*
X1049683Y1074672D03*
Y1067979D03*
X1042241Y1078018D03*
Y1071326D03*
Y1064633D03*
X1049683Y1091404D03*
Y1084711D03*
X1042241Y1094751D03*
Y1088058D03*
X1049683Y1111483D03*
Y1104790D03*
Y1098097D03*
X1042241Y1108137D03*
Y1101444D03*
Y1114829D03*
X1049683Y1128215D03*
Y1121522D03*
X1042241Y1124869D03*
X1049683Y1141601D03*
Y1134908D03*
X1042241Y1144948D03*
Y1138255D03*
Y1131562D03*
Y1161680D03*
X1049683Y1158333D03*
Y1148294D03*
X1042241Y1151641D03*
X1049683Y1171719D03*
Y1165026D03*
X1042241Y1175066D03*
Y1168373D03*
X1049683Y1185105D03*
Y1178412D03*
X1042241Y1188452D03*
Y1181759D03*
X1049683Y1208530D03*
Y1201837D03*
Y1195144D03*
X1042241Y1205184D03*
Y1198491D03*
X1049683Y1215223D03*
Y1221916D03*
X1042241Y1225263D03*
Y1218570D03*
Y1211877D03*
X1049683Y1238648D03*
Y1231955D03*
X1042241Y1241995D03*
Y1235302D03*
X1042331Y1257488D03*
X1049683Y1245341D03*
X1042241Y1248688D03*
X1052588Y1273344D03*
X1039388D03*
X1063241Y770144D03*
X1058383Y766798D03*
X1063241Y783530D03*
Y776837D03*
X1058383Y780184D03*
Y773491D03*
X1063241Y800263D03*
Y793570D03*
X1058383Y803609D03*
Y796916D03*
Y790223D03*
X1063241Y820341D03*
Y813648D03*
Y806955D03*
X1058383Y816995D03*
Y810302D03*
X1063241Y830381D03*
X1058383Y833727D03*
Y827034D03*
X1063241Y850459D03*
Y843766D03*
Y837074D03*
X1058383Y847113D03*
Y840420D03*
X1063241Y867192D03*
Y857152D03*
X1058383Y863845D03*
Y853806D03*
X1063241Y880577D03*
Y873885D03*
X1058383Y883924D03*
Y877231D03*
Y870538D03*
X1063241Y893963D03*
Y887270D03*
X1058383Y900656D03*
Y890617D03*
X1063241Y917389D03*
Y910696D03*
Y904003D03*
X1058383Y914042D03*
Y907349D03*
X1063241Y930774D03*
Y924081D03*
X1058383Y927428D03*
Y920735D03*
X1063241Y947507D03*
Y940814D03*
X1058383Y944160D03*
Y937467D03*
X1063241Y964239D03*
Y954200D03*
X1058383Y960892D03*
Y950853D03*
X1063241Y977625D03*
Y970932D03*
X1058383Y980971D03*
Y974278D03*
Y967585D03*
X1063241Y991011D03*
Y984318D03*
X1058383Y987664D03*
X1063241Y1031168D03*
Y1024475D03*
Y1017782D03*
X1058383Y1027822D03*
Y1017782D03*
X1063241Y1044554D03*
Y1037861D03*
X1058383Y1047900D03*
Y1041207D03*
Y1034515D03*
X1063241Y1057940D03*
Y1051247D03*
X1058383Y1061286D03*
Y1054593D03*
X1063241Y1078018D03*
Y1071326D03*
Y1064633D03*
X1058383Y1074672D03*
Y1067979D03*
X1063241Y1094751D03*
Y1088058D03*
X1058383Y1091404D03*
Y1084711D03*
X1063241Y1108137D03*
Y1101444D03*
X1058383Y1111483D03*
Y1104790D03*
Y1098097D03*
X1063241Y1124869D03*
Y1114829D03*
X1058383Y1128215D03*
Y1121522D03*
X1063241Y1144948D03*
Y1138255D03*
Y1131562D03*
X1058383Y1141601D03*
Y1134908D03*
X1063241Y1161680D03*
Y1151641D03*
X1058383Y1158333D03*
Y1148294D03*
X1063241Y1175066D03*
Y1168373D03*
X1058383Y1171719D03*
Y1165026D03*
X1063241Y1188452D03*
Y1181759D03*
X1058383Y1185105D03*
Y1178412D03*
X1063241Y1205184D03*
Y1198491D03*
X1058383Y1208530D03*
Y1201837D03*
Y1195144D03*
X1063241Y1225263D03*
Y1218570D03*
Y1211877D03*
X1058383Y1215223D03*
Y1221916D03*
X1063241Y1241995D03*
Y1235302D03*
X1058383Y1238648D03*
Y1231955D03*
X1063241Y1248688D03*
X1058383Y1245341D03*
X1069088Y1273344D03*
X1066288D03*
X1055388D03*
X1079383Y766798D03*
X1071941Y770144D03*
X1079383Y780184D03*
Y773491D03*
X1071941Y783530D03*
Y776837D03*
X1079383Y803609D03*
Y796916D03*
Y790223D03*
X1071941Y800263D03*
Y793570D03*
X1079383Y816995D03*
Y810302D03*
X1071941Y820341D03*
Y813648D03*
Y806955D03*
X1079383Y833727D03*
Y827034D03*
X1071941Y830381D03*
X1079383Y847113D03*
Y840420D03*
X1071941Y850459D03*
Y843766D03*
Y837074D03*
X1079383Y863845D03*
Y853806D03*
X1071941Y867192D03*
Y857152D03*
X1079383Y883924D03*
Y877231D03*
Y870538D03*
X1071941Y880577D03*
Y873885D03*
X1079383Y900656D03*
Y890617D03*
X1071941Y893963D03*
Y887270D03*
X1079383Y914042D03*
Y907349D03*
X1071941Y917389D03*
Y910696D03*
Y904003D03*
X1079383Y927428D03*
Y920735D03*
X1071941Y930774D03*
Y924081D03*
X1079383Y944160D03*
Y937467D03*
X1071941Y947507D03*
Y940814D03*
X1079383Y960892D03*
Y950853D03*
X1071941Y964239D03*
Y954200D03*
X1079383Y980971D03*
Y974278D03*
Y967585D03*
X1071941Y977625D03*
Y970932D03*
X1079383Y987664D03*
X1071941Y991011D03*
Y984318D03*
X1079383Y1027822D03*
Y1017782D03*
X1071941Y1031168D03*
Y1024475D03*
Y1017782D03*
X1079383Y1047900D03*
Y1041207D03*
Y1034515D03*
X1071941Y1044554D03*
Y1037861D03*
X1079383Y1061286D03*
Y1054593D03*
X1071941Y1057940D03*
Y1051247D03*
X1079383Y1074672D03*
Y1067979D03*
X1071941Y1078018D03*
Y1071326D03*
Y1064633D03*
X1079383Y1091404D03*
Y1084711D03*
X1071941Y1094751D03*
Y1088058D03*
X1079383Y1111483D03*
Y1104790D03*
Y1098097D03*
X1071941Y1108137D03*
Y1101444D03*
X1079383Y1128215D03*
Y1121522D03*
X1071941Y1124869D03*
Y1114829D03*
X1079383Y1141601D03*
Y1134908D03*
X1071941Y1144948D03*
Y1138255D03*
Y1131562D03*
X1079383Y1158333D03*
Y1148294D03*
X1071941Y1161680D03*
Y1151641D03*
X1079383Y1171719D03*
Y1165026D03*
X1071941Y1175066D03*
Y1168373D03*
X1079383Y1185105D03*
Y1178412D03*
X1071941Y1188452D03*
Y1181759D03*
X1079383Y1208530D03*
Y1201837D03*
Y1195144D03*
X1071941Y1205184D03*
Y1198491D03*
X1079383Y1221916D03*
Y1215223D03*
X1071941Y1225263D03*
Y1218570D03*
Y1211877D03*
X1079383Y1238648D03*
Y1231955D03*
X1071941Y1241995D03*
Y1235302D03*
X1071991Y1257262D03*
X1079383Y1245341D03*
X1071941Y1248688D03*
X1085088Y1273344D03*
X1082288D03*
X1092941Y770144D03*
X1101641D03*
X1088083Y766798D03*
X1092941Y783530D03*
X1101641D03*
X1092941Y776837D03*
X1101641D03*
X1088083Y780184D03*
Y773491D03*
X1101641Y800263D03*
X1092941D03*
X1101641Y793570D03*
X1092941D03*
X1088083Y803609D03*
Y796916D03*
Y790223D03*
X1101641Y820341D03*
X1092941D03*
X1101641Y813648D03*
X1092941D03*
X1101641Y806955D03*
X1092941D03*
X1088083Y816995D03*
Y810302D03*
X1101641Y830381D03*
X1092941D03*
X1088083Y833727D03*
Y827034D03*
X1101641Y850459D03*
X1092941D03*
X1101641Y843766D03*
X1092941D03*
X1101641Y837074D03*
X1092941D03*
X1088083Y847113D03*
Y840420D03*
X1101641Y867192D03*
X1092941D03*
X1101641Y857152D03*
X1092941D03*
X1088083Y863845D03*
Y853806D03*
X1101641Y880577D03*
X1092941D03*
X1101641Y873885D03*
X1092941D03*
X1088083Y883924D03*
Y877231D03*
Y870538D03*
X1101641Y893963D03*
X1092941D03*
X1101641Y887270D03*
X1092941D03*
X1088083Y900656D03*
Y890617D03*
X1101641Y917389D03*
X1092941D03*
X1101641Y910696D03*
X1092941D03*
X1101641Y904003D03*
X1092941D03*
X1088083Y914042D03*
Y907349D03*
X1101641Y930774D03*
X1092941D03*
X1101641Y924081D03*
X1092941D03*
X1088083Y927428D03*
Y920735D03*
X1101641Y947507D03*
X1092941D03*
X1101641Y940814D03*
X1092941D03*
X1088083Y944160D03*
Y937467D03*
X1101641Y964239D03*
X1092941D03*
X1101641Y954200D03*
X1092941D03*
X1088083Y960892D03*
Y950853D03*
X1101641Y977625D03*
X1092941D03*
X1101641Y970932D03*
X1092941D03*
X1088083Y980971D03*
Y974278D03*
Y967585D03*
X1101641Y991011D03*
X1092941D03*
X1101641Y984318D03*
X1092941D03*
X1088083Y987664D03*
X1101641Y1031168D03*
X1092941D03*
X1101641Y1024475D03*
X1092941D03*
X1101641Y1017782D03*
X1092941D03*
X1088083Y1027822D03*
Y1017782D03*
X1101641Y1044554D03*
X1092941D03*
X1101641Y1037861D03*
X1092941D03*
X1088083Y1047900D03*
Y1041207D03*
Y1034515D03*
X1101641Y1057940D03*
X1092941D03*
X1101641Y1051247D03*
X1092941D03*
X1088083Y1061286D03*
Y1054593D03*
X1101641Y1078018D03*
X1092941D03*
X1101641Y1071326D03*
X1092941D03*
X1101641Y1064633D03*
X1092941D03*
X1088083Y1074672D03*
Y1067979D03*
X1101641Y1094751D03*
X1092941D03*
X1101641Y1088058D03*
X1092941D03*
X1088083Y1091404D03*
Y1084711D03*
X1101641Y1108137D03*
X1092941D03*
X1101641Y1101444D03*
X1092941D03*
X1088083Y1111483D03*
Y1104790D03*
Y1098097D03*
X1101641Y1124869D03*
X1092941D03*
X1101641Y1114829D03*
X1092941D03*
X1088083Y1128215D03*
Y1121522D03*
X1101641Y1144948D03*
X1092941D03*
X1101641Y1138255D03*
X1092941D03*
X1101641Y1131562D03*
X1092941D03*
X1088083Y1141601D03*
Y1134908D03*
X1092941Y1161680D03*
X1101641D03*
Y1151641D03*
X1092941D03*
X1088083Y1158333D03*
Y1148294D03*
X1101641Y1175066D03*
X1092941D03*
X1101641Y1168373D03*
X1092941D03*
X1088083Y1171719D03*
Y1165026D03*
X1101641Y1181759D03*
X1092941D03*
Y1188452D03*
X1101641D03*
X1088083Y1185105D03*
Y1178412D03*
X1092941Y1205184D03*
X1101641D03*
X1092941Y1198491D03*
X1101641D03*
X1088083Y1208530D03*
Y1201837D03*
Y1195144D03*
X1101641Y1225263D03*
X1092941D03*
X1101641Y1218570D03*
X1092941D03*
Y1211877D03*
X1101641D03*
X1088083Y1221916D03*
Y1215223D03*
X1101641Y1241995D03*
X1092941D03*
X1101641Y1235302D03*
X1092941D03*
X1088083Y1238648D03*
Y1231955D03*
X1101554Y1257102D03*
X1101641Y1248688D03*
X1092941D03*
X1088083Y1245341D03*
X1098788Y1273344D03*
X1095988D03*
X1109083Y766798D03*
X1117783D03*
Y780184D03*
X1109083D03*
X1117783Y773491D03*
X1109083D03*
X1117783Y803609D03*
X1109083D03*
X1117783Y796916D03*
X1109083D03*
Y790223D03*
X1117783D03*
Y816995D03*
X1109083D03*
X1117783Y810302D03*
X1109083D03*
X1117783Y833727D03*
X1109083D03*
X1117783Y827034D03*
X1109083D03*
X1117783Y847113D03*
X1109083D03*
X1117783Y840420D03*
X1109083D03*
X1117783Y863845D03*
X1109083D03*
X1117783Y853806D03*
X1109083D03*
X1117783Y883924D03*
X1109083D03*
X1117783Y877231D03*
X1109083D03*
X1117783Y870538D03*
X1109083D03*
X1117783Y900656D03*
X1109083D03*
X1117783Y890617D03*
X1109083D03*
X1117783Y914042D03*
X1109083D03*
X1117783Y907349D03*
X1109083D03*
X1117783Y927428D03*
X1109083D03*
X1117783Y920735D03*
X1109083D03*
X1117783Y944160D03*
X1109083D03*
X1117783Y937467D03*
X1109083D03*
X1117783Y960892D03*
X1109083D03*
X1117783Y950853D03*
X1109083D03*
X1117783Y980971D03*
X1109083D03*
X1117783Y974278D03*
X1109083D03*
X1117783Y967585D03*
X1109083D03*
X1117783Y987664D03*
X1109083D03*
X1117783Y1027822D03*
X1109083D03*
X1117783Y1017782D03*
X1109083D03*
X1117783Y1047900D03*
X1109083D03*
X1117783Y1041207D03*
X1109083D03*
X1117783Y1034515D03*
X1109083D03*
X1117783Y1061286D03*
X1109083D03*
X1117783Y1054593D03*
X1109083D03*
X1117783Y1074672D03*
X1109083D03*
X1117783Y1067979D03*
X1109083D03*
X1117783Y1091404D03*
X1109083D03*
X1117783Y1084711D03*
X1109083D03*
X1117783Y1111483D03*
X1109083D03*
X1117783Y1104790D03*
X1109083D03*
X1117783Y1098097D03*
X1109083D03*
X1117783Y1128215D03*
X1109083D03*
X1117783Y1121522D03*
X1109083D03*
X1117783Y1141601D03*
X1109083D03*
X1117783Y1134908D03*
X1109083D03*
X1117783Y1158333D03*
X1109083D03*
X1117783Y1148294D03*
X1109083D03*
X1117783Y1171719D03*
X1109083D03*
X1117783Y1165026D03*
X1109083D03*
X1117783Y1185105D03*
X1109083D03*
X1117783Y1178412D03*
X1109083D03*
X1117783Y1208530D03*
X1109083D03*
X1117783Y1201837D03*
X1109083D03*
X1117783Y1195144D03*
X1109083D03*
X1117783Y1221916D03*
X1109083D03*
X1117783Y1215223D03*
X1109083D03*
X1117783Y1238648D03*
X1109083D03*
X1117783Y1231955D03*
X1109083D03*
X1117783Y1245341D03*
X1109083D03*
X1111988Y1273344D03*
X1114788D03*
X1131341Y770144D03*
X1122641D03*
X1131341Y783530D03*
X1122641D03*
X1131341Y776837D03*
X1122641D03*
X1131341Y800263D03*
X1122641D03*
X1131341Y793570D03*
X1122641D03*
X1131341Y820341D03*
X1122641D03*
X1131341Y813648D03*
X1122641D03*
X1131341Y806955D03*
X1122641D03*
X1131341Y830381D03*
X1122641D03*
X1131341Y850459D03*
X1122641D03*
X1131341Y843766D03*
X1122641D03*
X1131341Y837074D03*
X1122641D03*
X1131341Y867192D03*
X1122641D03*
X1131341Y857152D03*
X1122641D03*
X1131341Y880577D03*
X1122641D03*
X1131341Y873885D03*
X1122641D03*
X1131341Y893963D03*
X1122641D03*
X1131341Y887270D03*
X1122641D03*
X1131341Y917389D03*
X1122641D03*
X1131341Y910696D03*
X1122641D03*
X1131341Y904003D03*
X1122641D03*
X1131341Y930774D03*
X1122641D03*
X1131341Y924081D03*
X1122641D03*
Y947507D03*
X1131341D03*
Y940814D03*
X1122641D03*
X1131341Y964239D03*
X1122641D03*
X1131341Y954200D03*
X1122641D03*
X1131341Y977625D03*
X1122641D03*
X1131341Y970932D03*
X1122641D03*
X1131341Y991011D03*
X1122641D03*
X1131341Y984318D03*
X1122641D03*
X1131341Y1031168D03*
X1122641D03*
X1131341Y1024475D03*
X1122641D03*
X1131341Y1017782D03*
X1122641D03*
X1131341Y1044554D03*
X1122641D03*
X1131341Y1037861D03*
X1122641D03*
X1131341Y1057940D03*
X1122641D03*
X1131341Y1051247D03*
X1122641D03*
X1131341Y1078018D03*
X1122641D03*
X1131341Y1071326D03*
X1122641D03*
X1131341Y1064633D03*
X1122641D03*
X1131341Y1094751D03*
X1122641D03*
X1131341Y1088058D03*
X1122641D03*
X1131341Y1108137D03*
X1122641D03*
X1131341Y1101444D03*
X1122641D03*
X1131341Y1124869D03*
X1122641D03*
X1131341Y1114829D03*
X1122641D03*
X1131341Y1144948D03*
X1122641D03*
X1131341Y1138255D03*
X1122641D03*
X1131341Y1131562D03*
X1122641D03*
X1131341Y1161680D03*
X1122641D03*
X1131341Y1151641D03*
X1122641D03*
X1131341Y1175066D03*
X1122641D03*
X1131341Y1168373D03*
X1122641D03*
X1131341Y1188452D03*
X1122641D03*
X1131341Y1181759D03*
X1122641D03*
X1131341Y1205184D03*
X1122641D03*
X1131341Y1198491D03*
X1122641D03*
X1131341Y1225263D03*
X1122641D03*
X1131341Y1218570D03*
X1122641D03*
X1131341Y1211877D03*
X1122641D03*
X1131341Y1241995D03*
X1122641D03*
X1131341Y1235302D03*
X1122641D03*
X1131434Y1257291D03*
X1122641Y1248688D03*
X1131341D03*
X1126188Y1273344D03*
X1128988D03*
X1152341Y770144D03*
X1147483Y766798D03*
X1138783D03*
X1152341Y783530D03*
Y776837D03*
X1147483Y780184D03*
X1138783D03*
Y773491D03*
X1147483D03*
X1152341Y800263D03*
X1147483Y803609D03*
X1138783D03*
X1152341Y793570D03*
X1147483Y796916D03*
X1138783D03*
X1147483Y790223D03*
X1138783D03*
X1152341Y820341D03*
X1147483Y816995D03*
X1138783D03*
X1152341Y813648D03*
Y806955D03*
X1147483Y810302D03*
X1138783D03*
X1147483Y833727D03*
X1138783D03*
X1152341Y830381D03*
X1147483Y827034D03*
X1138783D03*
X1152341Y850459D03*
Y843766D03*
Y837074D03*
X1147483Y847113D03*
X1138783D03*
X1147483Y840420D03*
X1138783D03*
X1152341Y867192D03*
Y857152D03*
X1147483Y863845D03*
X1138783D03*
X1147483Y853806D03*
X1138783D03*
X1152341Y880577D03*
Y873885D03*
X1147483Y883924D03*
X1138783D03*
X1147483Y877231D03*
X1138783D03*
X1147483Y870538D03*
X1138783D03*
X1152341Y893963D03*
Y887270D03*
X1138783Y900656D03*
X1147483D03*
X1138783Y890617D03*
X1147483D03*
X1152341Y917389D03*
Y910696D03*
Y904003D03*
X1147483Y914042D03*
X1138783D03*
X1147483Y907349D03*
X1138783D03*
X1152341Y930774D03*
Y924081D03*
X1147483Y927428D03*
X1138783D03*
X1147483Y920735D03*
X1138783D03*
X1152341Y947507D03*
Y940814D03*
X1147483Y944160D03*
X1138783D03*
X1147483Y937467D03*
X1138783D03*
X1152341Y964239D03*
Y954200D03*
X1147483Y960892D03*
X1138783D03*
X1147483Y950853D03*
X1138783D03*
X1152341Y977625D03*
Y970932D03*
X1147483Y980971D03*
X1138783D03*
X1147483Y974278D03*
X1138783D03*
X1147483Y967585D03*
X1138783D03*
X1152341Y991011D03*
Y984318D03*
X1147483Y987664D03*
X1138783D03*
X1152341Y1031168D03*
Y1024475D03*
Y1017782D03*
X1147483Y1027822D03*
X1138783D03*
X1147483Y1017782D03*
X1138783D03*
X1152341Y1044554D03*
Y1037861D03*
X1138783Y1047900D03*
X1147483D03*
Y1041207D03*
X1138783D03*
X1147483Y1034515D03*
X1138783D03*
X1152341Y1057940D03*
Y1051247D03*
X1147483Y1061286D03*
X1138783D03*
X1147483Y1054593D03*
X1138783D03*
X1152341Y1078018D03*
Y1071326D03*
Y1064633D03*
X1147483Y1074672D03*
X1138783D03*
X1147483Y1067979D03*
X1138783D03*
X1152341Y1094751D03*
Y1088058D03*
X1147483Y1091404D03*
X1138783D03*
X1147483Y1084711D03*
X1138783D03*
X1152341Y1108137D03*
Y1101444D03*
X1147483Y1111483D03*
X1138783D03*
X1147483Y1104790D03*
X1138783D03*
X1147483Y1098097D03*
X1138783D03*
X1152341Y1124869D03*
Y1114829D03*
X1147483Y1128215D03*
X1138783D03*
X1147483Y1121522D03*
X1138783D03*
X1152341Y1144948D03*
Y1138255D03*
Y1131562D03*
X1147483Y1141601D03*
X1138783D03*
X1147483Y1134908D03*
X1138783D03*
X1152341Y1161680D03*
Y1151641D03*
X1147483Y1158333D03*
X1138783D03*
Y1148294D03*
X1147483D03*
X1152341Y1175066D03*
Y1168373D03*
X1147483Y1171719D03*
X1138783D03*
X1147483Y1165026D03*
X1138783D03*
X1152341Y1188452D03*
Y1181759D03*
X1147483Y1185105D03*
X1138783D03*
X1147483Y1178412D03*
X1138783D03*
X1152341Y1205184D03*
Y1198491D03*
X1147483Y1208530D03*
X1138783D03*
X1147483Y1201837D03*
X1138783D03*
X1147483Y1195144D03*
X1138783D03*
X1152341Y1225263D03*
Y1218570D03*
Y1211877D03*
X1147483Y1221916D03*
X1138783D03*
X1147483Y1215223D03*
X1138783D03*
X1152341Y1241995D03*
Y1235302D03*
X1147483Y1238648D03*
X1138783D03*
X1147483Y1231955D03*
X1138783D03*
X1152341Y1248688D03*
X1147483Y1245341D03*
X1138783D03*
X1152381Y1269684D03*
X1147681D03*
X1138201Y1270277D03*
X1168483Y766798D03*
X1161041Y770144D03*
X1168483Y780184D03*
Y773491D03*
X1161041Y783530D03*
Y776837D03*
X1168483Y803609D03*
Y796916D03*
Y790223D03*
X1161041Y800263D03*
Y793570D03*
X1168483Y816995D03*
Y810302D03*
X1161041Y820341D03*
Y813648D03*
Y806955D03*
X1168483Y833727D03*
X1167633Y827034D03*
X1161041Y830381D03*
X1168483Y847113D03*
Y840420D03*
X1161041Y850459D03*
Y843766D03*
Y837074D03*
X1167633Y863845D03*
X1161041Y867192D03*
X1168483Y853806D03*
X1161041Y857152D03*
X1168483Y883924D03*
Y877231D03*
Y870538D03*
X1161041Y880577D03*
Y873885D03*
X1168483Y900656D03*
Y890617D03*
X1161041Y893963D03*
Y887270D03*
X1168483Y914042D03*
Y907349D03*
X1161041Y917389D03*
Y910696D03*
Y904003D03*
X1167633Y927428D03*
X1168483Y920735D03*
X1161041Y930774D03*
Y924081D03*
X1168483Y937467D03*
Y944160D03*
X1161041Y947507D03*
Y940814D03*
X1168483Y960892D03*
Y950853D03*
X1161041Y964239D03*
Y954200D03*
X1168483Y974278D03*
Y980971D03*
Y967585D03*
X1161041Y977625D03*
Y970932D03*
X1168483Y987664D03*
X1161041Y991011D03*
Y984318D03*
X1168483Y1027822D03*
Y1017782D03*
X1161041Y1031168D03*
Y1024475D03*
Y1017782D03*
X1168483Y1047900D03*
Y1041207D03*
Y1034515D03*
X1161041Y1044554D03*
Y1037861D03*
X1168483Y1054593D03*
Y1061286D03*
X1161041Y1057940D03*
Y1051247D03*
X1168483Y1074672D03*
Y1067979D03*
X1161041Y1078018D03*
Y1071326D03*
Y1064633D03*
X1168483Y1091404D03*
X1167633Y1084711D03*
X1161041Y1094751D03*
Y1088058D03*
X1168483Y1111483D03*
Y1104790D03*
Y1098097D03*
X1161041Y1108137D03*
Y1101444D03*
X1168483Y1128215D03*
Y1121522D03*
X1161041Y1124869D03*
Y1114829D03*
X1168483Y1141601D03*
Y1134908D03*
X1161041Y1144948D03*
Y1138255D03*
Y1131562D03*
X1167633Y1158333D03*
X1168483Y1148294D03*
X1161041Y1161680D03*
Y1151641D03*
X1168483Y1171719D03*
Y1165026D03*
X1161041Y1175066D03*
Y1168373D03*
X1168483Y1185105D03*
Y1178412D03*
X1161041Y1188452D03*
Y1181759D03*
X1168483Y1208530D03*
Y1201837D03*
Y1195144D03*
X1161041Y1205184D03*
Y1198491D03*
X1168483Y1221916D03*
Y1215223D03*
X1161041Y1225263D03*
Y1218570D03*
Y1211877D03*
X1168483Y1238648D03*
X1167633Y1231955D03*
X1161041Y1241995D03*
Y1235302D03*
X1161065Y1258871D03*
X1168483Y1245341D03*
X1161041Y1248688D03*
X1161781Y1269684D03*
X1182041Y770144D03*
X1177183Y766798D03*
X1182041Y783530D03*
Y776837D03*
X1177183Y780184D03*
Y773491D03*
X1182041Y800263D03*
Y793570D03*
X1177183Y803609D03*
Y796916D03*
Y790223D03*
X1182041Y813648D03*
Y806955D03*
X1181191Y820341D03*
X1177183Y816995D03*
Y810302D03*
X1181191Y830381D03*
X1177183Y833727D03*
Y827034D03*
X1182041Y850459D03*
Y837074D03*
Y843766D03*
X1177183Y847113D03*
Y840420D03*
X1181191Y867192D03*
X1177183Y863845D03*
X1181191Y857152D03*
X1177183Y853806D03*
X1182041Y873885D03*
Y880577D03*
X1177183Y883924D03*
Y877231D03*
Y870538D03*
X1182041Y893963D03*
Y887270D03*
X1177183Y900656D03*
Y890617D03*
X1182041Y917389D03*
Y910696D03*
Y904003D03*
X1177183Y914042D03*
Y907349D03*
X1181191Y930774D03*
Y924081D03*
X1177183Y927428D03*
Y920735D03*
X1182041Y940814D03*
Y947507D03*
X1177183Y937467D03*
Y944160D03*
X1182041Y964239D03*
Y954200D03*
X1177183Y960892D03*
Y950853D03*
X1182041Y970932D03*
Y977625D03*
X1177183Y974278D03*
Y980971D03*
Y967585D03*
X1182041Y991011D03*
Y984318D03*
X1177183Y987664D03*
X1182041Y1031168D03*
Y1017782D03*
Y1024475D03*
X1177183Y1027822D03*
Y1017782D03*
X1182041Y1044554D03*
Y1037861D03*
X1177183Y1047900D03*
Y1041207D03*
Y1034515D03*
X1182041Y1057940D03*
Y1051247D03*
X1177183Y1054593D03*
Y1061286D03*
X1181191Y1078018D03*
X1182041Y1071326D03*
Y1064633D03*
X1177183Y1074672D03*
Y1067979D03*
X1182041Y1094751D03*
X1181191Y1088058D03*
X1177183Y1091404D03*
Y1084711D03*
X1182041Y1101444D03*
Y1108137D03*
X1177183Y1111483D03*
Y1104790D03*
Y1098097D03*
X1182041Y1114829D03*
Y1124869D03*
X1177183Y1128215D03*
Y1121522D03*
X1182041Y1144948D03*
Y1138255D03*
Y1131562D03*
X1177183Y1141601D03*
Y1134908D03*
X1181191Y1161680D03*
Y1151641D03*
X1177183Y1158333D03*
Y1148294D03*
X1182041Y1168373D03*
Y1175066D03*
X1177183Y1171719D03*
Y1165026D03*
X1182041Y1188452D03*
Y1181759D03*
X1177183Y1185105D03*
Y1178412D03*
X1182041Y1205184D03*
Y1198491D03*
X1177183Y1208530D03*
Y1201837D03*
Y1195144D03*
X1181191Y1225263D03*
X1182041Y1211877D03*
Y1218570D03*
X1177183Y1221916D03*
Y1215223D03*
X1182041Y1241995D03*
X1181191Y1235302D03*
X1177183Y1238648D03*
Y1231955D03*
X1182041Y1248688D03*
X1177183Y1245341D03*
X1176867Y1270029D03*
X1198183Y766798D03*
X1190741Y770144D03*
X1198183Y780184D03*
Y773491D03*
X1190741Y783530D03*
Y776837D03*
X1198183Y803609D03*
Y796916D03*
Y790223D03*
X1190741Y800263D03*
Y793570D03*
X1197333Y816995D03*
X1198183Y810302D03*
X1190741Y813648D03*
Y806955D03*
X1191591Y820341D03*
X1198183Y833727D03*
X1197333Y827034D03*
X1191591Y830381D03*
X1198183Y847113D03*
Y840420D03*
X1190741Y850459D03*
Y837074D03*
Y843766D03*
X1197333Y863845D03*
X1191591Y867192D03*
X1198183Y853806D03*
X1191591Y857152D03*
X1198183Y877231D03*
X1197333Y870538D03*
X1198183Y883924D03*
X1190741Y873885D03*
Y880577D03*
X1198183Y900656D03*
Y890617D03*
X1190741Y893963D03*
Y887270D03*
X1198183Y914042D03*
Y907349D03*
X1190741Y917389D03*
Y910696D03*
Y904003D03*
X1197383Y927428D03*
X1198183Y920735D03*
X1191591Y930774D03*
Y924081D03*
X1198183Y944160D03*
X1197333Y937467D03*
X1190741Y940814D03*
Y947507D03*
X1198183Y960892D03*
Y950853D03*
X1190741Y964239D03*
Y954200D03*
X1198183Y980971D03*
Y974278D03*
Y967585D03*
X1190741Y970932D03*
Y977625D03*
X1198183Y987664D03*
X1190741Y991011D03*
Y984318D03*
X1198183Y1027822D03*
Y1017782D03*
X1190741Y1031168D03*
Y1017782D03*
Y1024475D03*
X1198183Y1047900D03*
Y1041207D03*
Y1034515D03*
X1190741Y1044554D03*
Y1037861D03*
X1198183Y1054593D03*
Y1061286D03*
X1190741Y1057940D03*
Y1051247D03*
X1197333Y1074672D03*
X1198183Y1067979D03*
X1191591Y1078018D03*
X1190741Y1071326D03*
Y1064633D03*
X1198183Y1091404D03*
X1197333Y1084711D03*
X1190741Y1094751D03*
X1191591Y1088058D03*
X1198183Y1111483D03*
Y1098097D03*
Y1104790D03*
X1190741Y1101444D03*
Y1108137D03*
X1198183Y1128215D03*
Y1121522D03*
X1190741Y1114829D03*
Y1124869D03*
X1198183Y1141601D03*
X1197333Y1134908D03*
X1190741Y1144948D03*
Y1138255D03*
Y1131562D03*
X1198183Y1158333D03*
X1197333Y1148294D03*
X1191591Y1161680D03*
Y1151641D03*
X1198183Y1165026D03*
Y1171719D03*
X1190741Y1168373D03*
Y1175066D03*
X1198183Y1185105D03*
Y1178412D03*
X1190741Y1188452D03*
Y1181759D03*
X1198183Y1208530D03*
Y1201837D03*
Y1195144D03*
X1190741Y1205184D03*
Y1198491D03*
X1198183Y1221916D03*
Y1215223D03*
X1191591Y1225263D03*
X1190741Y1211877D03*
Y1218570D03*
X1197333Y1238648D03*
Y1231955D03*
X1190741Y1241995D03*
X1191591Y1235302D03*
X1198183Y1245341D03*
X1190966Y1258711D03*
X1190741Y1248688D03*
X1191538Y1270004D03*
X1194572Y1578182D03*
Y1590094D03*
X1199872Y1614292D03*
Y1602380D03*
X1211741Y770144D03*
X1206883Y766798D03*
X1211741Y783530D03*
Y776837D03*
X1206883Y780184D03*
Y773491D03*
X1211741Y800263D03*
Y793570D03*
X1206883Y803609D03*
Y796916D03*
Y790223D03*
X1210891Y820341D03*
Y813648D03*
X1211741Y806955D03*
X1207148Y817554D03*
X1206883Y810302D03*
X1211741Y830381D03*
X1206883Y833727D03*
X1207733Y827034D03*
X1211741Y850459D03*
Y837074D03*
Y843766D03*
X1206883Y847113D03*
Y840420D03*
X1210891Y867492D03*
X1207733Y863845D03*
X1210891Y857152D03*
X1206883Y853806D03*
X1211741Y874185D03*
Y880577D03*
X1206883Y877231D03*
X1207201Y871084D03*
X1206883Y883924D03*
X1211741Y893963D03*
Y887270D03*
X1206883Y900656D03*
Y890617D03*
X1211741Y917389D03*
Y910696D03*
Y904003D03*
X1206883Y914042D03*
Y907349D03*
X1211741Y930774D03*
Y924081D03*
X1207683Y927428D03*
X1206883Y920735D03*
X1211741Y947507D03*
X1211001Y940814D03*
X1206883Y944660D03*
X1207733Y937467D03*
X1211741Y964239D03*
Y954200D03*
X1206883Y960892D03*
Y950853D03*
X1211741Y977625D03*
Y970932D03*
X1206883Y980971D03*
Y974278D03*
Y967585D03*
X1211741Y991011D03*
X1206883Y987664D03*
X1211741Y984318D03*
Y1031168D03*
X1206883Y1027822D03*
Y1017782D03*
X1211741D03*
Y1024475D03*
Y1044554D03*
Y1037861D03*
X1206883Y1047900D03*
Y1041207D03*
Y1034515D03*
X1211741Y1051247D03*
Y1057940D03*
X1206883Y1054593D03*
Y1061286D03*
X1210891Y1078018D03*
X1211741Y1064633D03*
Y1071326D03*
X1207733Y1074672D03*
X1206883Y1067979D03*
X1211741Y1094751D03*
X1210891Y1088058D03*
X1206883Y1091404D03*
Y1084711D03*
X1211741Y1108137D03*
Y1101444D03*
X1206883Y1111483D03*
Y1098097D03*
Y1104790D03*
X1210891Y1124869D03*
X1211741Y1114829D03*
X1206883Y1128215D03*
Y1121522D03*
X1211741Y1144948D03*
Y1138255D03*
X1210891Y1131562D03*
X1206883Y1141601D03*
X1207733Y1134908D03*
X1211741Y1151641D03*
Y1161680D03*
X1206883Y1158333D03*
X1207733Y1148294D03*
X1211741Y1175066D03*
Y1168373D03*
X1206883Y1165026D03*
Y1171719D03*
X1211741Y1188452D03*
Y1181759D03*
X1206883Y1185105D03*
Y1178412D03*
X1211741Y1205184D03*
Y1198491D03*
X1206883Y1208530D03*
Y1201837D03*
Y1195144D03*
X1210891Y1225263D03*
X1211741Y1218570D03*
Y1211877D03*
X1206883Y1221916D03*
Y1215223D03*
X1211741Y1241995D03*
X1211328Y1234977D03*
X1207733Y1238648D03*
Y1231955D03*
X1206883Y1245341D03*
X1211741Y1248688D03*
X1204608Y1273119D03*
X1202043Y1273123D03*
X1202372Y1578182D03*
X1214432D03*
X1206632D03*
X1202372Y1590094D03*
X1214432D03*
X1206632D03*
X1207672Y1602380D03*
Y1614292D03*
X1211932D03*
Y1602380D03*
X1227883Y766798D03*
X1220441Y770144D03*
X1227883Y780184D03*
Y773491D03*
X1220441Y783530D03*
Y776837D03*
X1227883Y803609D03*
Y796916D03*
Y790223D03*
X1220441Y800263D03*
Y793570D03*
X1227033Y816995D03*
X1227883Y810302D03*
X1221291Y820341D03*
Y813648D03*
X1220441Y806955D03*
X1227883Y833727D03*
X1227033Y827034D03*
X1220441Y830381D03*
X1227883Y847113D03*
Y840420D03*
X1220441Y850459D03*
Y837074D03*
Y843766D03*
X1227033Y863845D03*
X1221291Y867192D03*
X1227033Y853806D03*
X1221291Y857152D03*
X1227883Y870538D03*
Y883924D03*
Y877231D03*
X1220441Y873885D03*
Y880577D03*
X1227033Y900656D03*
X1227883Y890617D03*
X1220441Y893963D03*
Y887270D03*
X1227883Y914042D03*
Y907349D03*
X1220441Y917389D03*
Y910696D03*
Y904003D03*
X1227033Y927428D03*
X1227883Y920735D03*
X1221291Y930774D03*
X1220441Y924081D03*
X1227883Y944160D03*
X1227033Y937467D03*
X1220441Y947507D03*
X1221291Y940814D03*
X1227883Y960892D03*
Y950853D03*
X1220441Y964239D03*
Y954200D03*
X1227883Y974278D03*
Y967585D03*
X1220441Y977625D03*
Y970932D03*
X1227883Y980971D03*
Y987664D03*
X1220441Y991011D03*
Y984318D03*
X1227883Y1027822D03*
X1220441Y1031168D03*
X1227883Y1017782D03*
X1220441D03*
Y1024475D03*
X1227883Y1047900D03*
Y1041207D03*
Y1034515D03*
X1220441Y1044554D03*
Y1037861D03*
X1227883Y1061286D03*
Y1054593D03*
X1220441Y1051247D03*
Y1057940D03*
X1227033Y1074672D03*
Y1067979D03*
X1221291Y1078018D03*
X1220441Y1064633D03*
Y1071326D03*
X1227883Y1091404D03*
Y1084711D03*
X1220441Y1094751D03*
X1221291Y1088058D03*
X1227883Y1104790D03*
X1227033Y1111483D03*
X1227883Y1098097D03*
X1220441Y1108137D03*
Y1101444D03*
X1227883Y1128215D03*
X1227033Y1121522D03*
X1221291Y1124869D03*
X1220441Y1114829D03*
X1227883Y1134908D03*
Y1141601D03*
X1220441Y1144948D03*
Y1138255D03*
X1221291Y1131562D03*
X1227883Y1158333D03*
Y1148294D03*
X1220441Y1151641D03*
Y1161680D03*
X1227883Y1171719D03*
Y1165026D03*
X1220441Y1175066D03*
Y1168373D03*
X1227883Y1185105D03*
Y1178412D03*
X1220441Y1188452D03*
Y1181759D03*
X1227883Y1208530D03*
Y1201837D03*
X1227033Y1195144D03*
X1220441Y1205184D03*
Y1198491D03*
X1227033Y1221916D03*
X1227883Y1215223D03*
X1221291Y1225263D03*
X1220441Y1218570D03*
Y1211877D03*
X1227883Y1238648D03*
X1227033Y1231955D03*
X1220441Y1241995D03*
X1221291Y1235302D03*
X1220441Y1248688D03*
X1227883Y1245341D03*
X1220601Y1269684D03*
X1220931Y1260093D03*
X1233327Y1274515D03*
X1231377Y1275855D03*
X1218692Y1578182D03*
X1226492D03*
X1230752D03*
X1218692Y1590094D03*
X1226492D03*
X1230752D03*
X1219732Y1614292D03*
Y1602380D03*
X1231792Y1614292D03*
Y1602380D03*
X1223992D03*
Y1614292D03*
X1236583Y766798D03*
Y780184D03*
Y773491D03*
Y803609D03*
Y796916D03*
Y790223D03*
X1237433Y816995D03*
X1236583Y810302D03*
Y833727D03*
X1237433Y827034D03*
X1236583Y847113D03*
Y840420D03*
X1237433Y863845D03*
Y853806D03*
X1236583Y870538D03*
Y883924D03*
Y877231D03*
Y900656D03*
Y890617D03*
Y914042D03*
Y907349D03*
X1237433Y927428D03*
X1236583Y920735D03*
Y944160D03*
X1237433Y937467D03*
X1236583Y960892D03*
Y950853D03*
Y974278D03*
Y967585D03*
Y980971D03*
Y987664D03*
Y1027822D03*
Y1017782D03*
Y1047900D03*
Y1041207D03*
Y1034515D03*
Y1061286D03*
Y1054593D03*
X1237433Y1074672D03*
Y1067979D03*
X1236583Y1091404D03*
Y1084711D03*
Y1104790D03*
X1237433Y1111483D03*
X1236583Y1098097D03*
Y1128215D03*
X1237433Y1121522D03*
X1236583Y1134908D03*
Y1141601D03*
Y1158333D03*
Y1148294D03*
Y1171719D03*
Y1165026D03*
Y1185105D03*
Y1178412D03*
Y1208530D03*
Y1201837D03*
Y1195144D03*
X1237433Y1221916D03*
X1236583Y1215223D03*
Y1238648D03*
X1237433Y1231955D03*
X1236583Y1245341D03*
X1238552Y1578182D03*
X1242812D03*
X1238552Y1590094D03*
X1242812D03*
X1236052Y1602380D03*
Y1614292D03*
X1243852D03*
Y1602380D03*
X1248112D03*
Y1614292D03*
X1241142Y1675383D03*
Y1679920D03*
X1249016Y1679320D03*
X1241142Y1684454D03*
Y1689556D03*
Y1694093D03*
Y1698627D03*
X1249016Y1688391D03*
Y1693493D03*
Y1698030D03*
Y1683857D03*
X1241142Y1703729D03*
Y1708266D03*
Y1712800D03*
X1249016Y1707666D03*
Y1712203D03*
Y1702564D03*
X1241142Y1726974D03*
Y1722440D03*
Y1717903D03*
X1249016Y1730911D03*
Y1726377D03*
Y1721840D03*
Y1716737D03*
X1250612Y1578182D03*
X1262672D03*
X1254872D03*
X1250612Y1590094D03*
X1262672D03*
X1254872D03*
X1255912Y1614292D03*
Y1602380D03*
X1260172D03*
Y1614292D03*
X1256890Y1675383D03*
Y1679920D03*
X1264764Y1679320D03*
X1256890Y1684454D03*
Y1689556D03*
Y1694093D03*
Y1698627D03*
X1264764Y1688391D03*
Y1693493D03*
Y1698030D03*
Y1683857D03*
X1256890Y1703729D03*
Y1708266D03*
Y1712800D03*
X1264764Y1707666D03*
Y1712203D03*
Y1702564D03*
X1256890Y1726974D03*
Y1722440D03*
Y1717903D03*
X1264764Y1730911D03*
Y1726377D03*
Y1721840D03*
Y1716737D03*
X1266932Y1578182D03*
X1274732D03*
X1278992D03*
X1266932Y1590094D03*
X1274732D03*
X1278992D03*
X1267972Y1614292D03*
Y1602380D03*
X1272232D03*
Y1614292D03*
X1280032D03*
Y1602380D03*
X1272638Y1675383D03*
Y1679920D03*
X1280512Y1679320D03*
X1272638Y1684454D03*
Y1689556D03*
Y1694093D03*
Y1698627D03*
X1280512Y1688391D03*
Y1693493D03*
Y1698030D03*
Y1683857D03*
X1272638Y1703729D03*
Y1708266D03*
Y1712800D03*
X1280512Y1707666D03*
Y1712203D03*
Y1702564D03*
X1272638Y1726974D03*
Y1722440D03*
Y1717903D03*
X1280512Y1730911D03*
Y1726377D03*
Y1721840D03*
Y1716737D03*
X1286792Y1578182D03*
X1298852D03*
X1291052D03*
X1286792Y1590094D03*
X1298852D03*
X1291052D03*
X1284292Y1602380D03*
Y1614292D03*
X1292092D03*
Y1602380D03*
X1296352D03*
Y1614292D03*
X1296260Y1679320D03*
X1288386Y1675383D03*
Y1679920D03*
X1296260Y1688391D03*
Y1693493D03*
Y1698030D03*
Y1683857D03*
X1288386Y1684454D03*
Y1689556D03*
Y1694093D03*
Y1698627D03*
X1296260Y1707666D03*
Y1712203D03*
Y1702564D03*
X1288386Y1703729D03*
Y1708266D03*
Y1712800D03*
X1296260Y1730911D03*
Y1726377D03*
Y1721840D03*
Y1716737D03*
X1288386Y1726974D03*
Y1722440D03*
Y1717903D03*
X1314353Y1124651D03*
X1303112Y1578182D03*
X1310912D03*
X1315172D03*
X1303112Y1590094D03*
X1310912D03*
X1315172D03*
X1304152Y1602380D03*
Y1614292D03*
X1308412Y1602380D03*
Y1614292D03*
X1308071Y1675383D03*
Y1679920D03*
Y1684454D03*
Y1689556D03*
Y1694093D03*
Y1698627D03*
Y1703729D03*
Y1708266D03*
Y1712800D03*
Y1726974D03*
Y1722440D03*
Y1717903D03*
X1328721Y854584D03*
X1323171Y870606D03*
Y889832D03*
X1319849Y1091513D03*
X1318053Y1124651D03*
X1321753Y1131060D03*
X1322972Y1578182D03*
X1327232D03*
X1322972Y1590094D03*
X1327232D03*
X1316212Y1614292D03*
Y1602380D03*
X1328272D03*
Y1614292D03*
X1320472Y1602380D03*
Y1614292D03*
X1323819Y1675383D03*
Y1679920D03*
X1315945Y1679320D03*
X1323819Y1684454D03*
Y1689556D03*
Y1694093D03*
Y1698627D03*
X1315945Y1688391D03*
Y1693493D03*
Y1698030D03*
Y1683857D03*
X1323819Y1703729D03*
Y1708266D03*
Y1712800D03*
X1315945Y1707666D03*
Y1712203D03*
Y1702564D03*
X1323819Y1726974D03*
Y1722440D03*
Y1717903D03*
X1315945Y1730911D03*
Y1726377D03*
Y1721840D03*
Y1716737D03*
X1336121Y880219D03*
Y899445D03*
X1347220D03*
X1336121Y918670D03*
X1341671Y941100D03*
X1336121Y937896D03*
X1347220D03*
X1345804Y1006093D03*
X1342104Y1076587D03*
X1335032Y1578182D03*
X1347092D03*
X1339292D03*
X1335032Y1590094D03*
X1347092D03*
X1339292D03*
X1340332Y1602380D03*
Y1614292D03*
X1332532Y1602380D03*
Y1614292D03*
X1344592Y1602380D03*
Y1614292D03*
X1339567Y1675383D03*
Y1679920D03*
X1331693Y1679320D03*
X1347441D03*
X1339567Y1684454D03*
Y1689556D03*
Y1694093D03*
Y1698627D03*
X1331693Y1688391D03*
Y1693493D03*
Y1698030D03*
Y1683857D03*
X1347441Y1688391D03*
Y1693493D03*
Y1698030D03*
Y1683857D03*
X1339567Y1703729D03*
Y1708266D03*
Y1712800D03*
X1331693Y1707666D03*
Y1712203D03*
Y1702564D03*
X1347441Y1707666D03*
Y1712203D03*
Y1702564D03*
X1339567Y1726974D03*
Y1722440D03*
Y1717903D03*
X1331693Y1730911D03*
Y1726377D03*
Y1721840D03*
Y1716737D03*
X1347441Y1730911D03*
Y1726377D03*
Y1721840D03*
Y1716737D03*
X1354620Y931488D03*
X1355053Y1060565D03*
X1351352Y1578182D03*
X1359152D03*
X1363412D03*
X1351352Y1590094D03*
X1359152D03*
X1363412D03*
X1352392Y1602380D03*
Y1614292D03*
X1356652Y1602380D03*
Y1614292D03*
X1363189Y1679320D03*
X1355315Y1675383D03*
Y1679920D03*
X1363189Y1688391D03*
Y1693493D03*
Y1698030D03*
Y1683857D03*
X1355315Y1684454D03*
Y1689556D03*
Y1694093D03*
Y1698627D03*
X1363189Y1707666D03*
Y1712203D03*
Y1702564D03*
X1355315Y1703729D03*
Y1708266D03*
Y1712800D03*
X1363189Y1730911D03*
Y1726377D03*
Y1721840D03*
Y1716737D03*
X1355315Y1726974D03*
Y1722440D03*
Y1717903D03*
X1373120Y899445D03*
Y931488D03*
Y937896D03*
X1371212Y1578088D03*
X1375472Y1578182D03*
X1371212Y1590094D03*
X1375472D03*
X1364452Y1602380D03*
Y1614292D03*
X1376512Y1602286D03*
Y1614292D03*
X1368712Y1602380D03*
Y1614292D03*
X1393716Y985579D03*
X1391326D03*
Y1014539D03*
X1393716D03*
X1393903Y1115039D03*
X1392053Y1118243D03*
X1390203Y1121447D03*
X1388353Y1124651D03*
Y1118243D03*
X1390204Y1134264D03*
X1388354Y1131060D03*
X1383272Y1578182D03*
Y1590094D03*
X1380772Y1602380D03*
Y1614292D03*
X1388572D03*
Y1602380D03*
X1411971Y851380D03*
Y864197D03*
Y877014D03*
Y889832D03*
Y902649D03*
X1404571Y921875D03*
X1410121Y944304D03*
Y957122D03*
Y950713D03*
Y963530D03*
Y976347D03*
Y969939D03*
Y982756D03*
X1410553Y1009297D03*
Y1002888D03*
Y1028523D03*
Y1022114D03*
Y1015705D03*
X1405004Y1044544D03*
X1410553Y1034931D03*
X1406854Y1047749D03*
X1399453D03*
X1408703Y1050952D03*
X1401304Y1057361D03*
X1410553Y1060565D03*
Y1054157D03*
X1408703Y1076587D03*
X1406853Y1073383D03*
X1403153D03*
Y1066974D03*
X1401304Y1076587D03*
X1399453Y1066974D03*
X1410553Y1073383D03*
Y1066974D03*
X1403154Y1079791D03*
X1410553D03*
X1408703Y1089404D03*
Y1082995D03*
X1405003D03*
X1401304Y1089404D03*
X1410553Y1092608D03*
Y1086200D03*
X1408703Y1095813D03*
X1405003D03*
X1403153Y1099017D03*
X1401303Y1102221D03*
X1399453Y1105426D03*
X1397604Y1108630D03*
X1410553Y1105426D03*
X1399453Y1111834D03*
X1410553D03*
X1399453Y1124651D03*
Y1118243D03*
X1397604Y1115039D03*
X1410553Y1124651D03*
Y1118243D03*
X1399454Y1137469D03*
X1399453Y1131060D03*
X1410554Y1137769D03*
X1410553Y1131060D03*
X1426771Y851380D03*
Y877014D03*
X1413820Y912262D03*
X1423070Y941100D03*
X1423071Y947509D03*
Y960326D03*
Y953917D03*
Y966735D03*
Y979552D03*
Y973143D03*
X1423503Y1006093D03*
Y999684D03*
Y1012501D03*
Y1025318D03*
Y1018910D03*
Y1031727D03*
X1429053Y1041340D03*
X1423503Y1038136D03*
X1429053Y1092608D03*
X1427204Y1089404D03*
X1427203Y1095812D03*
X1429053Y1099017D03*
X1423503Y1108630D03*
Y1102221D03*
Y1121447D03*
Y1115039D03*
Y1127856D03*
Y1134264D03*
X1432320Y912262D03*
X1437871Y921875D03*
X1438402Y942151D03*
X1440702D03*
X1443002D03*
X1430564Y949138D03*
X1440015Y956539D03*
X1430564Y951438D03*
X1442413Y956539D03*
X1430534Y963828D03*
Y966128D03*
X1440015Y971139D03*
X1442413Y971099D03*
X1430404Y981208D03*
Y978908D03*
X1440015Y985579D03*
X1430604Y995298D03*
Y992998D03*
X1442413Y985579D03*
X1440015Y1014539D03*
Y1000059D03*
X1430584Y1009408D03*
Y1007108D03*
X1442413Y1014539D03*
Y1000059D03*
X1436454Y1105426D03*
X1434604Y1102221D03*
X1432753Y1099017D03*
X1440154Y1105426D03*
X1438304Y1108630D03*
X1440154Y1111834D03*
X1434604Y1121447D03*
Y1115039D03*
X1443854Y1124651D03*
X1443853Y1118243D03*
X1442004Y1121447D03*
Y1115039D03*
X1434604Y1127856D03*
Y1134264D03*
X1450820Y899445D03*
Y912262D03*
X1445703Y1115039D03*
X1447553Y1118243D03*
X1445704Y1127856D03*
X1445703Y1140973D03*
X1447554Y1137469D03*
Y1131060D03*
X1460095Y1578182D03*
Y1590094D03*
X1465620Y912262D03*
X1471604Y1108630D03*
X1469753Y1111834D03*
X1472155Y1578182D03*
X1467895D03*
X1472155Y1590094D03*
X1467895D03*
X1477455Y1602380D03*
Y1614292D03*
X1473195D03*
Y1602380D03*
X1465395D03*
Y1614292D03*
X1484120Y937896D03*
X1485971Y947509D03*
X1491953Y1086200D03*
X1492015Y1578182D03*
X1484215D03*
X1479955D03*
X1492015Y1590094D03*
X1484215D03*
X1479955D03*
X1489515Y1614292D03*
Y1602380D03*
X1485255D03*
Y1614292D03*
X1508335Y1578182D03*
X1496275D03*
X1504075D03*
X1508335Y1590094D03*
X1496275D03*
X1504075D03*
X1501575Y1614292D03*
Y1602380D03*
X1509375D03*
Y1614292D03*
X1497315Y1602380D03*
Y1614292D03*
X1505315Y1675383D03*
Y1679920D03*
Y1684454D03*
Y1689556D03*
Y1694093D03*
Y1698627D03*
Y1703729D03*
Y1708266D03*
Y1712800D03*
Y1726974D03*
Y1722440D03*
Y1717903D03*
X1511871Y928283D03*
X1519271D03*
X1515571D03*
X1524820Y925079D03*
X1513720D03*
X1524820Y944304D03*
X1513720D03*
X1520395Y1578182D03*
X1516135D03*
X1520395Y1590094D03*
X1516135D03*
X1525695Y1614292D03*
Y1602380D03*
X1521435D03*
Y1614292D03*
X1513635D03*
Y1602380D03*
X1521063Y1675383D03*
Y1679920D03*
X1513189Y1679320D03*
X1521063Y1684454D03*
Y1689556D03*
Y1694093D03*
Y1698627D03*
X1513189Y1688391D03*
Y1693493D03*
Y1698030D03*
Y1683857D03*
X1521063Y1703729D03*
Y1708266D03*
Y1712800D03*
X1513189Y1707666D03*
Y1712203D03*
Y1702564D03*
X1521063Y1726974D03*
Y1722440D03*
Y1717903D03*
X1513189Y1730911D03*
Y1726377D03*
Y1721840D03*
Y1716737D03*
X1540255Y1578182D03*
X1532455D03*
X1528195D03*
X1540255Y1590094D03*
X1532455D03*
X1528195D03*
X1537755Y1614292D03*
Y1602380D03*
X1533495D03*
Y1614292D03*
X1536811Y1675383D03*
Y1679920D03*
X1528937Y1679320D03*
X1536811Y1684454D03*
Y1689556D03*
Y1694093D03*
Y1698627D03*
X1528937Y1688391D03*
Y1693493D03*
Y1698030D03*
Y1683857D03*
X1536811Y1703729D03*
Y1708266D03*
Y1712800D03*
X1528937Y1707666D03*
Y1712203D03*
Y1702564D03*
X1536811Y1726974D03*
Y1722440D03*
Y1717903D03*
X1528937Y1730911D03*
Y1726377D03*
Y1721840D03*
Y1716737D03*
X1556575Y1578182D03*
X1544515D03*
X1552315D03*
X1556575Y1590094D03*
X1544515D03*
X1552315D03*
X1549815Y1614292D03*
Y1602380D03*
X1557615D03*
Y1614292D03*
X1545555Y1602380D03*
Y1614292D03*
X1552559Y1675383D03*
Y1679920D03*
X1544685Y1679320D03*
X1552559Y1684454D03*
Y1689556D03*
Y1694093D03*
Y1698627D03*
X1544685Y1688391D03*
Y1693493D03*
Y1698030D03*
Y1683857D03*
X1552559Y1703729D03*
Y1708266D03*
Y1712800D03*
X1544685Y1707666D03*
Y1712203D03*
Y1702564D03*
X1552559Y1726974D03*
Y1722440D03*
Y1717903D03*
X1544685Y1730911D03*
Y1726377D03*
Y1721840D03*
Y1716737D03*
X1568635Y1578182D03*
X1564375D03*
X1568635Y1590094D03*
X1564375D03*
X1573935Y1614292D03*
Y1602380D03*
X1569675Y1614292D03*
Y1602380D03*
X1561875Y1614292D03*
Y1602380D03*
X1560433Y1679320D03*
X1572244Y1675383D03*
Y1679920D03*
X1560433Y1688391D03*
Y1693493D03*
Y1698030D03*
Y1683857D03*
X1572244Y1684454D03*
Y1689556D03*
Y1694093D03*
Y1698627D03*
X1560433Y1707666D03*
Y1712203D03*
Y1702564D03*
X1572244Y1703729D03*
Y1708266D03*
Y1712800D03*
X1560433Y1730911D03*
Y1726377D03*
Y1721840D03*
Y1716737D03*
X1572244Y1726974D03*
Y1722440D03*
Y1717903D03*
X1588495Y1578182D03*
X1580695D03*
X1576435D03*
X1588495Y1590094D03*
X1580695D03*
X1576435D03*
X1585995Y1614292D03*
Y1602380D03*
X1581735D03*
Y1614292D03*
X1587992Y1675383D03*
Y1679920D03*
X1580118Y1679320D03*
X1587992Y1684454D03*
Y1689556D03*
Y1694093D03*
Y1698627D03*
X1580118Y1688391D03*
Y1693493D03*
Y1698030D03*
Y1683857D03*
X1587992Y1703729D03*
Y1708266D03*
Y1712800D03*
X1580118Y1707666D03*
Y1712203D03*
Y1702564D03*
X1587992Y1726974D03*
Y1722440D03*
Y1717903D03*
X1580118Y1730911D03*
Y1726377D03*
Y1721840D03*
Y1716737D03*
X1597041Y770144D03*
X1605741D03*
Y776837D03*
X1597041D03*
X1605741Y783530D03*
X1597041D03*
X1605741Y793570D03*
X1597041D03*
X1596988Y800263D03*
X1605741D03*
X1595774Y806955D03*
X1606934D03*
X1596218Y813648D03*
X1606735D03*
X1597041Y820341D03*
X1605741D03*
X1597041Y830381D03*
X1605741D03*
Y837074D03*
X1597041D03*
Y843766D03*
X1605741D03*
X1596147Y850459D03*
X1606896D03*
X1596200Y857152D03*
X1606623D03*
X1597041Y867192D03*
X1605741D03*
X1597041Y873885D03*
X1605741D03*
X1597041Y880577D03*
X1605741D03*
X1597041Y887270D03*
X1605741D03*
X1606898Y893963D03*
X1597041D03*
X1605741Y904003D03*
X1597041D03*
Y917389D03*
X1605741D03*
X1597041Y910696D03*
X1605741D03*
X1597041Y924081D03*
X1605741D03*
X1606541Y930697D03*
X1596047Y930774D03*
X1596106Y940814D03*
X1606919D03*
X1605741Y947507D03*
X1597041D03*
X1605741Y954200D03*
X1597041D03*
Y964239D03*
X1605741D03*
X1597041Y977625D03*
X1605741D03*
Y970932D03*
X1597041D03*
Y984318D03*
X1605741D03*
X1597041Y991011D03*
X1605741D03*
X1597041Y1024475D03*
X1605741D03*
X1597041Y1017782D03*
X1605741D03*
X1597041Y1031168D03*
X1605741D03*
X1597041Y1037861D03*
X1605741D03*
X1597041Y1044554D03*
X1605741D03*
Y1051247D03*
X1597041D03*
Y1057940D03*
X1605741D03*
X1597041Y1064633D03*
X1605741D03*
X1606541Y1071326D03*
X1596141D03*
X1597041Y1078018D03*
X1605741D03*
Y1094751D03*
X1597041D03*
Y1088058D03*
X1605741D03*
Y1101444D03*
X1597041D03*
Y1108137D03*
X1605741D03*
X1606541Y1114829D03*
X1596241D03*
X1596511Y1124969D03*
X1606505Y1124674D03*
X1605741Y1138255D03*
X1597041D03*
X1605741Y1144948D03*
X1597041D03*
Y1131562D03*
X1605741D03*
Y1151641D03*
X1597041D03*
X1596653Y1161680D03*
X1605975Y1161581D03*
X1605741Y1168373D03*
X1597041D03*
X1605741Y1175066D03*
X1597041D03*
X1605741Y1181759D03*
X1597041D03*
X1606765Y1188452D03*
X1597041D03*
Y1198491D03*
X1605741D03*
Y1205184D03*
X1597041D03*
Y1211877D03*
X1605741D03*
X1597041Y1218570D03*
X1605741D03*
X1597041Y1225263D03*
X1605741D03*
X1607064Y1235302D03*
X1596178D03*
X1605741Y1241995D03*
X1597041D03*
Y1248688D03*
X1605741D03*
X1603788Y1273144D03*
X1601388D03*
X1604815Y1578182D03*
X1592755D03*
X1600555D03*
X1604815Y1590094D03*
X1592755D03*
X1600555D03*
X1598055Y1614292D03*
Y1602380D03*
X1605855Y1614292D03*
Y1602380D03*
X1593795Y1614292D03*
Y1602380D03*
X1603740Y1675383D03*
Y1679920D03*
X1595866Y1679320D03*
X1603740Y1684454D03*
Y1689556D03*
Y1694093D03*
Y1698627D03*
X1595866Y1688391D03*
Y1693493D03*
Y1698030D03*
Y1683857D03*
X1603740Y1703729D03*
Y1708266D03*
Y1712800D03*
X1595866Y1707666D03*
Y1712203D03*
Y1702564D03*
X1603740Y1726974D03*
Y1722440D03*
Y1717903D03*
X1595866Y1730911D03*
Y1726377D03*
Y1721840D03*
Y1716737D03*
X1613183Y766798D03*
X1621883D03*
Y773491D03*
X1613183D03*
X1621883Y780184D03*
X1613183D03*
X1621883Y790223D03*
X1613183D03*
Y796916D03*
X1621883D03*
X1613183Y803609D03*
X1621883D03*
X1622916Y816995D03*
X1613183D03*
X1612363Y810302D03*
X1622986D03*
X1613183Y827034D03*
X1621883D03*
Y833727D03*
X1613183D03*
Y840420D03*
X1621883D03*
X1613183Y847113D03*
X1621943D03*
X1622060Y863845D03*
X1612408D03*
X1612474Y853955D03*
X1622961Y853806D03*
X1621883Y883924D03*
X1613183D03*
Y870538D03*
X1621883D03*
X1613183Y877231D03*
X1621883D03*
X1613183Y890617D03*
X1621883D03*
X1613183Y900656D03*
X1621883D03*
Y907349D03*
X1613183D03*
Y914042D03*
X1621883D03*
Y920735D03*
X1613183D03*
X1622535Y927526D03*
X1612168Y927428D03*
X1622845Y937467D03*
X1612312D03*
X1621883Y944160D03*
X1613183D03*
X1621883Y950853D03*
X1613183D03*
X1621883Y960892D03*
X1613183D03*
Y974278D03*
X1621883D03*
X1613183Y980971D03*
X1621883D03*
X1613183Y967585D03*
X1621883D03*
X1613183Y987664D03*
X1621883D03*
Y1017782D03*
X1613183D03*
Y1027822D03*
X1621883D03*
X1613183Y1034515D03*
X1621883D03*
X1613183Y1041207D03*
X1621883D03*
X1613183Y1047900D03*
X1621883D03*
Y1054593D03*
X1613183D03*
Y1061286D03*
X1621883D03*
Y1067979D03*
X1612983D03*
X1612283Y1074672D03*
X1622683D03*
X1621883Y1084711D03*
X1612383D03*
X1613183Y1091404D03*
X1621883D03*
Y1104790D03*
X1613183D03*
X1621883Y1098097D03*
X1613183D03*
X1621883Y1111483D03*
X1613183D03*
Y1128915D03*
X1621883Y1128215D03*
X1613183Y1121522D03*
X1621883D03*
Y1141601D03*
X1613183D03*
X1622726Y1135108D03*
X1611886Y1134908D03*
X1621883Y1158333D03*
X1613183D03*
X1621883Y1148294D03*
X1613183D03*
X1621883Y1165026D03*
X1613183D03*
Y1171719D03*
X1621883D03*
Y1178412D03*
X1613183D03*
X1621883Y1185105D03*
X1613183D03*
Y1195144D03*
X1621883D03*
Y1201837D03*
X1613183D03*
X1621883Y1208530D03*
X1613183D03*
X1621883Y1215223D03*
X1613183D03*
X1612147Y1221916D03*
X1622712D03*
X1612137Y1231862D03*
X1622681Y1231955D03*
X1621883Y1238648D03*
X1613183D03*
X1610150Y1257172D03*
X1621883Y1245341D03*
X1613183D03*
X1618888Y1273344D03*
X1616088D03*
X1616875Y1578182D03*
X1612615D03*
X1616875Y1590094D03*
X1612615D03*
X1622175Y1614292D03*
Y1602380D03*
X1617915Y1614292D03*
Y1602380D03*
X1610115Y1614292D03*
Y1602380D03*
X1619488Y1675383D03*
Y1679920D03*
X1611614Y1679320D03*
X1619488Y1684454D03*
Y1689556D03*
Y1694093D03*
Y1698627D03*
X1611614Y1688391D03*
Y1693493D03*
Y1698030D03*
Y1683857D03*
X1619488Y1703729D03*
Y1708266D03*
Y1712800D03*
X1611614Y1707666D03*
Y1712203D03*
Y1702564D03*
X1619488Y1726974D03*
Y1722440D03*
Y1717903D03*
X1611614Y1730911D03*
Y1726377D03*
Y1721840D03*
Y1716737D03*
X1626741Y770144D03*
X1635441D03*
X1626741Y776837D03*
X1635441D03*
X1626741Y783530D03*
X1635441D03*
X1626741Y793570D03*
X1635441D03*
Y800263D03*
X1626741D03*
X1636341Y820341D03*
X1626741D03*
X1636574Y813648D03*
X1626741D03*
X1635441Y806955D03*
X1626741D03*
X1635441Y830381D03*
X1626741D03*
X1635441Y837074D03*
X1626741D03*
Y843766D03*
X1635441D03*
Y850459D03*
X1626741D03*
X1625705Y867192D03*
X1636441D03*
X1635441Y857152D03*
X1626741D03*
Y880577D03*
X1635441D03*
Y873885D03*
X1626741D03*
Y887270D03*
X1635441D03*
X1626741Y893963D03*
X1635441D03*
X1626741Y904003D03*
X1635441D03*
Y910696D03*
X1626741D03*
X1635441Y917389D03*
X1626741D03*
X1636316Y930774D03*
X1625803D03*
X1636646Y924081D03*
X1626741D03*
X1635441Y940814D03*
X1626741D03*
X1635441Y947507D03*
X1626741D03*
X1635441Y954200D03*
X1626741D03*
Y964239D03*
X1635441D03*
Y977625D03*
X1626741D03*
X1635441Y970932D03*
X1626741D03*
X1635441Y984318D03*
X1626741D03*
Y991011D03*
X1635441D03*
Y1024475D03*
X1626741D03*
X1635441Y1017782D03*
X1626741D03*
X1635441Y1031168D03*
X1626741D03*
X1635441Y1037861D03*
X1626741D03*
X1635441Y1044554D03*
X1626741D03*
Y1057940D03*
X1635441D03*
Y1051247D03*
X1626741D03*
X1635441Y1064633D03*
X1626741D03*
X1635441Y1071326D03*
X1626741D03*
X1636241Y1078018D03*
X1625941D03*
Y1088058D03*
X1636241D03*
X1635441Y1094751D03*
X1626741D03*
Y1101444D03*
X1635441D03*
X1626741Y1108137D03*
X1635441D03*
X1626074Y1124640D03*
X1636341Y1124869D03*
X1635441Y1114829D03*
X1626741D03*
X1635441Y1144948D03*
X1626741D03*
X1635441Y1138255D03*
X1626741D03*
X1635441Y1130762D03*
X1626741D03*
Y1161680D03*
X1635441D03*
Y1151641D03*
X1626741D03*
Y1168373D03*
X1635441D03*
X1626741Y1175066D03*
X1635441D03*
X1626741Y1181759D03*
X1635441D03*
X1626741Y1188452D03*
X1635441D03*
X1626741Y1198491D03*
X1635441D03*
X1626741Y1205184D03*
X1635441D03*
Y1211877D03*
X1626741D03*
X1635441Y1218570D03*
X1626741D03*
X1636212Y1225263D03*
X1626055D03*
X1636376Y1235302D03*
X1625843D03*
X1635441Y1241995D03*
X1626741D03*
X1635688Y1257664D03*
X1626741Y1248688D03*
X1635441D03*
X1629788Y1273344D03*
X1632588D03*
X1625729Y1266766D03*
X1636735Y1578088D03*
X1628935Y1578182D03*
X1624675D03*
X1636735Y1590094D03*
X1628935D03*
X1624675D03*
X1634235Y1614292D03*
Y1602380D03*
X1629975Y1614292D03*
Y1602380D03*
X1627362Y1679320D03*
Y1688391D03*
Y1693493D03*
Y1698030D03*
Y1683857D03*
Y1707666D03*
Y1712203D03*
Y1702564D03*
Y1730911D03*
Y1726377D03*
Y1721840D03*
Y1716737D03*
X1651583Y766798D03*
X1642883D03*
X1656441Y770144D03*
Y776837D03*
X1642883Y773491D03*
X1651583D03*
X1642883Y780184D03*
X1651583D03*
X1656441Y783530D03*
Y793570D03*
X1642883Y790223D03*
X1651583D03*
X1642883Y796916D03*
X1651583D03*
X1656441Y800263D03*
X1651583Y803609D03*
X1642883D03*
X1656441Y806955D03*
Y813648D03*
Y820341D03*
X1651583Y810302D03*
X1642883D03*
X1652545Y816995D03*
X1641945D03*
X1656441Y830381D03*
X1652767Y827034D03*
X1642018D03*
X1651583Y833727D03*
X1642883D03*
X1656441Y837074D03*
Y843766D03*
X1642883Y840420D03*
X1651583D03*
X1656441Y850459D03*
X1651583Y847113D03*
X1642883D03*
X1642058Y863845D03*
X1652742D03*
X1656441Y857152D03*
Y867192D03*
X1652559Y853806D03*
X1642032D03*
X1656441Y873885D03*
Y880577D03*
X1642883Y883924D03*
X1651583D03*
Y870538D03*
X1642883D03*
X1651583Y877231D03*
X1642883D03*
X1656441Y887270D03*
Y893963D03*
X1642883Y890617D03*
X1651583D03*
X1642883Y900656D03*
X1651583D03*
X1656441Y904003D03*
Y910696D03*
X1642883Y907349D03*
X1651583D03*
X1656441Y917389D03*
X1651583Y914042D03*
X1642883D03*
X1656441Y924081D03*
Y930774D03*
X1652630Y927428D03*
X1642038D03*
X1651583Y920735D03*
X1642883D03*
X1656441Y940814D03*
Y947507D03*
X1652501Y937467D03*
X1642065D03*
X1651583Y944160D03*
X1642883D03*
X1656441Y954200D03*
X1642883Y950853D03*
X1651583D03*
Y960892D03*
X1642883D03*
X1656441Y964239D03*
Y977625D03*
Y970932D03*
X1651583Y967585D03*
X1642883D03*
X1651583Y974278D03*
X1642883D03*
X1651583Y980971D03*
X1642883D03*
X1656441Y984318D03*
Y991011D03*
X1651583Y987664D03*
X1642883D03*
X1651583Y1017782D03*
X1642883D03*
X1656441D03*
Y1024475D03*
X1651583Y1027822D03*
X1642883D03*
X1656441Y1031168D03*
Y1044554D03*
Y1037861D03*
X1651583Y1034515D03*
X1642883D03*
X1651583Y1041207D03*
X1642883D03*
X1651583Y1047900D03*
X1642883D03*
Y1061286D03*
X1651583D03*
X1656441Y1051247D03*
Y1057940D03*
X1651583Y1054593D03*
X1642883D03*
X1656441Y1064633D03*
Y1071326D03*
Y1078018D03*
X1652483Y1074672D03*
X1641983D03*
X1651583Y1067979D03*
X1642883D03*
X1656441Y1088058D03*
Y1094751D03*
X1652383Y1084711D03*
X1642083D03*
X1651583Y1091404D03*
X1642883D03*
X1656441Y1101444D03*
Y1108137D03*
X1642883Y1098097D03*
X1651583D03*
X1642883Y1104790D03*
X1651583D03*
X1642883Y1111483D03*
X1651583D03*
X1656441Y1114829D03*
Y1124869D03*
X1642883Y1121522D03*
X1651583D03*
X1642883Y1128215D03*
X1651583D03*
X1656441Y1131562D03*
Y1138255D03*
X1642883Y1134908D03*
X1651583D03*
X1642883Y1141601D03*
X1651583D03*
X1656441Y1144948D03*
Y1151641D03*
Y1161680D03*
X1652383Y1158333D03*
X1642083D03*
X1652794Y1148294D03*
X1641744D03*
X1656441Y1168373D03*
Y1175066D03*
X1642883Y1171719D03*
X1651583D03*
Y1165026D03*
X1642883D03*
X1656441Y1181759D03*
Y1188452D03*
X1651583Y1178412D03*
X1642883D03*
X1651583Y1185105D03*
X1642883D03*
X1656441Y1198491D03*
Y1205184D03*
X1642883Y1195144D03*
X1651583D03*
X1642883Y1201837D03*
X1651583D03*
X1642883Y1208530D03*
X1651583D03*
X1656441Y1211877D03*
X1652590Y1221916D03*
X1641793D03*
X1656441Y1225263D03*
Y1218570D03*
X1651583Y1215223D03*
X1642883D03*
X1656441Y1235302D03*
Y1241995D03*
X1652604Y1231955D03*
X1642054D03*
X1651583Y1238648D03*
X1642883D03*
X1656441Y1248688D03*
X1651583Y1245341D03*
X1642883D03*
X1648588Y1273344D03*
X1645788D03*
X1640995Y1578182D03*
X1648795D03*
X1640995Y1590094D03*
X1648795D03*
X1646295Y1614292D03*
Y1602380D03*
X1654095Y1614292D03*
Y1602380D03*
X1642035Y1614292D03*
Y1602286D03*
X1665141Y770144D03*
X1672583Y766798D03*
X1665141Y776837D03*
Y783530D03*
X1672583Y773491D03*
Y780184D03*
X1665141Y793570D03*
Y800263D03*
X1672583Y790223D03*
Y796916D03*
Y803609D03*
X1665141Y806955D03*
Y813648D03*
X1666030Y820341D03*
X1672583Y810302D03*
Y816995D03*
X1665141Y830381D03*
X1672583Y827034D03*
Y833727D03*
X1665141Y837074D03*
Y843766D03*
X1672583Y840420D03*
X1665141Y850459D03*
X1672583Y847113D03*
X1666038Y857152D03*
X1665141Y867192D03*
X1672583Y853806D03*
Y863845D03*
X1665141Y873885D03*
Y880577D03*
X1672583Y870538D03*
Y877231D03*
Y883924D03*
X1665141Y887270D03*
Y893963D03*
X1672583Y890617D03*
Y900656D03*
X1665141Y904003D03*
Y910696D03*
Y917389D03*
X1672583Y907349D03*
Y914042D03*
X1665141Y924081D03*
X1666246Y930774D03*
X1672583Y920735D03*
Y927428D03*
X1665141Y940814D03*
Y947507D03*
X1672583Y937467D03*
Y944160D03*
X1665141Y954200D03*
Y964239D03*
X1672583Y950853D03*
Y960892D03*
X1665141Y977625D03*
Y970932D03*
X1672583Y967585D03*
Y974278D03*
Y980971D03*
X1665141Y984318D03*
Y991011D03*
X1672583Y987664D03*
X1665141Y1017782D03*
Y1024475D03*
Y1031168D03*
X1672583Y1017782D03*
Y1027822D03*
X1665141Y1044554D03*
Y1037861D03*
X1672583Y1034515D03*
Y1041207D03*
Y1047900D03*
X1665141Y1057940D03*
X1672583Y1061286D03*
Y1054593D03*
X1665141Y1064633D03*
Y1071326D03*
Y1077118D03*
X1672583Y1067979D03*
Y1074672D03*
X1665141Y1088058D03*
Y1094751D03*
X1672583Y1084711D03*
Y1091404D03*
X1665141Y1101444D03*
Y1108137D03*
X1672583Y1098097D03*
Y1104790D03*
Y1111483D03*
X1665141Y1114829D03*
Y1124869D03*
X1672583Y1121522D03*
Y1128215D03*
X1665141Y1131562D03*
Y1138255D03*
Y1144948D03*
X1672583Y1134908D03*
Y1141601D03*
X1666141Y1151641D03*
X1665141Y1161680D03*
X1672583Y1148294D03*
Y1158333D03*
X1665141Y1168373D03*
Y1175066D03*
X1672583Y1165026D03*
Y1171719D03*
X1665141Y1181759D03*
Y1188452D03*
X1672583Y1178412D03*
Y1185105D03*
X1665141Y1198491D03*
Y1205184D03*
X1672583Y1195144D03*
Y1201837D03*
Y1208530D03*
X1665141Y1211877D03*
X1665941Y1225263D03*
X1665141Y1218570D03*
X1672583Y1215223D03*
Y1221916D03*
X1665141Y1235302D03*
Y1241995D03*
X1672583Y1231955D03*
Y1238648D03*
X1665141Y1248688D03*
X1672583Y1245341D03*
X1665688Y1257964D03*
X1659488Y1273344D03*
X1662288D03*
X1681283Y766798D03*
X1686141Y770144D03*
X1681283Y773491D03*
Y780184D03*
X1686141Y776837D03*
Y783530D03*
X1681283Y790223D03*
Y796916D03*
Y803609D03*
X1686141Y793570D03*
Y800263D03*
X1681283Y810302D03*
Y816995D03*
X1686141Y806955D03*
Y813648D03*
Y820341D03*
X1681283Y827034D03*
Y833727D03*
X1686141Y830381D03*
X1681283Y840420D03*
X1686141Y837074D03*
Y843766D03*
Y850459D03*
X1681283Y847113D03*
X1686141Y857152D03*
Y867192D03*
X1681283Y853806D03*
Y863845D03*
X1686141Y873885D03*
Y880577D03*
X1681283Y870538D03*
Y877231D03*
Y883924D03*
X1686141Y887270D03*
Y893963D03*
X1681283Y890617D03*
Y900656D03*
X1686141Y904003D03*
Y910696D03*
Y917389D03*
X1681283Y907349D03*
Y914042D03*
X1686141Y924081D03*
Y930774D03*
X1681283Y920735D03*
Y927428D03*
X1686141Y940814D03*
Y947507D03*
X1681283Y937467D03*
Y944160D03*
X1686141Y954200D03*
Y964239D03*
X1681283Y950853D03*
Y960892D03*
X1686141Y970932D03*
Y977625D03*
X1681283Y967585D03*
Y974278D03*
Y980971D03*
X1686141Y984318D03*
Y991011D03*
X1681283Y987664D03*
X1686141Y1017782D03*
Y1024475D03*
Y1031168D03*
X1681283Y1017782D03*
Y1027822D03*
X1686141Y1037861D03*
Y1044554D03*
X1681283Y1034515D03*
Y1041207D03*
Y1047900D03*
X1686141Y1051247D03*
Y1057940D03*
X1681283Y1061286D03*
Y1054593D03*
X1686141Y1064633D03*
Y1071326D03*
Y1078018D03*
X1681283Y1067979D03*
Y1074672D03*
X1686141Y1088058D03*
Y1094751D03*
X1681283Y1084711D03*
Y1091404D03*
X1686141Y1101444D03*
Y1108137D03*
X1681283Y1098097D03*
Y1104790D03*
Y1111483D03*
X1686141Y1114829D03*
Y1124869D03*
X1681283Y1121522D03*
Y1128215D03*
X1686141Y1131562D03*
Y1138255D03*
Y1144948D03*
X1681283Y1134908D03*
Y1141601D03*
X1686141Y1151641D03*
Y1161680D03*
X1681283Y1148294D03*
Y1158333D03*
X1686141Y1168373D03*
Y1175066D03*
X1681283Y1165026D03*
Y1171719D03*
X1686141Y1181759D03*
Y1188452D03*
X1681283Y1178412D03*
Y1185105D03*
X1686141Y1198491D03*
Y1205184D03*
X1681283Y1195144D03*
Y1201837D03*
Y1208530D03*
X1686141Y1211877D03*
Y1218570D03*
Y1225263D03*
X1681283Y1215223D03*
Y1221916D03*
Y1231955D03*
Y1238648D03*
X1686141Y1235302D03*
Y1241995D03*
X1681283Y1245341D03*
X1686141Y1248688D03*
X1675488Y1273344D03*
X1678288D03*
X1689188D03*
X1694841Y770144D03*
X1702283Y766798D03*
X1694841Y776837D03*
Y783530D03*
X1702283Y773491D03*
Y780184D03*
X1694841Y793570D03*
Y800263D03*
X1702283Y790223D03*
Y796916D03*
Y803609D03*
X1694841Y806955D03*
Y813648D03*
Y820341D03*
X1702283Y810302D03*
Y816995D03*
X1694841Y830381D03*
X1702283Y827034D03*
Y833727D03*
X1694841Y837074D03*
Y843766D03*
Y850459D03*
X1702283Y840420D03*
Y847113D03*
X1694841Y857152D03*
Y867192D03*
X1702283Y853806D03*
Y863845D03*
X1694841Y873885D03*
Y880577D03*
X1702283Y870538D03*
Y877231D03*
Y883924D03*
X1694841Y887270D03*
Y893963D03*
X1702283Y890617D03*
Y900656D03*
X1694841Y904003D03*
Y910696D03*
Y917389D03*
X1702283Y907349D03*
Y914042D03*
X1694841Y924081D03*
Y930774D03*
X1702283Y920735D03*
Y927428D03*
X1694841Y940814D03*
Y947507D03*
X1702283Y937467D03*
Y944160D03*
X1694841Y954200D03*
Y964239D03*
X1702283Y950853D03*
Y960892D03*
X1694841Y970932D03*
Y977625D03*
X1702283Y967585D03*
Y974278D03*
Y980971D03*
X1694841Y984318D03*
Y991011D03*
X1702283Y987664D03*
X1694841Y1017782D03*
Y1024475D03*
Y1031168D03*
X1702283Y1017782D03*
Y1027822D03*
X1694841Y1037861D03*
Y1044554D03*
X1702283Y1034515D03*
Y1041207D03*
Y1047900D03*
X1694841Y1051247D03*
Y1057940D03*
X1702283Y1054593D03*
Y1061286D03*
X1694841Y1064633D03*
Y1071326D03*
Y1078018D03*
X1702283Y1067979D03*
Y1074672D03*
X1694841Y1088058D03*
Y1094751D03*
X1702283Y1084711D03*
Y1091404D03*
X1694841Y1101444D03*
Y1108137D03*
X1702283Y1098097D03*
Y1104790D03*
Y1111483D03*
X1694841Y1114829D03*
Y1124869D03*
X1702283Y1121522D03*
Y1128215D03*
X1694841Y1131562D03*
Y1138255D03*
Y1144948D03*
X1702283Y1134908D03*
Y1141601D03*
X1694841Y1151641D03*
Y1161680D03*
X1702283Y1148294D03*
Y1158333D03*
X1694841Y1168373D03*
Y1175066D03*
X1702283Y1165026D03*
Y1171719D03*
X1694841Y1181759D03*
Y1188452D03*
X1702283Y1178412D03*
Y1185105D03*
X1694841Y1198491D03*
Y1205184D03*
X1702283Y1195144D03*
Y1201837D03*
Y1208530D03*
X1694841Y1211877D03*
Y1218570D03*
Y1225263D03*
X1702283Y1215223D03*
Y1221916D03*
X1694841Y1235302D03*
Y1241995D03*
X1702283Y1231955D03*
Y1238648D03*
X1694841Y1248688D03*
X1695188Y1257064D03*
X1702283Y1245341D03*
X1691988Y1273344D03*
X1705188D03*
X1710983Y766798D03*
X1715841Y770144D03*
X1710983Y773491D03*
Y780184D03*
X1715841Y783530D03*
Y776837D03*
X1710983Y790223D03*
Y796916D03*
Y803609D03*
X1715841Y793570D03*
Y800263D03*
X1710983Y810302D03*
Y816995D03*
X1715841Y806955D03*
Y813648D03*
Y820341D03*
X1710983Y827034D03*
Y833727D03*
X1715841Y830381D03*
X1710983Y840420D03*
Y847113D03*
X1715841Y837074D03*
Y843766D03*
Y850459D03*
X1710983Y853806D03*
Y863845D03*
X1715841Y857152D03*
Y867192D03*
X1710983Y870538D03*
Y877231D03*
Y883924D03*
X1715841Y873885D03*
Y880577D03*
X1710983Y890617D03*
Y900656D03*
X1715841Y893963D03*
Y887270D03*
X1710983Y907349D03*
Y914042D03*
X1715841Y904003D03*
Y910696D03*
Y917389D03*
X1710983Y920735D03*
Y927428D03*
X1715841Y924081D03*
Y930774D03*
X1710983Y937467D03*
Y944160D03*
X1715841Y940814D03*
Y947507D03*
X1710983Y950853D03*
Y960892D03*
X1715841Y954200D03*
Y964239D03*
X1710983Y967585D03*
Y974278D03*
Y980971D03*
X1715841Y970932D03*
Y977625D03*
X1710983Y987664D03*
X1715841Y984318D03*
Y991011D03*
X1710983Y1017782D03*
Y1027822D03*
X1715841Y1017782D03*
Y1024475D03*
Y1031168D03*
X1710983Y1034515D03*
Y1041207D03*
Y1047900D03*
X1715841Y1037861D03*
Y1044554D03*
X1710983Y1054593D03*
Y1061286D03*
X1715841Y1051247D03*
Y1057940D03*
X1710983Y1067979D03*
Y1074672D03*
X1715841Y1071326D03*
Y1064633D03*
Y1078018D03*
X1710983Y1084711D03*
Y1091404D03*
X1715841Y1088058D03*
Y1094751D03*
X1710983Y1098097D03*
Y1104790D03*
Y1111483D03*
X1715841Y1101444D03*
Y1108137D03*
X1710983Y1121522D03*
Y1128215D03*
X1715841Y1114829D03*
Y1124869D03*
X1710983Y1134908D03*
Y1141601D03*
X1715841Y1131562D03*
Y1138255D03*
Y1144948D03*
X1710983Y1148294D03*
Y1158333D03*
X1715841Y1151641D03*
Y1161680D03*
X1710983Y1165026D03*
Y1171719D03*
X1715841Y1168373D03*
Y1175066D03*
X1710983Y1178412D03*
Y1185105D03*
X1715841Y1181759D03*
Y1188452D03*
X1710983Y1195144D03*
Y1201837D03*
Y1208530D03*
X1715841Y1198491D03*
Y1205184D03*
X1710983Y1215223D03*
Y1221916D03*
X1715841Y1211877D03*
Y1218570D03*
Y1225263D03*
X1710983Y1231955D03*
Y1238648D03*
X1715841Y1235302D03*
Y1241995D03*
X1710983Y1245341D03*
X1715841Y1248688D03*
X1707514Y1273444D03*
X1718888Y1273344D03*
X1721688D03*
X1731983Y766798D03*
X1724541Y770144D03*
X1731983Y773491D03*
Y780184D03*
X1724541Y783530D03*
Y776837D03*
Y793570D03*
Y800263D03*
X1731983Y790223D03*
Y796916D03*
Y803609D03*
X1724541Y806955D03*
Y813648D03*
Y820341D03*
X1731983Y810302D03*
Y816995D03*
X1724541Y830381D03*
X1731983Y827034D03*
Y833727D03*
X1724541Y837074D03*
Y843766D03*
Y850459D03*
X1731983Y840420D03*
Y847113D03*
X1724541Y857152D03*
Y867192D03*
X1731983Y853806D03*
Y863845D03*
X1724541Y873885D03*
Y880577D03*
X1731983Y870538D03*
Y877231D03*
Y883924D03*
X1724541Y893963D03*
Y887270D03*
X1731983Y890617D03*
Y900656D03*
X1724541Y904003D03*
Y910696D03*
Y917389D03*
X1731983Y907349D03*
Y914042D03*
X1724541Y924081D03*
Y930774D03*
X1731983Y920735D03*
Y927428D03*
X1724541Y940814D03*
Y947507D03*
X1731983Y937467D03*
Y944160D03*
X1724541Y954200D03*
Y964239D03*
X1731983Y950853D03*
Y960892D03*
X1724541Y970932D03*
Y977625D03*
X1731983Y967585D03*
Y974278D03*
Y980971D03*
X1724541Y984318D03*
Y991011D03*
X1731983Y987664D03*
X1724541Y1017782D03*
Y1024475D03*
Y1031168D03*
X1731983Y1017782D03*
Y1027822D03*
X1724541Y1037861D03*
Y1044554D03*
X1731983Y1034515D03*
Y1041207D03*
Y1047900D03*
X1724541Y1057940D03*
X1731983Y1054593D03*
Y1061286D03*
X1724541Y1071326D03*
Y1064633D03*
Y1078018D03*
X1731983Y1074672D03*
Y1067979D03*
X1724541Y1088058D03*
Y1094751D03*
X1731983Y1084711D03*
Y1091404D03*
X1724541Y1101444D03*
Y1108137D03*
X1731983Y1098097D03*
Y1104790D03*
Y1111483D03*
X1724541Y1114829D03*
Y1124869D03*
X1731983Y1121522D03*
Y1128215D03*
X1724541Y1131562D03*
Y1138255D03*
Y1144948D03*
X1731983Y1134908D03*
Y1141601D03*
X1724541Y1151641D03*
Y1161680D03*
X1731983Y1148294D03*
Y1158333D03*
X1724541Y1168373D03*
Y1175066D03*
X1731983Y1165026D03*
Y1171719D03*
X1724541Y1181759D03*
Y1188452D03*
X1731983Y1178412D03*
Y1185105D03*
X1724541Y1198491D03*
Y1205184D03*
X1731983Y1195144D03*
Y1201837D03*
Y1208530D03*
X1724541Y1211877D03*
Y1218570D03*
Y1225263D03*
X1731983Y1215223D03*
Y1221916D03*
X1724541Y1235302D03*
Y1241995D03*
X1731983Y1231955D03*
Y1238648D03*
X1724541Y1248688D03*
X1724588Y1257164D03*
X1731983Y1245341D03*
X1734888Y1273344D03*
X1737688D03*
X1740683Y766798D03*
X1745541Y770144D03*
X1754241D03*
X1740683Y773491D03*
Y780184D03*
X1745541Y776837D03*
X1754241D03*
X1745541Y783530D03*
X1754241D03*
X1740683Y790223D03*
Y796916D03*
Y803609D03*
X1745541Y793570D03*
X1754241D03*
X1745541Y800263D03*
X1754241D03*
X1740683Y810302D03*
Y816995D03*
X1745541Y806955D03*
X1754241D03*
X1745541Y813648D03*
X1754241D03*
X1745541Y820341D03*
X1754241D03*
X1740683Y827034D03*
Y833727D03*
X1745541Y830381D03*
X1754241D03*
X1740683Y840420D03*
Y847113D03*
X1754241Y843766D03*
X1745541D03*
Y837074D03*
X1754241D03*
X1745541Y850459D03*
X1754241D03*
X1740683Y853806D03*
Y863845D03*
X1745541Y857152D03*
X1754241D03*
Y867192D03*
X1745541D03*
X1740683Y870538D03*
Y877231D03*
Y883924D03*
X1745541Y873885D03*
X1754241D03*
X1745541Y880577D03*
X1754241D03*
X1740683Y890617D03*
Y900656D03*
X1754241Y893963D03*
X1745541D03*
Y887270D03*
X1754241D03*
X1740683Y907349D03*
Y914042D03*
X1754241Y904003D03*
X1745541D03*
X1754241Y910696D03*
X1745541D03*
X1754241Y917389D03*
X1745541D03*
X1740683Y920735D03*
Y927428D03*
X1754241Y924081D03*
X1745541D03*
X1754241Y930774D03*
X1745541D03*
X1740683Y937467D03*
Y944160D03*
X1754241Y940814D03*
X1745541D03*
X1754241Y947507D03*
X1745541D03*
X1740683Y950853D03*
Y960892D03*
X1754241Y954200D03*
X1745541D03*
X1754241Y964239D03*
X1745541D03*
X1740683Y967585D03*
Y974278D03*
Y980971D03*
X1754241Y970932D03*
X1745541D03*
X1754241Y977625D03*
X1745541D03*
X1740683Y987664D03*
X1754241Y984318D03*
X1745541D03*
X1754241Y991011D03*
X1745541D03*
X1740683Y1017782D03*
Y1027822D03*
X1754241Y1017782D03*
X1745541D03*
Y1024475D03*
X1754241D03*
X1745541Y1031168D03*
X1754241D03*
X1740683Y1034515D03*
Y1041207D03*
Y1047900D03*
X1754241Y1044554D03*
X1745541D03*
Y1037861D03*
X1754241D03*
X1740683Y1054593D03*
Y1061286D03*
X1745541Y1051247D03*
X1754241D03*
X1745541Y1057940D03*
X1754241D03*
X1740683Y1074672D03*
Y1067979D03*
X1754241Y1071326D03*
X1745541D03*
Y1064633D03*
X1754241D03*
Y1078018D03*
X1745541D03*
X1740683Y1084711D03*
Y1091404D03*
X1754241Y1088058D03*
X1745541D03*
X1754241Y1094751D03*
X1745541D03*
X1740683Y1098097D03*
Y1104790D03*
Y1111483D03*
X1754241Y1101444D03*
X1745541D03*
X1754241Y1108137D03*
X1745541D03*
X1740683Y1121522D03*
Y1128215D03*
X1754241Y1114829D03*
X1745541D03*
X1754241Y1124869D03*
X1745541D03*
X1740683Y1134908D03*
Y1141601D03*
X1754241Y1131562D03*
X1745541D03*
X1754241Y1138255D03*
X1745541D03*
X1754241Y1144948D03*
X1745541D03*
X1740683Y1148294D03*
Y1158333D03*
X1754241Y1151641D03*
X1745541D03*
X1754241Y1161680D03*
X1745541D03*
X1740683Y1165026D03*
Y1171719D03*
X1745541Y1175066D03*
X1754241D03*
Y1168373D03*
X1745541D03*
X1740683Y1178412D03*
Y1185105D03*
X1745541Y1181759D03*
X1754241D03*
Y1188452D03*
X1745541D03*
X1740683Y1195144D03*
Y1201837D03*
Y1208530D03*
X1754241Y1198491D03*
X1745541D03*
X1754241Y1205184D03*
X1745541D03*
X1740683Y1215223D03*
Y1221916D03*
X1754241Y1211877D03*
X1745541D03*
X1754241Y1218570D03*
X1745541D03*
X1754241Y1225263D03*
X1745541D03*
X1740683Y1231955D03*
Y1238648D03*
X1754241Y1235302D03*
X1745541D03*
X1754241Y1241995D03*
X1745541D03*
X1740683Y1245341D03*
X1754241Y1248688D03*
X1745541D03*
X1754488Y1257264D03*
X1751388Y1273344D03*
X1748588D03*
X1749088Y1310474D03*
X1746288D03*
X1770383Y766798D03*
X1761683D03*
X1770383Y773491D03*
X1761683D03*
Y780184D03*
X1770383D03*
X1761683Y790223D03*
X1770383D03*
X1761683Y796916D03*
X1770383D03*
X1761683Y803609D03*
X1770383D03*
X1761683Y810302D03*
X1770383D03*
X1761683Y816995D03*
X1770383D03*
X1761683Y827034D03*
X1770383D03*
X1761683Y833727D03*
X1770383D03*
X1761683Y840420D03*
X1770383D03*
X1761683Y847113D03*
X1770383D03*
X1761683Y853806D03*
X1770383D03*
X1761683Y863845D03*
X1770383D03*
X1761683Y870538D03*
X1770383D03*
X1761683Y877231D03*
X1770383D03*
X1761683Y883924D03*
X1770383D03*
X1761683Y890617D03*
X1770383D03*
X1761683Y900656D03*
X1770383D03*
X1761683Y907349D03*
X1770383D03*
X1761683Y914042D03*
X1770383D03*
Y927428D03*
X1761683D03*
Y920735D03*
X1770383D03*
X1761683Y937467D03*
X1770383D03*
X1761683Y944160D03*
X1770383D03*
X1761683Y950853D03*
X1770383D03*
X1761683Y960892D03*
X1770383D03*
X1761683Y967585D03*
X1770383D03*
X1761683Y974278D03*
X1770383D03*
X1761683Y980971D03*
X1770383D03*
X1761683Y987664D03*
X1770383D03*
X1761683Y1017782D03*
X1770383D03*
X1761683Y1027822D03*
X1770383D03*
X1761683Y1034515D03*
X1770383D03*
X1761683Y1041207D03*
X1770383D03*
X1761683Y1047900D03*
X1770383D03*
X1761683Y1054593D03*
X1770383D03*
X1761683Y1061286D03*
X1770383D03*
X1761683Y1067979D03*
X1770383D03*
X1761683Y1074672D03*
X1770383D03*
X1761683Y1084711D03*
X1770383D03*
X1761683Y1091404D03*
X1770383D03*
Y1098097D03*
X1761683D03*
Y1104790D03*
X1770383D03*
X1761683Y1111483D03*
X1770383D03*
X1761683Y1121522D03*
X1770383D03*
X1761683Y1128215D03*
X1770383D03*
X1761683Y1134908D03*
X1770383D03*
X1761683Y1141601D03*
X1770383D03*
X1761683Y1148294D03*
X1770383D03*
X1761683Y1158333D03*
X1770383D03*
X1761683Y1165026D03*
X1770383D03*
X1761683Y1171719D03*
X1770383D03*
X1761683Y1178412D03*
X1770383D03*
X1761683Y1185105D03*
X1770383D03*
X1761683Y1195144D03*
X1770383D03*
X1761683Y1201837D03*
X1770383D03*
X1761683Y1208530D03*
X1770383D03*
X1761683Y1215223D03*
X1770383D03*
X1761683Y1221916D03*
X1770383D03*
X1761683Y1231955D03*
X1770383D03*
X1761683Y1238648D03*
X1770383D03*
X1761683Y1245341D03*
X1770383D03*
X1767388Y1273344D03*
X1764588D03*
X1775241Y770144D03*
X1783941D03*
X1775241Y776837D03*
X1783941D03*
X1775241Y783530D03*
X1783941D03*
X1775241Y793570D03*
X1783941D03*
X1775241Y800263D03*
X1783941D03*
X1775241Y806955D03*
X1783941D03*
X1775241Y813648D03*
X1783941D03*
X1775241Y820341D03*
X1783941D03*
Y830381D03*
X1775241D03*
Y837074D03*
X1783941D03*
X1775241Y843766D03*
X1783941D03*
X1775241Y850459D03*
X1783941D03*
X1775241Y857152D03*
X1783941D03*
X1775241Y867192D03*
X1783941D03*
X1775241Y873885D03*
X1783941D03*
X1775241Y880577D03*
X1783941D03*
X1775241Y887270D03*
X1783941D03*
X1775241Y893963D03*
X1783941D03*
X1775241Y904003D03*
X1783941D03*
X1775241Y910696D03*
X1783941D03*
X1775241Y917389D03*
X1783941D03*
X1775241Y924081D03*
X1783941D03*
X1775241Y930774D03*
X1783941D03*
X1775241Y940814D03*
X1783941D03*
X1775241Y947507D03*
X1783941D03*
X1775241Y954200D03*
X1783941D03*
X1775241Y964239D03*
X1783941D03*
X1775241Y970932D03*
X1783941D03*
X1775241Y977625D03*
X1783941D03*
X1775241Y984318D03*
X1783941D03*
X1775241Y991011D03*
X1783941D03*
X1775241Y1017782D03*
X1783941D03*
X1775241Y1024475D03*
X1783941D03*
X1775241Y1031168D03*
X1783941D03*
X1775241Y1037861D03*
X1783941D03*
X1775241Y1044554D03*
X1783941D03*
X1775241Y1051247D03*
X1783941D03*
X1775241Y1057940D03*
X1783941D03*
X1775241Y1064633D03*
X1783941D03*
X1775241Y1071326D03*
X1783941D03*
X1775241Y1078018D03*
X1783941D03*
X1775241Y1088058D03*
X1783941D03*
X1775241Y1094751D03*
X1783941D03*
X1775241Y1101444D03*
X1783941D03*
X1775241Y1108137D03*
X1783941D03*
X1775241Y1114829D03*
X1783941D03*
X1775241Y1124869D03*
X1783941D03*
X1775241Y1131562D03*
X1783941D03*
X1775241Y1138255D03*
X1783941D03*
X1775241Y1144948D03*
X1783941D03*
Y1151641D03*
X1775241D03*
Y1161680D03*
X1783941D03*
X1775241Y1168373D03*
X1783941D03*
X1775241Y1175066D03*
X1783941D03*
X1775241Y1181759D03*
X1783941D03*
X1775241Y1188452D03*
X1783941D03*
X1775241Y1198491D03*
X1783941D03*
X1775241Y1205184D03*
X1783941D03*
X1775241Y1211877D03*
X1783941D03*
X1775241Y1218570D03*
X1783941D03*
X1775241Y1225263D03*
X1783941D03*
X1775241Y1235302D03*
X1783941D03*
X1775241Y1241995D03*
X1783941D03*
X1784188Y1257664D03*
X1775241Y1248688D03*
X1783941D03*
X1781088Y1273344D03*
X1778288D03*
X1791383Y766798D03*
X1800083D03*
X1791383Y773491D03*
X1800083D03*
X1791383Y780184D03*
X1800083D03*
X1791383Y790223D03*
X1800083D03*
X1791383Y796916D03*
X1800083D03*
X1791383Y803609D03*
X1800083D03*
X1791383Y810302D03*
X1800083D03*
X1791383Y816995D03*
X1800083D03*
X1791383Y827034D03*
X1800083D03*
Y833727D03*
X1791383D03*
Y840420D03*
X1800083D03*
X1791383Y847113D03*
X1800083D03*
X1791383Y853806D03*
X1800083D03*
X1791383Y863845D03*
X1800083D03*
X1791383Y870538D03*
X1800083D03*
X1791383Y877231D03*
X1800083D03*
X1791383Y883924D03*
X1800083D03*
X1791383Y890617D03*
X1800083D03*
X1791383Y900656D03*
X1800083D03*
X1791383Y907349D03*
X1800083D03*
X1791383Y914042D03*
X1800083D03*
X1791383Y920735D03*
X1800083D03*
X1791383Y927428D03*
X1800083D03*
X1791383Y937467D03*
X1800083D03*
X1791383Y944160D03*
X1800083D03*
Y950853D03*
X1791383D03*
Y960892D03*
X1800083D03*
X1791383Y967585D03*
X1800083D03*
X1791383Y974278D03*
X1800083D03*
X1791383Y980971D03*
X1800083D03*
X1791383Y987664D03*
X1800083D03*
X1791383Y1017782D03*
X1800083D03*
X1791383Y1027822D03*
X1800083D03*
X1791383Y1034515D03*
X1800083D03*
X1791383Y1041207D03*
X1800083D03*
X1791383Y1047900D03*
X1800083D03*
X1791383Y1054593D03*
X1800083D03*
X1791383Y1061286D03*
X1800083D03*
X1791383Y1067979D03*
X1800083D03*
X1791383Y1074672D03*
X1800083D03*
X1791383Y1084711D03*
X1800083D03*
X1791383Y1091404D03*
X1800083D03*
X1791383Y1098097D03*
X1800083D03*
X1791383Y1104790D03*
X1800083D03*
X1791383Y1111483D03*
X1800083D03*
X1791383Y1121522D03*
X1800083D03*
X1791383Y1128215D03*
X1800083D03*
Y1134908D03*
X1791383D03*
Y1141601D03*
X1800083D03*
X1791383Y1148294D03*
X1800083D03*
X1791383Y1158333D03*
X1800083D03*
X1791383Y1165026D03*
X1800083D03*
X1791383Y1171719D03*
X1800083D03*
X1791383Y1178412D03*
X1800083D03*
X1791383Y1185105D03*
X1800083D03*
X1791383Y1195144D03*
X1800083D03*
X1791383Y1201837D03*
X1800083D03*
X1791383Y1208530D03*
X1800083D03*
X1791383Y1215223D03*
X1800083D03*
X1791383Y1221916D03*
X1800083D03*
X1791383Y1231955D03*
X1800083D03*
X1791383Y1238648D03*
X1800083D03*
X1791383Y1245341D03*
X1800083D03*
X1797088Y1273344D03*
X1794288D03*
X1804941Y770144D03*
X1813641D03*
X1804941Y776837D03*
X1813641D03*
X1804941Y783530D03*
X1813641D03*
X1804941Y793570D03*
X1813641D03*
X1804941Y800263D03*
X1813641D03*
X1804941Y806955D03*
X1813641D03*
X1804941Y813648D03*
X1813641D03*
X1804941Y820341D03*
X1813641D03*
X1804941Y830381D03*
X1813641D03*
X1804941Y843766D03*
X1813641D03*
X1804941Y837074D03*
X1813641D03*
X1804941Y850459D03*
X1813641D03*
X1804941Y857152D03*
X1813641D03*
Y867192D03*
X1804941D03*
Y873885D03*
X1813641D03*
X1804941Y880577D03*
X1813641D03*
X1804941Y887270D03*
X1813641D03*
X1804941Y893963D03*
X1813641D03*
X1804941Y904003D03*
X1813641D03*
X1804941Y910696D03*
X1813641D03*
X1804941Y917389D03*
X1813641D03*
X1804941Y924081D03*
X1813641D03*
X1804941Y930774D03*
X1813641D03*
X1804941Y940814D03*
X1813641D03*
X1804941Y947507D03*
X1813641D03*
X1804941Y954200D03*
X1813641D03*
X1804941Y964239D03*
X1813641D03*
X1804941Y970932D03*
X1813641D03*
X1804941Y977625D03*
X1813641D03*
X1804941Y984318D03*
X1813641D03*
X1804941Y991011D03*
X1813641D03*
X1804941Y1017782D03*
X1813641D03*
X1804941Y1024475D03*
X1813641D03*
X1804941Y1031168D03*
X1813641D03*
X1804941Y1037861D03*
X1813641D03*
X1804941Y1044554D03*
X1813641D03*
Y1057940D03*
X1804941D03*
Y1051247D03*
X1813641D03*
X1804941Y1064633D03*
X1813641D03*
Y1071326D03*
X1804941D03*
X1813641Y1078018D03*
X1804941D03*
X1813641Y1088058D03*
X1804941D03*
X1813641Y1094751D03*
X1804941D03*
X1813641Y1101444D03*
X1804941D03*
X1813641Y1108137D03*
X1804941D03*
X1813641Y1114829D03*
X1804941D03*
X1813641Y1124869D03*
X1804941D03*
X1813641Y1131562D03*
X1804941D03*
X1813641Y1138255D03*
X1804941D03*
X1813641Y1144948D03*
X1804941D03*
X1813641Y1151641D03*
X1804941D03*
X1813641Y1161680D03*
X1804941D03*
X1813641Y1168373D03*
X1804941D03*
X1813641Y1175066D03*
X1804941D03*
X1813641Y1181759D03*
X1804941D03*
X1813641Y1188452D03*
X1804941D03*
X1813641Y1198491D03*
X1804941D03*
X1813641Y1205184D03*
X1804941D03*
X1813641Y1211877D03*
X1804941D03*
X1813641Y1218570D03*
X1804941D03*
X1813641Y1225263D03*
X1804941D03*
X1813641Y1235302D03*
X1804941D03*
X1813641Y1241995D03*
X1804941D03*
X1813641Y1248688D03*
X1804941D03*
X1819054Y1253986D03*
X1818188Y1273044D03*
X1810788Y1273344D03*
X1807988D03*
X1815388Y1273044D03*
X1829783Y766798D03*
X1821083D03*
X1829783Y773491D03*
X1821083D03*
X1829783Y780184D03*
X1821083D03*
X1829783Y790223D03*
X1821083D03*
X1829783Y796916D03*
X1821083D03*
X1829783Y803609D03*
X1821083D03*
X1829783Y810302D03*
X1821083D03*
X1829783Y816995D03*
X1821083D03*
X1829783Y827034D03*
X1821083D03*
X1829783Y833727D03*
X1821083D03*
Y847113D03*
X1829783D03*
Y840420D03*
X1821083D03*
X1829783Y853806D03*
X1821083D03*
X1829783Y863845D03*
X1821083D03*
X1829783Y870538D03*
X1821083D03*
X1829783Y877231D03*
X1821083D03*
X1829783Y883924D03*
X1821083D03*
X1829783Y890617D03*
X1821083D03*
X1829783Y900656D03*
X1821083D03*
X1829783Y907349D03*
X1821083D03*
X1829783Y914042D03*
X1821083D03*
X1829783Y920735D03*
X1821083D03*
X1829783Y927428D03*
X1821083D03*
X1829783Y937467D03*
X1821083D03*
X1829783Y944160D03*
X1821083D03*
X1829783Y950853D03*
X1821083D03*
X1829783Y960892D03*
X1821083D03*
X1829783Y967585D03*
X1821083D03*
X1829783Y974278D03*
X1821083D03*
X1829783Y980971D03*
X1821083D03*
X1829783Y987664D03*
X1821083D03*
X1829783Y1017782D03*
X1821083D03*
X1829783Y1027822D03*
X1821083D03*
X1829783Y1034515D03*
X1821083D03*
X1829783Y1041207D03*
X1821083D03*
X1829783Y1047900D03*
X1821083D03*
X1829783Y1054593D03*
X1821083D03*
X1829783Y1061286D03*
X1821083D03*
X1829783Y1067979D03*
X1821083D03*
Y1074672D03*
X1829783D03*
X1821083Y1084711D03*
X1829783D03*
X1821083Y1091404D03*
X1829783D03*
X1821083Y1098097D03*
X1829783D03*
X1821083Y1104790D03*
X1829783D03*
X1821083Y1111483D03*
X1829783D03*
X1821083Y1121522D03*
X1829783D03*
X1821083Y1128215D03*
X1829783D03*
X1821083Y1134908D03*
X1829783D03*
X1821083Y1141601D03*
X1829783D03*
X1821083Y1148294D03*
X1829783D03*
X1821083Y1158333D03*
X1829783D03*
X1821083Y1165026D03*
X1829783D03*
X1821083Y1171719D03*
X1829783D03*
X1821083Y1178412D03*
X1829783D03*
X1821083Y1185105D03*
X1829783D03*
X1821083Y1195144D03*
X1829783D03*
X1821083Y1201837D03*
X1829783D03*
X1821083Y1208530D03*
X1829783D03*
X1821083Y1215223D03*
X1829783D03*
X1821083Y1221916D03*
X1829783D03*
X1821083Y1231955D03*
X1829783D03*
X1821083Y1238648D03*
X1829783D03*
Y1245341D03*
X1821083D03*
G54D58*
X841240Y1420330D03*
X1016240D03*
G54D64*
X986642Y-27947D03*
X986627Y-25432D03*
Y-21558D03*
X986642Y-17918D03*
X986627Y-15403D03*
Y-11529D03*
X986642Y-7889D03*
X986627Y-5374D03*
Y4655D03*
X986642Y2140D03*
X986627Y14684D03*
X986642Y12169D03*
X986627Y8529D03*
X986642Y22698D03*
X989910Y22684D03*
X986627Y19058D03*
Y25213D03*
X989895Y25199D03*
X1296019Y-35472D03*
Y-31598D03*
X1296034Y-37987D03*
Y-27958D03*
X1296019Y-25443D03*
Y-21569D03*
X1296034Y-17929D03*
X1296019Y-15414D03*
Y-11540D03*
X1296034Y-7900D03*
X1296019Y-5385D03*
Y4644D03*
X1296034Y2129D03*
X1296019Y-1511D03*
Y14673D03*
X1296034Y12158D03*
X1296019Y8518D03*
X1296034Y22687D03*
X1296019Y19047D03*
Y25202D03*
X1299302Y22673D03*
X1299287Y25188D03*
X1488393Y-27958D03*
X1488378Y-25443D03*
X1488393Y-37987D03*
X1488378Y-35472D03*
Y-31598D03*
X1488393Y-17929D03*
X1488378Y-15414D03*
Y-11540D03*
Y-21569D03*
X1488393Y2129D03*
X1488378Y4644D03*
X1488393Y-7900D03*
X1488378Y-5385D03*
Y-1511D03*
Y14673D03*
X1488393Y12158D03*
Y22687D03*
X1491661Y22673D03*
X1488378Y8518D03*
Y19047D03*
Y25202D03*
X1491646Y25188D03*
G54D72*
X1879155Y344948D03*
Y592848D03*
X1900275Y-19342D03*
X1889155Y344948D03*
Y592848D03*
X1900275Y716808D03*
X1910275Y-19342D03*
Y716808D03*
X1931395Y592868D03*
X1921395D03*
X1952395Y-19152D03*
X1942395D03*
X1963362Y593010D03*
X1984482Y-19180D03*
X1973362Y593010D03*
X1994482Y-19180D03*
X2015452Y593020D03*
X2005452D03*
X2026452Y-19000D03*
X2036452D03*
X2047419Y593162D03*
X2057419D03*
G54D25*
X57646Y12480D03*
X137272D03*
X186622D03*
X266858D03*
X315598D03*
X502528Y33268D03*
X582154D03*
X631504D03*
X711740D03*
X760480D03*
X1532055Y12480D03*
X1611681D03*
X1661031D03*
X1741267D03*
X1790007D03*
G54D65*
X1077638Y133866D03*
G54D47*
X460000Y278543D03*
G54D70*
X1771457Y1634646D03*
G54D59*
X900196Y175197D03*
X944684Y155216D03*
G54D79*
X1903086Y1318228D03*
X1902402Y1683256D03*
X1950484Y1683497D03*
X1993147Y1682875D03*
G54D77*
X1880836Y1317164D03*
X1881165Y1682207D03*
X1929695Y1683220D03*
X1971555Y1683130D03*
%LPC*%
G75*
G54D80*
G01X-6350Y-464479D02*
Y-539479D01*
X493650D01*
Y-464479D01*
X-6350D01*
G01X5650Y-529479D02*
Y-534479D01*
G01X4193Y-529479D02*
X7107D01*
G01X12017Y-534479D02*
X9483D01*
Y-529479D01*
X12017D01*
G01X11003Y-531896D02*
X9483D01*
G01X14583Y-529479D02*
Y-534479D01*
X17117D01*
G01X20950Y-534646D02*
X20823Y-534562D01*
Y-534396D01*
X20950Y-534312D01*
X21077Y-534396D01*
Y-534562D01*
X20950Y-534646D01*
G01Y-532396D02*
X20823Y-532312D01*
Y-532146D01*
X20950Y-532062D01*
X21077Y-532146D01*
Y-532312D01*
X20950Y-532396D01*
G01X25733Y-536146D02*
X25100Y-535312D01*
X24783Y-534479D01*
Y-531146D01*
X25100Y-530312D01*
X25733Y-529479D01*
G01X31150D02*
X30643Y-529646D01*
X30263Y-530062D01*
X30010Y-530562D01*
X29820Y-531229D01*
X29757Y-531979D01*
X29820Y-532729D01*
X30010Y-533396D01*
X30263Y-533896D01*
X30643Y-534312D01*
X31150Y-534479D01*
X31657Y-534312D01*
X32037Y-533896D01*
X32290Y-533396D01*
X32480Y-532729D01*
X32543Y-531979D01*
X32480Y-531229D01*
X32290Y-530562D01*
X32037Y-530062D01*
X31657Y-529646D01*
X31150Y-529479D01*
G01X34857Y-533479D02*
X35237Y-534062D01*
X35743Y-534396D01*
X36313Y-534479D01*
X36820Y-534396D01*
X37327Y-533979D01*
X37643Y-533479D01*
X37707Y-532979D01*
X37580Y-532396D01*
X37137Y-531979D01*
X36693Y-531812D01*
X36123D01*
G01X36693D02*
X37073Y-531562D01*
X37390Y-531146D01*
X37517Y-530646D01*
X37390Y-530146D01*
X37073Y-529729D01*
X36503Y-529479D01*
X35933Y-529562D01*
X35363Y-529896D01*
G01X41667Y-536146D02*
X42300Y-535312D01*
X42617Y-534479D01*
Y-531146D01*
X42300Y-530312D01*
X41667Y-529479D01*
G01X45057Y-533479D02*
X45437Y-534062D01*
X45943Y-534396D01*
X46513Y-534479D01*
X47020Y-534396D01*
X47527Y-533979D01*
X47843Y-533479D01*
X47907Y-532979D01*
X47780Y-532396D01*
X47337Y-531979D01*
X46893Y-531812D01*
X46323D01*
G01X46893D02*
X47273Y-531562D01*
X47590Y-531146D01*
X47717Y-530646D01*
X47590Y-530146D01*
X47273Y-529729D01*
X46703Y-529479D01*
X46133Y-529562D01*
X45563Y-529896D01*
G01X50347Y-530312D02*
X50727Y-529812D01*
X51170Y-529562D01*
X51677Y-529479D01*
X52310Y-529646D01*
X52753Y-530062D01*
X52880Y-530562D01*
X52817Y-531062D01*
X52563Y-531479D01*
X51297Y-532312D01*
X50727Y-532896D01*
X50347Y-533729D01*
X50220Y-534479D01*
X52880D01*
G01X56523D02*
X56650Y-533396D01*
X56840Y-532479D01*
X57093Y-531646D01*
X57410Y-530729D01*
X57917Y-529479D01*
X55383D01*
G01X60927Y-532812D02*
X62573D01*
G01X65647Y-530312D02*
X66027Y-529812D01*
X66470Y-529562D01*
X66977Y-529479D01*
X67610Y-529646D01*
X68053Y-530062D01*
X68180Y-530562D01*
X68117Y-531062D01*
X67863Y-531479D01*
X66597Y-532312D01*
X66027Y-532896D01*
X65647Y-533729D01*
X65520Y-534479D01*
X68180D01*
G01X70557Y-533479D02*
X70937Y-534062D01*
X71443Y-534396D01*
X72013Y-534479D01*
X72520Y-534396D01*
X73027Y-533979D01*
X73343Y-533479D01*
X73407Y-532979D01*
X73280Y-532396D01*
X72837Y-531979D01*
X72393Y-531812D01*
X71823D01*
G01X72393D02*
X72773Y-531562D01*
X73090Y-531146D01*
X73217Y-530646D01*
X73090Y-530146D01*
X72773Y-529729D01*
X72203Y-529479D01*
X71633Y-529562D01*
X71063Y-529896D01*
G01X77810Y-534479D02*
Y-529479D01*
X75467Y-533062D01*
X78633D01*
G01X80757Y-533729D02*
X81137Y-534146D01*
X81580Y-534396D01*
X82150Y-534479D01*
X82720Y-534312D01*
X83163Y-533979D01*
X83480Y-533396D01*
X83543Y-532729D01*
X83417Y-532062D01*
X83100Y-531646D01*
X82657Y-531312D01*
X82213Y-531229D01*
X81770Y-531312D01*
X81200Y-531646D01*
X81390Y-529479D01*
X83100D01*
G01X91147Y-534479D02*
Y-529479D01*
X93553D01*
G01X92667Y-531896D02*
X91147D01*
G01X95867Y-534479D02*
X97450Y-529479D01*
X99033Y-534479D01*
G01X98463Y-532729D02*
X96437D01*
G01X101220Y-534479D02*
X103880Y-529479D01*
G01X101220D02*
X103880Y-534479D01*
G01X107650Y-534646D02*
X107523Y-534562D01*
Y-534396D01*
X107650Y-534312D01*
X107777Y-534396D01*
Y-534562D01*
X107650Y-534646D01*
G01Y-532396D02*
X107523Y-532312D01*
Y-532146D01*
X107650Y-532062D01*
X107777Y-532146D01*
Y-532312D01*
X107650Y-532396D01*
G01X112433Y-536146D02*
X111800Y-535312D01*
X111483Y-534479D01*
Y-531146D01*
X111800Y-530312D01*
X112433Y-529479D01*
G01X117850D02*
X117343Y-529646D01*
X116963Y-530062D01*
X116710Y-530562D01*
X116520Y-531229D01*
X116457Y-531979D01*
X116520Y-532729D01*
X116710Y-533396D01*
X116963Y-533896D01*
X117343Y-534312D01*
X117850Y-534479D01*
X118357Y-534312D01*
X118737Y-533896D01*
X118990Y-533396D01*
X119180Y-532729D01*
X119243Y-531979D01*
X119180Y-531229D01*
X118990Y-530562D01*
X118737Y-530062D01*
X118357Y-529646D01*
X117850Y-529479D01*
G01X121557Y-533479D02*
X121937Y-534062D01*
X122443Y-534396D01*
X123013Y-534479D01*
X123520Y-534396D01*
X124027Y-533979D01*
X124343Y-533479D01*
X124407Y-532979D01*
X124280Y-532396D01*
X123837Y-531979D01*
X123393Y-531812D01*
X122823D01*
G01X123393D02*
X123773Y-531562D01*
X124090Y-531146D01*
X124217Y-530646D01*
X124090Y-530146D01*
X123773Y-529729D01*
X123203Y-529479D01*
X122633Y-529562D01*
X122063Y-529896D01*
G01X128367Y-536146D02*
X129000Y-535312D01*
X129317Y-534479D01*
Y-531146D01*
X129000Y-530312D01*
X128367Y-529479D01*
G01X131757Y-533479D02*
X132137Y-534062D01*
X132643Y-534396D01*
X133213Y-534479D01*
X133720Y-534396D01*
X134227Y-533979D01*
X134543Y-533479D01*
X134607Y-532979D01*
X134480Y-532396D01*
X134037Y-531979D01*
X133593Y-531812D01*
X133023D01*
G01X133593D02*
X133973Y-531562D01*
X134290Y-531146D01*
X134417Y-530646D01*
X134290Y-530146D01*
X133973Y-529729D01*
X133403Y-529479D01*
X132833Y-529562D01*
X132263Y-529896D01*
G01X137173Y-533896D02*
X137617Y-534312D01*
X138123Y-534479D01*
X138630Y-534312D01*
X139073Y-533812D01*
X139390Y-533062D01*
X139517Y-532312D01*
Y-531396D01*
X139390Y-530646D01*
X139073Y-529979D01*
X138693Y-529646D01*
X138250Y-529479D01*
X137743Y-529646D01*
X137363Y-529979D01*
X137110Y-530479D01*
X136983Y-531146D01*
X137110Y-531729D01*
X137427Y-532312D01*
X137807Y-532646D01*
X138250Y-532729D01*
X138757Y-532562D01*
X139137Y-532146D01*
X139517Y-531396D01*
G01X143223Y-534479D02*
X143350Y-533396D01*
X143540Y-532479D01*
X143793Y-531646D01*
X144110Y-530729D01*
X144617Y-529479D01*
X142083D01*
G01X147627Y-532812D02*
X149273D01*
G01X152157Y-533479D02*
X152537Y-534062D01*
X153043Y-534396D01*
X153613Y-534479D01*
X154120Y-534396D01*
X154627Y-533979D01*
X154943Y-533479D01*
X155007Y-532979D01*
X154880Y-532396D01*
X154437Y-531979D01*
X153993Y-531812D01*
X153423D01*
G01X153993D02*
X154373Y-531562D01*
X154690Y-531146D01*
X154817Y-530646D01*
X154690Y-530146D01*
X154373Y-529729D01*
X153803Y-529479D01*
X153233Y-529562D01*
X152663Y-529896D01*
G01X157447Y-532396D02*
X157890Y-531812D01*
X158270Y-531479D01*
X158777Y-531312D01*
X159220Y-531479D01*
X159537Y-531812D01*
X159790Y-532312D01*
X159853Y-532896D01*
X159790Y-533396D01*
X159537Y-533896D01*
X159157Y-534312D01*
X158713Y-534479D01*
X158207Y-534312D01*
X157763Y-533812D01*
X157510Y-533062D01*
X157447Y-532229D01*
X157573Y-531146D01*
X157763Y-530562D01*
X158080Y-529979D01*
X158523Y-529562D01*
X158967Y-529479D01*
X159410Y-529646D01*
X159727Y-530062D01*
G01X163750Y-534479D02*
Y-529479D01*
X162990Y-530479D01*
G01Y-534479D02*
X164510D01*
G01X169610D02*
Y-529479D01*
X167267Y-533062D01*
X170433D01*
G01X188650Y-464479D02*
Y-539479D01*
G01Y-514479D02*
X291650D01*
Y-489479D01*
G01X188650D02*
X291650D01*
G01Y-464479D02*
Y-539479D01*
G01X293650Y-464479D02*
Y-539479D01*
G01X299157Y-524479D02*
Y-519479D01*
X300423D01*
X300930Y-519729D01*
X301310Y-520062D01*
X301627Y-520562D01*
X301880Y-521146D01*
X301943Y-521979D01*
X301880Y-522812D01*
X301627Y-523396D01*
X301310Y-523896D01*
X300930Y-524229D01*
X300423Y-524479D01*
X299157D01*
G01X304067D02*
X305650Y-519479D01*
X307233Y-524479D01*
G01X306663Y-522729D02*
X304637D01*
G01X310750Y-519479D02*
Y-524479D01*
G01X309293Y-519479D02*
X312207D01*
G01X317117Y-524479D02*
X314583D01*
Y-519479D01*
X317117D01*
G01X316103Y-521896D02*
X314583D01*
G01X320950Y-524646D02*
X320823Y-524562D01*
Y-524396D01*
X320950Y-524312D01*
X321077Y-524396D01*
Y-524562D01*
X320950Y-524646D01*
G01Y-522396D02*
X320823Y-522312D01*
Y-522146D01*
X320950Y-522062D01*
X321077Y-522146D01*
Y-522312D01*
X320950Y-522396D01*
G01X299283Y-499479D02*
Y-494479D01*
X300803D01*
X301310Y-494729D01*
X301690Y-495312D01*
X301817Y-495979D01*
X301690Y-496646D01*
X301373Y-497146D01*
X300803Y-497396D01*
X299283D01*
G01X304510Y-499646D02*
X306790Y-494479D01*
G01X309293Y-499479D02*
Y-494479D01*
X312207Y-499479D01*
Y-494479D01*
G01X315850Y-499646D02*
X315723Y-499562D01*
Y-499396D01*
X315850Y-499312D01*
X315977Y-499396D01*
Y-499562D01*
X315850Y-499646D01*
G01Y-497396D02*
X315723Y-497312D01*
Y-497146D01*
X315850Y-497062D01*
X315977Y-497146D01*
Y-497312D01*
X315850Y-497396D01*
G01X293650Y-514479D02*
X493650D01*
G01X293650Y-489479D02*
X493650D01*
G01X299283Y-474479D02*
Y-469479D01*
X300803D01*
X301310Y-469729D01*
X301690Y-470312D01*
X301817Y-470979D01*
X301690Y-471646D01*
X301373Y-472146D01*
X300803Y-472396D01*
X299283D01*
G01X304383Y-474479D02*
Y-469479D01*
X305967D01*
X306473Y-469729D01*
X306790Y-470062D01*
X306917Y-470729D01*
X306790Y-471396D01*
X306410Y-471812D01*
X305967Y-472062D01*
X304383D01*
G01X305967D02*
X306917Y-474479D01*
G01X310750D02*
X310243Y-474396D01*
X309800Y-474062D01*
X309420Y-473562D01*
X309167Y-472979D01*
X309040Y-472312D01*
Y-471646D01*
X309167Y-470979D01*
X309420Y-470396D01*
X309800Y-469896D01*
X310243Y-469562D01*
X310750Y-469479D01*
X311257Y-469562D01*
X311700Y-469896D01*
X312080Y-470396D01*
X312333Y-470979D01*
X312460Y-471646D01*
Y-472312D01*
X312333Y-472979D01*
X312080Y-473562D01*
X311700Y-474062D01*
X311257Y-474396D01*
X310750Y-474479D01*
G01X314583Y-473479D02*
X314900Y-473979D01*
X315280Y-474312D01*
X315723Y-474479D01*
X316230Y-474312D01*
X316610Y-473979D01*
X316990Y-473479D01*
X317117Y-472812D01*
Y-469479D01*
G01X322217Y-474479D02*
X319683D01*
Y-469479D01*
X322217D01*
G01X321203Y-471896D02*
X319683D01*
G01X327443Y-469896D02*
X327063Y-469646D01*
X326620Y-469479D01*
X326113D01*
X325543Y-469729D01*
X325100Y-470146D01*
X324783Y-470646D01*
X324530Y-471479D01*
X324467Y-472229D01*
X324593Y-472979D01*
X324783Y-473479D01*
X325163Y-473979D01*
X325607Y-474312D01*
X326050Y-474479D01*
X326493D01*
X326937Y-474312D01*
X327317Y-474062D01*
X327633Y-473729D01*
G01X331150Y-469479D02*
Y-474479D01*
G01X329693Y-469479D02*
X332607D01*
G01X336250Y-474646D02*
X336123Y-474562D01*
Y-474396D01*
X336250Y-474312D01*
X336377Y-474396D01*
Y-474562D01*
X336250Y-474646D01*
G01Y-472396D02*
X336123Y-472312D01*
Y-472146D01*
X336250Y-472062D01*
X336377Y-472146D01*
Y-472312D01*
X336250Y-472396D01*
G01X408650Y-514479D02*
Y-539479D01*
G01X411283Y-516979D02*
Y-521979D01*
X413817D01*
G01X416890Y-516979D02*
X418410D01*
G01X417650D02*
Y-521979D01*
G01X416890D02*
X418410D01*
G01X423257Y-519312D02*
X423510Y-519062D01*
X423700Y-518646D01*
X423827Y-518062D01*
X423700Y-517562D01*
X423447Y-517229D01*
X423003Y-516979D01*
X421293D01*
Y-521979D01*
X423383D01*
X423827Y-521646D01*
X424080Y-521146D01*
X424207Y-520562D01*
X424080Y-519979D01*
X423700Y-519479D01*
X423257Y-519312D01*
X421293D01*
G01X427850Y-522146D02*
X427723Y-522062D01*
Y-521896D01*
X427850Y-521812D01*
X427977Y-521896D01*
Y-522062D01*
X427850Y-522146D01*
G01Y-519896D02*
X427723Y-519812D01*
Y-519646D01*
X427850Y-519562D01*
X427977Y-519646D01*
Y-519812D01*
X427850Y-519896D01*
G01X451650Y-514479D02*
Y-539479D01*
G01Y-489479D02*
Y-514479D01*
G01X456663Y-541646D02*
X456770Y-541521D01*
X456850Y-541312D01*
X456903Y-541021D01*
X456850Y-540771D01*
X456743Y-540604D01*
X456557Y-540479D01*
X455837D01*
Y-542979D01*
X456717D01*
X456903Y-542812D01*
X457010Y-542562D01*
X457063Y-542271D01*
X457010Y-541979D01*
X456850Y-541729D01*
X456663Y-541646D01*
X455837D01*
G01X459130Y-542979D02*
Y-541312D01*
G01Y-541604D02*
X459023Y-541437D01*
X458863Y-541354D01*
X458677Y-541312D01*
X458490Y-541396D01*
X458330Y-541562D01*
X458223Y-541812D01*
X458170Y-542146D01*
X458223Y-542479D01*
X458330Y-542729D01*
X458490Y-542896D01*
X458677Y-542979D01*
X458863Y-542937D01*
X459023Y-542812D01*
X459130Y-542646D01*
G01X460450Y-542687D02*
X460583Y-542854D01*
X460770Y-542979D01*
X460930D01*
X461090Y-542896D01*
X461197Y-542771D01*
X461250Y-542604D01*
X461223Y-542354D01*
X461117Y-542229D01*
X460637Y-541979D01*
X460530Y-541687D01*
X460583Y-541479D01*
X460690Y-541354D01*
X460850Y-541312D01*
X461010Y-541354D01*
X461170Y-541479D01*
G01X462650Y-541854D02*
X463503D01*
X463423Y-541562D01*
X463290Y-541396D01*
X463103Y-541312D01*
X462917Y-541354D01*
X462757Y-541479D01*
X462650Y-541771D01*
X462597Y-542021D01*
Y-542271D01*
X462650Y-542521D01*
X462783Y-542771D01*
X462943Y-542937D01*
X463130Y-542979D01*
X463317Y-542896D01*
X463503Y-542646D01*
G01X464770Y-542979D02*
Y-540479D01*
G01Y-541729D02*
X464903Y-541479D01*
X465063Y-541354D01*
X465223Y-541312D01*
X465463Y-541396D01*
X465623Y-541562D01*
X465730Y-541854D01*
Y-542187D01*
X465677Y-542521D01*
X465570Y-542771D01*
X465383Y-542937D01*
X465223Y-542979D01*
X465063Y-542937D01*
X464903Y-542812D01*
X464770Y-542604D01*
G01X467450Y-542979D02*
X467290Y-542937D01*
X467130Y-542771D01*
X467023Y-542479D01*
X466970Y-542146D01*
X467023Y-541812D01*
X467130Y-541521D01*
X467290Y-541354D01*
X467450Y-541312D01*
X467610Y-541354D01*
X467770Y-541521D01*
X467877Y-541812D01*
X467903Y-542146D01*
X467877Y-542479D01*
X467770Y-542771D01*
X467610Y-542937D01*
X467450Y-542979D01*
G01X470130D02*
Y-541312D01*
G01Y-541604D02*
X470023Y-541437D01*
X469863Y-541354D01*
X469677Y-541312D01*
X469490Y-541396D01*
X469330Y-541562D01*
X469223Y-541812D01*
X469170Y-542146D01*
X469223Y-542479D01*
X469330Y-542729D01*
X469490Y-542896D01*
X469677Y-542979D01*
X469863Y-542937D01*
X470023Y-542812D01*
X470130Y-542646D01*
G01X471477Y-542979D02*
Y-541312D01*
G01Y-541646D02*
X471610Y-541479D01*
X471743Y-541354D01*
X471930Y-541312D01*
X472063Y-541354D01*
X472223Y-541479D01*
G01X474530Y-540479D02*
Y-542979D01*
G01Y-542604D02*
X474423Y-542812D01*
X474263Y-542937D01*
X474077Y-542979D01*
X473863Y-542896D01*
X473703Y-542687D01*
X473597Y-542437D01*
X473570Y-542146D01*
X473597Y-541854D01*
X473703Y-541604D01*
X473863Y-541396D01*
X474077Y-541312D01*
X474263Y-541354D01*
X474397Y-541437D01*
X474530Y-541604D01*
G01X477917Y-542979D02*
Y-540479D01*
X478583D01*
X478797Y-540604D01*
X478930Y-540771D01*
X478983Y-541104D01*
X478930Y-541437D01*
X478770Y-541646D01*
X478583Y-541771D01*
X477917D01*
G01X478583D02*
X478983Y-542979D01*
G01X480250Y-541854D02*
X481103D01*
X481023Y-541562D01*
X480890Y-541396D01*
X480703Y-541312D01*
X480517Y-541354D01*
X480357Y-541479D01*
X480250Y-541771D01*
X480197Y-542021D01*
Y-542271D01*
X480250Y-542521D01*
X480383Y-542771D01*
X480543Y-542937D01*
X480730Y-542979D01*
X480917Y-542896D01*
X481103Y-542646D01*
G01X482370Y-541312D02*
X482850Y-542979D01*
X483330Y-541312D01*
G01X485050Y-543062D02*
X484997Y-543021D01*
Y-542937D01*
X485050Y-542896D01*
X485103Y-542937D01*
Y-543021D01*
X485050Y-543062D01*
G01X487250Y-542979D02*
X487437Y-542937D01*
X487650Y-542812D01*
X487783Y-542604D01*
X487837Y-542312D01*
X487783Y-542021D01*
X487623Y-541771D01*
X487383Y-541646D01*
X487117D01*
X486957Y-541562D01*
X486823Y-541354D01*
X486770Y-541062D01*
X486850Y-540771D01*
X487037Y-540562D01*
X487250Y-540479D01*
X487463Y-540562D01*
X487650Y-540771D01*
X487730Y-541062D01*
X487677Y-541354D01*
X487543Y-541562D01*
X487383Y-541646D01*
X487117D01*
X486877Y-541771D01*
X486717Y-542021D01*
X486663Y-542312D01*
X486717Y-542604D01*
X486850Y-542812D01*
X487063Y-542937D01*
X487250Y-542979D01*
G01X489663Y-541646D02*
X489770Y-541521D01*
X489850Y-541312D01*
X489903Y-541021D01*
X489850Y-540771D01*
X489743Y-540604D01*
X489557Y-540479D01*
X488837D01*
Y-542979D01*
X489717D01*
X489903Y-542812D01*
X490010Y-542562D01*
X490063Y-542271D01*
X490010Y-541979D01*
X489850Y-541729D01*
X489663Y-541646D01*
X488837D01*
G01X455550Y-516979D02*
Y-521979D01*
G01X454093Y-516979D02*
X457007D01*
G01X460650Y-521979D02*
X460270Y-521896D01*
X459890Y-521562D01*
X459637Y-520979D01*
X459510Y-520312D01*
X459637Y-519646D01*
X459890Y-519062D01*
X460270Y-518729D01*
X460650Y-518646D01*
X461030Y-518729D01*
X461410Y-519062D01*
X461663Y-519646D01*
X461727Y-520312D01*
X461663Y-520979D01*
X461410Y-521562D01*
X461030Y-521896D01*
X460650Y-521979D01*
G01X465750D02*
X465370Y-521896D01*
X464990Y-521562D01*
X464737Y-520979D01*
X464610Y-520312D01*
X464737Y-519646D01*
X464990Y-519062D01*
X465370Y-518729D01*
X465750Y-518646D01*
X466130Y-518729D01*
X466510Y-519062D01*
X466763Y-519646D01*
X466827Y-520312D01*
X466763Y-520979D01*
X466510Y-521562D01*
X466130Y-521896D01*
X465750Y-521979D01*
G01X470850D02*
Y-516979D01*
G01X475950Y-522146D02*
X475823Y-522062D01*
Y-521896D01*
X475950Y-521812D01*
X476077Y-521896D01*
Y-522062D01*
X475950Y-522146D01*
G01Y-519896D02*
X475823Y-519812D01*
Y-519646D01*
X475950Y-519562D01*
X476077Y-519646D01*
Y-519812D01*
X475950Y-519896D01*
G01X454283Y-496979D02*
Y-491979D01*
X455867D01*
X456373Y-492229D01*
X456690Y-492562D01*
X456817Y-493229D01*
X456690Y-493896D01*
X456310Y-494312D01*
X455867Y-494562D01*
X454283D01*
G01X455867D02*
X456817Y-496979D01*
G01X461917D02*
X459383D01*
Y-491979D01*
X461917D01*
G01X460903Y-494396D02*
X459383D01*
G01X464167Y-491979D02*
X465750Y-496979D01*
X467333Y-491979D01*
G01X470850Y-497146D02*
X470723Y-497062D01*
Y-496896D01*
X470850Y-496812D01*
X470977Y-496896D01*
Y-497062D01*
X470850Y-497146D01*
G01Y-494896D02*
X470723Y-494812D01*
Y-494646D01*
X470850Y-494562D01*
X470977Y-494646D01*
Y-494812D01*
X470850Y-494896D01*
G01X-984580Y-698988D02*
Y4193602D01*
X5868320D01*
Y-698988D01*
X-984580D01*
G01X7723Y-521204D02*
X7253Y-520889D01*
X6705Y-520679D01*
X6078D01*
X5373Y-520994D01*
X4825Y-521519D01*
X4433Y-522149D01*
X4120Y-523199D01*
X4042Y-524144D01*
X4198Y-525089D01*
X4433Y-525719D01*
X4903Y-526349D01*
X5452Y-526769D01*
X6000Y-526979D01*
X6548D01*
X7097Y-526769D01*
X7567Y-526454D01*
X7958Y-526034D01*
G01X11360Y-520679D02*
X13240D01*
G01X12300D02*
Y-526979D01*
G01X11360D02*
X13240D01*
G01X18600Y-520679D02*
Y-526979D01*
G01X16798Y-520679D02*
X20402D01*
G01X24900Y-526979D02*
Y-524144D01*
X23333Y-520679D01*
G01X26467D02*
X24900Y-524144D01*
G01X35777Y-525719D02*
X36247Y-526454D01*
X36873Y-526874D01*
X37578Y-526979D01*
X38205Y-526874D01*
X38832Y-526349D01*
X39223Y-525719D01*
X39302Y-525089D01*
X39145Y-524354D01*
X38597Y-523829D01*
X38048Y-523619D01*
X37343D01*
G01X38048D02*
X38518Y-523304D01*
X38910Y-522779D01*
X39067Y-522149D01*
X38910Y-521519D01*
X38518Y-520994D01*
X37813Y-520679D01*
X37108Y-520784D01*
X36403Y-521204D01*
G01X42077Y-525719D02*
X42547Y-526454D01*
X43173Y-526874D01*
X43878Y-526979D01*
X44505Y-526874D01*
X45132Y-526349D01*
X45523Y-525719D01*
X45602Y-525089D01*
X45445Y-524354D01*
X44897Y-523829D01*
X44348Y-523619D01*
X43643D01*
G01X44348D02*
X44818Y-523304D01*
X45210Y-522779D01*
X45367Y-522149D01*
X45210Y-521519D01*
X44818Y-520994D01*
X44113Y-520679D01*
X43408Y-520784D01*
X42703Y-521204D01*
G01X48377Y-525719D02*
X48847Y-526454D01*
X49473Y-526874D01*
X50178Y-526979D01*
X50805Y-526874D01*
X51432Y-526349D01*
X51823Y-525719D01*
X51902Y-525089D01*
X51745Y-524354D01*
X51197Y-523829D01*
X50648Y-523619D01*
X49943D01*
G01X50648D02*
X51118Y-523304D01*
X51510Y-522779D01*
X51667Y-522149D01*
X51510Y-521519D01*
X51118Y-520994D01*
X50413Y-520679D01*
X49708Y-520784D01*
X49003Y-521204D01*
G01X56243Y-526979D02*
X56400Y-525614D01*
X56635Y-524459D01*
X56948Y-523409D01*
X57340Y-522254D01*
X57967Y-520679D01*
X54833D01*
G01X62543Y-526979D02*
X62700Y-525614D01*
X62935Y-524459D01*
X63248Y-523409D01*
X63640Y-522254D01*
X64267Y-520679D01*
X61133D01*
G01X68843Y-528134D02*
X69157Y-526769D01*
G01X75300Y-520679D02*
Y-526979D01*
G01X73498Y-520679D02*
X77102D01*
G01X79642Y-526979D02*
X81600Y-520679D01*
X83558Y-526979D01*
G01X82853Y-524774D02*
X80347D01*
G01X86960Y-520679D02*
X88840D01*
G01X87900D02*
Y-526979D01*
G01X86960D02*
X88840D01*
G01X91850Y-520679D02*
X92947Y-526979D01*
X94200Y-520679D01*
X95453Y-526979D01*
X96550Y-520679D01*
G01X98542Y-526979D02*
X100500Y-520679D01*
X102458Y-526979D01*
G01X101753Y-524774D02*
X99247D01*
G01X104998Y-526979D02*
Y-520679D01*
X108602Y-526979D01*
Y-520679D01*
G01X119008Y-529079D02*
X118225Y-528029D01*
X117833Y-526979D01*
Y-522779D01*
X118225Y-521729D01*
X119008Y-520679D01*
G01X130433Y-526979D02*
Y-520679D01*
X132392D01*
X133018Y-520994D01*
X133410Y-521414D01*
X133567Y-522254D01*
X133410Y-523094D01*
X132940Y-523619D01*
X132392Y-523934D01*
X130433D01*
G01X132392D02*
X133567Y-526979D01*
G01X138300Y-527189D02*
X138143Y-527084D01*
Y-526874D01*
X138300Y-526769D01*
X138457Y-526874D01*
Y-527084D01*
X138300Y-527189D01*
G01X144600Y-526979D02*
X143973Y-526874D01*
X143425Y-526454D01*
X142955Y-525824D01*
X142642Y-525089D01*
X142485Y-524249D01*
Y-523409D01*
X142642Y-522569D01*
X142955Y-521834D01*
X143425Y-521204D01*
X143973Y-520784D01*
X144600Y-520679D01*
X145227Y-520784D01*
X145775Y-521204D01*
X146245Y-521834D01*
X146558Y-522569D01*
X146715Y-523409D01*
Y-524249D01*
X146558Y-525089D01*
X146245Y-525824D01*
X145775Y-526454D01*
X145227Y-526874D01*
X144600Y-526979D01*
G01X150900Y-527189D02*
X150743Y-527084D01*
Y-526874D01*
X150900Y-526769D01*
X151057Y-526874D01*
Y-527084D01*
X150900Y-527189D01*
G01X158923Y-521204D02*
X158453Y-520889D01*
X157905Y-520679D01*
X157278D01*
X156573Y-520994D01*
X156025Y-521519D01*
X155633Y-522149D01*
X155320Y-523199D01*
X155242Y-524144D01*
X155398Y-525089D01*
X155633Y-525719D01*
X156103Y-526349D01*
X156652Y-526769D01*
X157200Y-526979D01*
X157748D01*
X158297Y-526769D01*
X158767Y-526454D01*
X159158Y-526034D01*
G01X163500Y-527189D02*
X163343Y-527084D01*
Y-526874D01*
X163500Y-526769D01*
X163657Y-526874D01*
Y-527084D01*
X163500Y-527189D01*
G01X170192Y-529079D02*
X170975Y-528029D01*
X171367Y-526979D01*
Y-522779D01*
X170975Y-521729D01*
X170192Y-520679D01*
G01X6470Y-513829D02*
X8037D01*
Y-515719D01*
X7567Y-516349D01*
X7018Y-516769D01*
X6235Y-516979D01*
X5452Y-516769D01*
X4903Y-516349D01*
X4433Y-515719D01*
X4120Y-514984D01*
X3963Y-514144D01*
Y-513409D01*
X4120Y-512779D01*
X4433Y-512044D01*
X4903Y-511414D01*
X5373Y-510994D01*
X6000Y-510679D01*
X6548D01*
X7175Y-510889D01*
X7645Y-511309D01*
G01X10577Y-510679D02*
Y-515194D01*
X10890Y-516139D01*
X11517Y-516769D01*
X12300Y-516979D01*
X13083Y-516769D01*
X13710Y-516139D01*
X14023Y-515194D01*
Y-510679D01*
G01X17660D02*
X19540D01*
G01X18600D02*
Y-516979D01*
G01X17660D02*
X19540D01*
G01X23255Y-516139D02*
X23882Y-516664D01*
X24587Y-516979D01*
X25213D01*
X25840Y-516664D01*
X26310Y-516139D01*
X26545Y-515404D01*
X26388Y-514669D01*
X25997Y-514039D01*
X25292Y-513619D01*
X24352Y-513409D01*
X23803Y-512989D01*
X23568Y-512254D01*
X23725Y-511519D01*
X24117Y-510994D01*
X24665Y-510679D01*
X25213D01*
X25762Y-510889D01*
X26232Y-511414D01*
G01X29555Y-516979D02*
Y-510679D01*
G01X32845D02*
Y-516979D01*
G01Y-513829D02*
X29555D01*
G01X35542Y-516979D02*
X37500Y-510679D01*
X39458Y-516979D01*
G01X38753Y-514774D02*
X36247D01*
G01X41998Y-516979D02*
Y-510679D01*
X45602Y-516979D01*
Y-510679D01*
G01X54677Y-516979D02*
Y-510679D01*
X56243D01*
X56870Y-510994D01*
X57340Y-511414D01*
X57732Y-512044D01*
X58045Y-512779D01*
X58123Y-513829D01*
X58045Y-514879D01*
X57732Y-515614D01*
X57340Y-516244D01*
X56870Y-516664D01*
X56243Y-516979D01*
X54677D01*
G01X61760Y-510679D02*
X63640D01*
G01X62700D02*
Y-516979D01*
G01X61760D02*
X63640D01*
G01X67355Y-516139D02*
X67982Y-516664D01*
X68687Y-516979D01*
X69313D01*
X69940Y-516664D01*
X70410Y-516139D01*
X70645Y-515404D01*
X70488Y-514669D01*
X70097Y-514039D01*
X69392Y-513619D01*
X68452Y-513409D01*
X67903Y-512989D01*
X67668Y-512254D01*
X67825Y-511519D01*
X68217Y-510994D01*
X68765Y-510679D01*
X69313D01*
X69862Y-510889D01*
X70332Y-511414D01*
G01X75300Y-510679D02*
Y-516979D01*
G01X73498Y-510679D02*
X77102D01*
G01X81600Y-517189D02*
X81443Y-517084D01*
Y-516874D01*
X81600Y-516769D01*
X81757Y-516874D01*
Y-517084D01*
X81600Y-517189D01*
G01X87743Y-518134D02*
X88057Y-516769D01*
G01X94200Y-510679D02*
Y-516979D01*
G01X92398Y-510679D02*
X96002D01*
G01X98542Y-516979D02*
X100500Y-510679D01*
X102458Y-516979D01*
G01X101753Y-514774D02*
X99247D01*
G01X106800Y-516979D02*
X106173Y-516874D01*
X105625Y-516454D01*
X105155Y-515824D01*
X104842Y-515089D01*
X104685Y-514249D01*
Y-513409D01*
X104842Y-512569D01*
X105155Y-511834D01*
X105625Y-511204D01*
X106173Y-510784D01*
X106800Y-510679D01*
X107427Y-510784D01*
X107975Y-511204D01*
X108445Y-511834D01*
X108758Y-512569D01*
X108915Y-513409D01*
Y-514249D01*
X108758Y-515089D01*
X108445Y-515824D01*
X107975Y-516454D01*
X107427Y-516874D01*
X106800Y-516979D01*
G01X113100D02*
Y-514144D01*
X111533Y-510679D01*
G01X114667D02*
X113100Y-514144D01*
G01X117677Y-510679D02*
Y-515194D01*
X117990Y-516139D01*
X118617Y-516769D01*
X119400Y-516979D01*
X120183Y-516769D01*
X120810Y-516139D01*
X121123Y-515194D01*
Y-510679D01*
G01X123742Y-516979D02*
X125700Y-510679D01*
X127658Y-516979D01*
G01X126953Y-514774D02*
X124447D01*
G01X130198Y-516979D02*
Y-510679D01*
X133802Y-516979D01*
Y-510679D01*
G01X4198Y-506979D02*
Y-500679D01*
X7802Y-506979D01*
Y-500679D01*
G01X12300Y-506979D02*
X11673Y-506874D01*
X11125Y-506454D01*
X10655Y-505824D01*
X10342Y-505089D01*
X10185Y-504249D01*
Y-503409D01*
X10342Y-502569D01*
X10655Y-501834D01*
X11125Y-501204D01*
X11673Y-500784D01*
X12300Y-500679D01*
X12927Y-500784D01*
X13475Y-501204D01*
X13945Y-501834D01*
X14258Y-502569D01*
X14415Y-503409D01*
Y-504249D01*
X14258Y-505089D01*
X13945Y-505824D01*
X13475Y-506454D01*
X12927Y-506874D01*
X12300Y-506979D01*
G01X18600Y-507189D02*
X18443Y-507084D01*
Y-506874D01*
X18600Y-506769D01*
X18757Y-506874D01*
Y-507084D01*
X18600Y-507189D01*
G01X23412Y-501729D02*
X23882Y-501099D01*
X24430Y-500784D01*
X25057Y-500679D01*
X25840Y-500889D01*
X26388Y-501414D01*
X26545Y-502044D01*
X26467Y-502674D01*
X26153Y-503199D01*
X24587Y-504249D01*
X23882Y-504984D01*
X23412Y-506034D01*
X23255Y-506979D01*
X26545D01*
G01X31200D02*
Y-500679D01*
X30260Y-501939D01*
G01Y-506979D02*
X32140D01*
G01X37500D02*
Y-500679D01*
X36560Y-501939D01*
G01Y-506979D02*
X38440D01*
G01X43643Y-508134D02*
X43957Y-506769D01*
G01X47750Y-500679D02*
X48847Y-506979D01*
X50100Y-500679D01*
X51353Y-506979D01*
X52450Y-500679D01*
G01X57967Y-506979D02*
X54833D01*
Y-500679D01*
X57967D01*
G01X56713Y-503724D02*
X54833D01*
G01X60898Y-506979D02*
Y-500679D01*
X64502Y-506979D01*
Y-500679D01*
G01X67355Y-506979D02*
Y-500679D01*
G01X70645D02*
Y-506979D01*
G01Y-503829D02*
X67355D01*
G01X73577Y-500679D02*
Y-505194D01*
X73890Y-506139D01*
X74517Y-506769D01*
X75300Y-506979D01*
X76083Y-506769D01*
X76710Y-506139D01*
X77023Y-505194D01*
Y-500679D01*
G01X79642Y-506979D02*
X81600Y-500679D01*
X83558Y-506979D01*
G01X82853Y-504774D02*
X80347D01*
G01X92712Y-501729D02*
X93182Y-501099D01*
X93730Y-500784D01*
X94357Y-500679D01*
X95140Y-500889D01*
X95688Y-501414D01*
X95845Y-502044D01*
X95767Y-502674D01*
X95453Y-503199D01*
X93887Y-504249D01*
X93182Y-504984D01*
X92712Y-506034D01*
X92555Y-506979D01*
X95845D01*
G01X98698D02*
Y-500679D01*
X102302Y-506979D01*
Y-500679D01*
G01X105077Y-506979D02*
Y-500679D01*
X106643D01*
X107270Y-500994D01*
X107740Y-501414D01*
X108132Y-502044D01*
X108445Y-502779D01*
X108523Y-503829D01*
X108445Y-504879D01*
X108132Y-505614D01*
X107740Y-506244D01*
X107270Y-506664D01*
X106643Y-506979D01*
X105077D01*
G01X117833D02*
Y-500679D01*
X119792D01*
X120418Y-500994D01*
X120810Y-501414D01*
X120967Y-502254D01*
X120810Y-503094D01*
X120340Y-503619D01*
X119792Y-503934D01*
X117833D01*
G01X119792D02*
X120967Y-506979D01*
G01X123977D02*
Y-500679D01*
X125543D01*
X126170Y-500994D01*
X126640Y-501414D01*
X127032Y-502044D01*
X127345Y-502779D01*
X127423Y-503829D01*
X127345Y-504879D01*
X127032Y-505614D01*
X126640Y-506244D01*
X126170Y-506664D01*
X125543Y-506979D01*
X123977D01*
G01X132000Y-507189D02*
X131843Y-507084D01*
Y-506874D01*
X132000Y-506769D01*
X132157Y-506874D01*
Y-507084D01*
X132000Y-507189D01*
G01X28300Y-494279D02*
X25780Y-493862D01*
X23575Y-492196D01*
X21685Y-489696D01*
X20425Y-486779D01*
X19795Y-483446D01*
Y-480112D01*
X20425Y-476779D01*
X21685Y-473862D01*
X23575Y-471363D01*
X25780Y-469696D01*
X28300Y-469279D01*
X30820Y-469696D01*
X33025Y-471363D01*
X34915Y-473862D01*
X36175Y-476779D01*
X36805Y-480112D01*
Y-483446D01*
X36175Y-486779D01*
X34915Y-489696D01*
X33025Y-492196D01*
X30820Y-493862D01*
X28300Y-494279D01*
G01X30820Y-487612D02*
X34600Y-494279D01*
G01X48145Y-477613D02*
Y-489279D01*
X49405Y-492196D01*
X51295Y-493862D01*
X53500Y-494279D01*
X55705Y-493862D01*
X57595Y-492196D01*
X58855Y-489279D01*
G01Y-494279D02*
Y-477613D01*
G01X84370Y-494279D02*
Y-477613D01*
G01Y-480529D02*
X83110Y-478863D01*
X81220Y-478029D01*
X79015Y-477613D01*
X76810Y-478446D01*
X74920Y-480112D01*
X73660Y-482613D01*
X73030Y-485946D01*
X73660Y-489279D01*
X74920Y-491780D01*
X76810Y-493446D01*
X79015Y-494279D01*
X81220Y-493862D01*
X83110Y-492613D01*
X84370Y-490946D01*
G01X98545Y-494279D02*
Y-477613D01*
G01Y-481779D02*
X99805Y-479696D01*
X101695Y-478029D01*
X104215Y-477613D01*
X106420Y-478029D01*
X108310Y-479696D01*
X109255Y-482613D01*
Y-494279D01*
G01X129100Y-469279D02*
Y-494279D01*
G01X124690Y-477613D02*
X133510D01*
G01X159970Y-494279D02*
Y-477613D01*
G01Y-480529D02*
X158710Y-478863D01*
X156820Y-478029D01*
X154615Y-477613D01*
X152410Y-478446D01*
X150520Y-480112D01*
X149260Y-482613D01*
X148630Y-485946D01*
X149260Y-489279D01*
X150520Y-491780D01*
X152410Y-493446D01*
X154615Y-494279D01*
X156820Y-493862D01*
X158710Y-492613D01*
X159970Y-490946D01*
G01X199650Y-473979D02*
Y-481979D01*
X203650D01*
G01X211450D02*
Y-476646D01*
G01Y-477579D02*
X211050Y-477046D01*
X210450Y-476779D01*
X209750Y-476646D01*
X209050Y-476912D01*
X208450Y-477446D01*
X208050Y-478246D01*
X207850Y-479312D01*
X208050Y-480379D01*
X208450Y-481179D01*
X209050Y-481712D01*
X209750Y-481979D01*
X210450Y-481846D01*
X211050Y-481446D01*
X211450Y-480913D01*
G01X215550Y-484379D02*
X216150Y-484646D01*
X216950Y-484379D01*
X217450Y-483846D01*
X217850Y-483179D01*
X218450Y-481046D01*
X219750Y-476646D01*
G01X216550D02*
X218450Y-481046D01*
G01X224150Y-478379D02*
X227350D01*
X227050Y-477446D01*
X226550Y-476912D01*
X225850Y-476646D01*
X225150Y-476779D01*
X224550Y-477179D01*
X224150Y-478112D01*
X223950Y-478913D01*
Y-479712D01*
X224150Y-480512D01*
X224650Y-481312D01*
X225250Y-481846D01*
X225950Y-481979D01*
X226650Y-481712D01*
X227350Y-480913D01*
G01X232250Y-481979D02*
Y-476646D01*
G01Y-477712D02*
X232750Y-477179D01*
X233250Y-476779D01*
X233950Y-476646D01*
X234450Y-476779D01*
X235050Y-477179D01*
G01X223350Y-531979D02*
Y-523979D01*
X227950Y-531979D01*
Y-523979D01*
G01X233650Y-526646D02*
Y-531979D01*
G01Y-524512D02*
X233450Y-524379D01*
Y-524112D01*
X233650Y-523979D01*
X233850Y-524112D01*
Y-524379D01*
X233650Y-524512D01*
G01X239950Y-531979D02*
Y-526646D01*
G01Y-527979D02*
X240350Y-527312D01*
X240950Y-526779D01*
X241750Y-526646D01*
X242450Y-526779D01*
X243050Y-527312D01*
X243350Y-528246D01*
Y-531979D01*
G01X251450D02*
Y-526646D01*
G01Y-527579D02*
X251050Y-527046D01*
X250450Y-526779D01*
X249750Y-526646D01*
X249050Y-526912D01*
X248450Y-527446D01*
X248050Y-528246D01*
X247850Y-529312D01*
X248050Y-530379D01*
X248450Y-531179D01*
X249050Y-531712D01*
X249750Y-531979D01*
X250450Y-531846D01*
X251050Y-531446D01*
X251450Y-530913D01*
G01X220979Y-503836D02*
X222979D01*
Y-506236D01*
X222379Y-507036D01*
X221679Y-507569D01*
X220679Y-507836D01*
X219679Y-507569D01*
X218979Y-507036D01*
X218379Y-506236D01*
X217979Y-505303D01*
X217779Y-504236D01*
Y-503303D01*
X217979Y-502503D01*
X218379Y-501569D01*
X218979Y-500769D01*
X219579Y-500236D01*
X220379Y-499836D01*
X221079D01*
X221879Y-500103D01*
X222479Y-500636D01*
G01X226079Y-507836D02*
Y-499836D01*
X230679Y-507836D01*
Y-499836D01*
G01X234179Y-507836D02*
Y-499836D01*
X236179D01*
X236979Y-500236D01*
X237579Y-500769D01*
X238079Y-501569D01*
X238479Y-502503D01*
X238579Y-503836D01*
X238479Y-505169D01*
X238079Y-506103D01*
X237579Y-506903D01*
X236979Y-507436D01*
X236179Y-507836D01*
X234179D01*
G01X245579D02*
Y-499836D01*
X241879Y-505569D01*
X246879D01*
G01X255179Y-484136D02*
Y-476136D01*
X253979Y-477736D01*
G01Y-484136D02*
X256379D01*
G01X263179D02*
Y-476136D01*
X261979Y-477736D01*
G01Y-484136D02*
X264379D01*
G01X326250Y-525312D02*
X326850Y-524512D01*
X327550Y-524112D01*
X328350Y-523979D01*
X329350Y-524246D01*
X330050Y-524912D01*
X330250Y-525712D01*
X330150Y-526513D01*
X329750Y-527179D01*
X327750Y-528512D01*
X326850Y-529446D01*
X326250Y-530779D01*
X326050Y-531979D01*
X330250D01*
G01X336150Y-523979D02*
X335350Y-524246D01*
X334750Y-524912D01*
X334350Y-525712D01*
X334050Y-526779D01*
X333950Y-527979D01*
X334050Y-529179D01*
X334350Y-530246D01*
X334750Y-531046D01*
X335350Y-531712D01*
X336150Y-531979D01*
X336950Y-531712D01*
X337550Y-531046D01*
X337950Y-530246D01*
X338250Y-529179D01*
X338350Y-527979D01*
X338250Y-526779D01*
X337950Y-525712D01*
X337550Y-524912D01*
X336950Y-524246D01*
X336150Y-523979D01*
G01X342250Y-525312D02*
X342850Y-524512D01*
X343550Y-524112D01*
X344350Y-523979D01*
X345350Y-524246D01*
X346050Y-524912D01*
X346250Y-525712D01*
X346150Y-526513D01*
X345750Y-527179D01*
X343750Y-528512D01*
X342850Y-529446D01*
X342250Y-530779D01*
X342050Y-531979D01*
X346250D01*
G01X349950Y-530379D02*
X350550Y-531312D01*
X351350Y-531846D01*
X352250Y-531979D01*
X353050Y-531846D01*
X353850Y-531179D01*
X354350Y-530379D01*
X354450Y-529579D01*
X354250Y-528646D01*
X353550Y-527979D01*
X352850Y-527712D01*
X351950D01*
G01X352850D02*
X353450Y-527312D01*
X353950Y-526646D01*
X354150Y-525846D01*
X353950Y-525046D01*
X353450Y-524379D01*
X352550Y-523979D01*
X351650Y-524112D01*
X350750Y-524646D01*
G01X358350Y-532246D02*
X361950Y-523979D01*
G01X368150D02*
X367350Y-524246D01*
X366750Y-524912D01*
X366350Y-525712D01*
X366050Y-526779D01*
X365950Y-527979D01*
X366050Y-529179D01*
X366350Y-530246D01*
X366750Y-531046D01*
X367350Y-531712D01*
X368150Y-531979D01*
X368950Y-531712D01*
X369550Y-531046D01*
X369950Y-530246D01*
X370250Y-529179D01*
X370350Y-527979D01*
X370250Y-526779D01*
X369950Y-525712D01*
X369550Y-524912D01*
X368950Y-524246D01*
X368150Y-523979D01*
G01X373950Y-530379D02*
X374550Y-531312D01*
X375350Y-531846D01*
X376250Y-531979D01*
X377050Y-531846D01*
X377850Y-531179D01*
X378350Y-530379D01*
X378450Y-529579D01*
X378250Y-528646D01*
X377550Y-527979D01*
X376850Y-527712D01*
X375950D01*
G01X376850D02*
X377450Y-527312D01*
X377950Y-526646D01*
X378150Y-525846D01*
X377950Y-525046D01*
X377450Y-524379D01*
X376550Y-523979D01*
X375650Y-524112D01*
X374750Y-524646D01*
G01X382350Y-532246D02*
X385950Y-523979D01*
G01X390250Y-525312D02*
X390850Y-524512D01*
X391550Y-524112D01*
X392350Y-523979D01*
X393350Y-524246D01*
X394050Y-524912D01*
X394250Y-525712D01*
X394150Y-526513D01*
X393750Y-527179D01*
X391750Y-528512D01*
X390850Y-529446D01*
X390250Y-530779D01*
X390050Y-531979D01*
X394250D01*
G01X401350D02*
Y-523979D01*
X397650Y-529712D01*
X402650D01*
G01X325950Y-506979D02*
Y-498979D01*
X327950D01*
X328750Y-499379D01*
X329350Y-499912D01*
X329850Y-500712D01*
X330250Y-501646D01*
X330350Y-502979D01*
X330250Y-504312D01*
X329850Y-505246D01*
X329350Y-506046D01*
X328750Y-506579D01*
X327950Y-506979D01*
X325950D01*
G01X333650D02*
X336150Y-498979D01*
X338650Y-506979D01*
G01X337750Y-504179D02*
X334550D01*
G01X344150Y-498979D02*
X343350Y-499246D01*
X342750Y-499912D01*
X342350Y-500712D01*
X342050Y-501779D01*
X341950Y-502979D01*
X342050Y-504179D01*
X342350Y-505246D01*
X342750Y-506046D01*
X343350Y-506712D01*
X344150Y-506979D01*
X344950Y-506712D01*
X345550Y-506046D01*
X345950Y-505246D01*
X346250Y-504179D01*
X346350Y-502979D01*
X346250Y-501779D01*
X345950Y-500712D01*
X345550Y-499912D01*
X344950Y-499246D01*
X344150Y-498979D01*
G01X350250Y-506979D02*
Y-498979D01*
X354050D01*
G01X352650Y-502846D02*
X350250D01*
G01X360150Y-498979D02*
X359350Y-499246D01*
X358750Y-499912D01*
X358350Y-500712D01*
X358050Y-501779D01*
X357950Y-502979D01*
X358050Y-504179D01*
X358350Y-505246D01*
X358750Y-506046D01*
X359350Y-506712D01*
X360150Y-506979D01*
X360950Y-506712D01*
X361550Y-506046D01*
X361950Y-505246D01*
X362250Y-504179D01*
X362350Y-502979D01*
X362250Y-501779D01*
X361950Y-500712D01*
X361550Y-499912D01*
X360950Y-499246D01*
X360150Y-498979D01*
G01X368150D02*
Y-506979D01*
G01X365850Y-498979D02*
X370450D01*
G01X373550Y-506979D02*
Y-498979D01*
X376150Y-505646D01*
X378750Y-498979D01*
Y-506979D01*
G01X384950Y-502712D02*
X385350Y-502312D01*
X385650Y-501646D01*
X385850Y-500712D01*
X385650Y-499912D01*
X385250Y-499379D01*
X384550Y-498979D01*
X381850D01*
Y-506979D01*
X385150D01*
X385850Y-506446D01*
X386250Y-505646D01*
X386450Y-504712D01*
X386250Y-503779D01*
X385650Y-502979D01*
X384950Y-502712D01*
X381850D01*
G01X390950Y-498979D02*
X393350D01*
G01X392150D02*
Y-506979D01*
G01X390950D02*
X393350D01*
G01X398150Y-505379D02*
X398650Y-506179D01*
X399250Y-506712D01*
X399950Y-506979D01*
X400750Y-506712D01*
X401350Y-506179D01*
X401950Y-505379D01*
X402150Y-504312D01*
Y-498979D01*
G01X408150D02*
X407350Y-499246D01*
X406750Y-499912D01*
X406350Y-500712D01*
X406050Y-501779D01*
X405950Y-502979D01*
X406050Y-504179D01*
X406350Y-505246D01*
X406750Y-506046D01*
X407350Y-506712D01*
X408150Y-506979D01*
X408950Y-506712D01*
X409550Y-506046D01*
X409950Y-505246D01*
X410250Y-504179D01*
X410350Y-502979D01*
X410250Y-501779D01*
X409950Y-500712D01*
X409550Y-499912D01*
X408950Y-499246D01*
X408150Y-498979D01*
G01X343750Y-481979D02*
Y-473979D01*
X347550D01*
G01X346150Y-477846D02*
X343750D01*
G01X353650Y-473979D02*
X352850Y-474246D01*
X352250Y-474912D01*
X351850Y-475712D01*
X351550Y-476779D01*
X351450Y-477979D01*
X351550Y-479179D01*
X351850Y-480246D01*
X352250Y-481046D01*
X352850Y-481712D01*
X353650Y-481979D01*
X354450Y-481712D01*
X355050Y-481046D01*
X355450Y-480246D01*
X355750Y-479179D01*
X355850Y-477979D01*
X355750Y-476779D01*
X355450Y-475712D01*
X355050Y-474912D01*
X354450Y-474246D01*
X353650Y-473979D01*
G01X361650D02*
Y-481979D01*
G01X359350Y-473979D02*
X363950D01*
G01X366650Y-484646D02*
X372650D01*
G01X375050Y-481979D02*
Y-473979D01*
X377650Y-480646D01*
X380250Y-473979D01*
Y-481979D01*
G01X386450Y-477712D02*
X386850Y-477312D01*
X387150Y-476646D01*
X387350Y-475712D01*
X387150Y-474912D01*
X386750Y-474379D01*
X386050Y-473979D01*
X383350D01*
Y-481979D01*
X386650D01*
X387350Y-481446D01*
X387750Y-480646D01*
X387950Y-479712D01*
X387750Y-478779D01*
X387150Y-477979D01*
X386450Y-477712D01*
X383350D01*
G01X390650Y-484646D02*
X396650D01*
G01X403650Y-481979D02*
X399650D01*
Y-473979D01*
X403650D01*
G01X402050Y-477846D02*
X399650D01*
G01X407050Y-481979D02*
Y-473979D01*
X409650Y-480646D01*
X412250Y-473979D01*
Y-481979D01*
G01X417650D02*
X418350Y-481846D01*
X419150Y-481446D01*
X419650Y-480779D01*
X419850Y-479846D01*
X419650Y-478913D01*
X419050Y-478112D01*
X418150Y-477712D01*
X417150D01*
X416550Y-477446D01*
X416050Y-476779D01*
X415850Y-475846D01*
X416150Y-474912D01*
X416850Y-474246D01*
X417650Y-473979D01*
X418450Y-474246D01*
X419150Y-474912D01*
X419450Y-475846D01*
X419250Y-476779D01*
X418750Y-477446D01*
X418150Y-477712D01*
X417150D01*
X416250Y-478112D01*
X415650Y-478913D01*
X415450Y-479846D01*
X415650Y-480779D01*
X416150Y-481446D01*
X416950Y-481846D01*
X417650Y-481979D01*
G01X423950Y-481046D02*
X424650Y-481712D01*
X425450Y-481979D01*
X426250Y-481712D01*
X426950Y-480913D01*
X427450Y-479712D01*
X427650Y-478512D01*
Y-477046D01*
X427450Y-475846D01*
X426950Y-474779D01*
X426350Y-474246D01*
X425650Y-473979D01*
X424850Y-474246D01*
X424250Y-474779D01*
X423850Y-475579D01*
X423650Y-476646D01*
X423850Y-477579D01*
X424350Y-478512D01*
X424950Y-479046D01*
X425650Y-479179D01*
X426450Y-478913D01*
X427050Y-478246D01*
X427650Y-477046D01*
G01X433650Y-473979D02*
X432850Y-474246D01*
X432250Y-474912D01*
X431850Y-475712D01*
X431550Y-476779D01*
X431450Y-477979D01*
X431550Y-479179D01*
X431850Y-480246D01*
X432250Y-481046D01*
X432850Y-481712D01*
X433650Y-481979D01*
X434450Y-481712D01*
X435050Y-481046D01*
X435450Y-480246D01*
X435750Y-479179D01*
X435850Y-477979D01*
X435750Y-476779D01*
X435450Y-475712D01*
X435050Y-474912D01*
X434450Y-474246D01*
X433650Y-473979D01*
G01X439450Y-481979D02*
Y-473979D01*
G01X443250D02*
X439450Y-478913D01*
G01X443850Y-481979D02*
X441150Y-476646D01*
G01X414650Y-534979D02*
Y-526979D01*
X413450Y-528579D01*
G01Y-534979D02*
X415850D01*
G01X420750Y-531646D02*
X421450Y-530712D01*
X422050Y-530179D01*
X422850Y-529912D01*
X423550Y-530179D01*
X424050Y-530712D01*
X424450Y-531512D01*
X424550Y-532446D01*
X424450Y-533246D01*
X424050Y-534046D01*
X423450Y-534712D01*
X422750Y-534979D01*
X421950Y-534712D01*
X421250Y-533913D01*
X420850Y-532712D01*
X420750Y-531379D01*
X420950Y-529646D01*
X421250Y-528712D01*
X421750Y-527779D01*
X422450Y-527112D01*
X423150Y-526979D01*
X423850Y-527246D01*
X424350Y-527912D01*
G01X430650Y-535246D02*
X430450Y-535112D01*
Y-534846D01*
X430650Y-534712D01*
X430850Y-534846D01*
Y-535112D01*
X430650Y-535246D01*
G01X436750Y-531646D02*
X437450Y-530712D01*
X438050Y-530179D01*
X438850Y-529912D01*
X439550Y-530179D01*
X440050Y-530712D01*
X440450Y-531512D01*
X440550Y-532446D01*
X440450Y-533246D01*
X440050Y-534046D01*
X439450Y-534712D01*
X438750Y-534979D01*
X437950Y-534712D01*
X437250Y-533913D01*
X436850Y-532712D01*
X436750Y-531379D01*
X436950Y-529646D01*
X437250Y-528712D01*
X437750Y-527779D01*
X438450Y-527112D01*
X439150Y-526979D01*
X439850Y-527246D01*
X440350Y-527912D01*
G01X459650Y-534979D02*
Y-526979D01*
X458450Y-528579D01*
G01Y-534979D02*
X460850D01*
G01X467450D02*
X467650Y-533246D01*
X467950Y-531779D01*
X468350Y-530446D01*
X468850Y-528979D01*
X469650Y-526979D01*
X465650D01*
G01X475650Y-535246D02*
X475450Y-535112D01*
Y-534846D01*
X475650Y-534712D01*
X475850Y-534846D01*
Y-535112D01*
X475650Y-535246D01*
G01X481750Y-528312D02*
X482350Y-527512D01*
X483050Y-527112D01*
X483850Y-526979D01*
X484850Y-527246D01*
X485550Y-527912D01*
X485750Y-528712D01*
X485650Y-529513D01*
X485250Y-530179D01*
X483250Y-531512D01*
X482350Y-532446D01*
X481750Y-533779D01*
X481550Y-534979D01*
X485750D01*
G01X479650Y-508379D02*
X480150Y-509179D01*
X480750Y-509712D01*
X481450Y-509979D01*
X482250Y-509712D01*
X482850Y-509179D01*
X483450Y-508379D01*
X483650Y-507312D01*
Y-501979D01*
M02*
